G04 ================== begin FILE IDENTIFICATION RECORD ==================*
G04 Layout Name:  9324_DA0F0TMBIJ0_F0T_Motherboard_J_v01_20230324_0910.brd*
G04 Film Name:    gnd2*
G04 File Format:  Gerber RS274X*
G04 File Origin:  Cadence Allegro 17.2-S081*
G04 Origin Date:  Sat Mar 25 08:45:06 2023*
G04 *
G04 Layer:  DRAWING FORMAT/TITLE_BLOCK_A*
G04 Layer:  PIN/SPECIAL_DRILL*
G04 Layer:  VIA CLASS/GND2*
G04 Layer:  PIN/GND2*
G04 Layer:  MANUFACTURING/PHOTOPLOT_OUTLINE*
G04 Layer:  ETCH/GND2*
G04 Layer:  DRAWING FORMAT/TITLE_BLOCK*
G04 Layer:  DRAWING FORMAT/TITLE_DATA_GND2*
G04 *
G04 Offset:    (0.00 0.00)*
G04 Mirror:    No*
G04 Mode:      Negative*
G04 Rotation:  0*
G04 FullContactRelief:  No*
G04 UndefLineWidth:     6.00*
G04 ================== end FILE IDENTIFICATION RECORD ====================*
%FSLAX25Y25*MOIN*%
%IR0*IPPOS*OFA0.00000B0.00000*MIA0B0*SFA1.00000B1.00000*%
%ADD15C,.03*%
%ADD31C,.06*%
%ADD45C,.061*%
%ADD26C,.07*%
%AMMACRO54*
4,1,36,0.0,.01,
-.001736,.009848,
-.00342,.009397,
-.005,.00866,
-.006428,.00766,
-.00766,.006428,
-.00866,.005,
-.009397,.00342,
-.009848,.001736,
-.01,0.0,
-.009848,-.001736,
-.009397,-.00342,
-.00866,-.005,
-.00766,-.006428,
-.006428,-.00766,
-.005,-.00866,
-.00342,-.009397,
-.001736,-.009848,
0.0,-.01,
.001736,-.009848,
.00342,-.009397,
.005,-.00866,
.006428,-.00766,
.00766,-.006428,
.00866,-.005,
.009397,-.00342,
.009848,-.001736,
.01,0.0,
.009848,.001736,
.009397,.00342,
.00866,.005,
.00766,.006428,
.006428,.00766,
.005,.00866,
.00342,.009397,
.001736,.009848,
0.0,.01,
0.0*
%
%ADD54MACRO54*%
%ADD51C,.071*%
%ADD29C,.062*%
%ADD17C,.026*%
%AMMACRO70*
4,1,36,.0025,0.0,
.002462,.000434,
.002349,.000855,
.002165,.00125,
.001915,.001607,
.001607,.001915,
.00125,.002165,
.000855,.002349,
.000434,.002462,
0.0,.0025,
-.000434,.002462,
-.000855,.002349,
-.00125,.002165,
-.001607,.001915,
-.001915,.001607,
-.002165,.00125,
-.002349,.000855,
-.002462,.000434,
-.0025,0.0,
-.002462,-.000434,
-.002349,-.000855,
-.002165,-.00125,
-.001915,-.001607,
-.001607,-.001915,
-.00125,-.002165,
-.000855,-.002349,
-.000434,-.002462,
0.0,-.0025,
.000434,-.002462,
.000855,-.002349,
.00125,-.002165,
.001607,-.001915,
.001915,-.001607,
.002165,-.00125,
.002349,-.000855,
.002462,-.000434,
.0025,0.0,
135.*
%
%ADD70MACRO70*%
%ADD66C,.064*%
%AMMACRO19*
4,1,36,.0025,0.0,
.002462,.000434,
.002349,.000855,
.002165,.00125,
.001915,.001607,
.001607,.001915,
.00125,.002165,
.000855,.002349,
.000434,.002462,
0.0,.0025,
-.000434,.002462,
-.000855,.002349,
-.00125,.002165,
-.001607,.001915,
-.001915,.001607,
-.002165,.00125,
-.002349,.000855,
-.002462,.000434,
-.0025,0.0,
-.002462,-.000434,
-.002349,-.000855,
-.002165,-.00125,
-.001915,-.001607,
-.001607,-.001915,
-.00125,-.002165,
-.000855,-.002349,
-.000434,-.002462,
0.0,-.0025,
.000434,-.002462,
.000855,-.002349,
.00125,-.002165,
.001607,-.001915,
.001915,-.001607,
.002165,-.00125,
.002349,-.000855,
.002462,-.000434,
.0025,0.0,
225.*
%
%ADD19MACRO19*%
%AMMACRO14*
4,1,36,.0025,0.0,
.002462,.000434,
.002349,.000855,
.002165,.00125,
.001915,.001607,
.001607,.001915,
.00125,.002165,
.000855,.002349,
.000434,.002462,
0.0,.0025,
-.000434,.002462,
-.000855,.002349,
-.00125,.002165,
-.001607,.001915,
-.001915,.001607,
-.002165,.00125,
-.002349,.000855,
-.002462,.000434,
-.0025,0.0,
-.002462,-.000434,
-.002349,-.000855,
-.002165,-.00125,
-.001915,-.001607,
-.001607,-.001915,
-.00125,-.002165,
-.000855,-.002349,
-.000434,-.002462,
0.0,-.0025,
.000434,-.002462,
.000855,-.002349,
.00125,-.002165,
.001607,-.001915,
.001915,-.001607,
.002165,-.00125,
.002349,-.000855,
.002462,-.000434,
.0025,0.0,
180.*
%
%ADD14MACRO14*%
%AMMACRO11*
4,1,36,.0025,0.0,
.002462,.000434,
.002349,.000855,
.002165,.00125,
.001915,.001607,
.001607,.001915,
.00125,.002165,
.000855,.002349,
.000434,.002462,
0.0,.0025,
-.000434,.002462,
-.000855,.002349,
-.00125,.002165,
-.001607,.001915,
-.001915,.001607,
-.002165,.00125,
-.002349,.000855,
-.002462,.000434,
-.0025,0.0,
-.002462,-.000434,
-.002349,-.000855,
-.002165,-.00125,
-.001915,-.001607,
-.001607,-.001915,
-.00125,-.002165,
-.000855,-.002349,
-.000434,-.002462,
0.0,-.0025,
.000434,-.002462,
.000855,-.002349,
.00125,-.002165,
.001607,-.001915,
.001915,-.001607,
.002165,-.00125,
.002349,-.000855,
.002462,-.000434,
.0025,0.0,
270.*
%
%ADD11MACRO11*%
%AMMACRO52*
4,1,36,-.0025,0.0,
-.002462,.000434,
-.002349,.000855,
-.002165,.00125,
-.001915,.001607,
-.001607,.001915,
-.00125,.002165,
-.000855,.002349,
-.000434,.002462,
0.0,.0025,
.000434,.002462,
.000855,.002349,
.00125,.002165,
.001607,.001915,
.001915,.001607,
.002165,.00125,
.002349,.000855,
.002462,.000434,
.0025,0.0,
.002462,-.000434,
.002349,-.000855,
.002165,-.00125,
.001915,-.001607,
.001607,-.001915,
.00125,-.002165,
.000855,-.002349,
.000434,-.002462,
0.0,-.0025,
-.000434,-.002462,
-.000855,-.002349,
-.00125,-.002165,
-.001607,-.001915,
-.001915,-.001607,
-.002165,-.00125,
-.002349,-.000855,
-.002462,-.000434,
-.0025,0.0,
180.*
%
%ADD52MACRO52*%
%AMMACRO43*
4,1,36,.003,0.0,
.002954,.000521,
.002819,.001026,
.002598,.0015,
.002298,.001928,
.001928,.002298,
.0015,.002598,
.001026,.002819,
.000521,.002954,
0.0,.003,
-.000521,.002954,
-.001026,.002819,
-.0015,.002598,
-.001928,.002298,
-.002298,.001928,
-.002598,.0015,
-.002819,.001026,
-.002954,.000521,
-.003,0.0,
-.002954,-.000521,
-.002819,-.001026,
-.002598,-.0015,
-.002298,-.001928,
-.001928,-.002298,
-.0015,-.002598,
-.001026,-.002819,
-.000521,-.002954,
0.0,-.003,
.000521,-.002954,
.001026,-.002819,
.0015,-.002598,
.001928,-.002298,
.002298,-.001928,
.002598,-.0015,
.002819,-.001026,
.002954,-.000521,
.003,0.0,
270.*
%
%ADD43MACRO43*%
%AMMACRO41*
4,1,36,.003,0.0,
.002954,.000521,
.002819,.001026,
.002598,.0015,
.002298,.001928,
.001928,.002298,
.0015,.002598,
.001026,.002819,
.000521,.002954,
0.0,.003,
-.000521,.002954,
-.001026,.002819,
-.0015,.002598,
-.001928,.002298,
-.002298,.001928,
-.002598,.0015,
-.002819,.001026,
-.002954,.000521,
-.003,0.0,
-.002954,-.000521,
-.002819,-.001026,
-.002598,-.0015,
-.002298,-.001928,
-.001928,-.002298,
-.0015,-.002598,
-.001026,-.002819,
-.000521,-.002954,
0.0,-.003,
.000521,-.002954,
.001026,-.002819,
.0015,-.002598,
.001928,-.002298,
.002298,-.001928,
.002598,-.0015,
.002819,-.001026,
.002954,-.000521,
.003,0.0,
180.*
%
%ADD41MACRO41*%
%ADD25C,.074*%
%AMMACRO73*
4,1,36,-.003,0.0,
-.002954,.000521,
-.002819,.001026,
-.002598,.0015,
-.002298,.001928,
-.001928,.002298,
-.0015,.002598,
-.001026,.002819,
-.000521,.002954,
0.0,.003,
.000521,.002954,
.001026,.002819,
.0015,.002598,
.001928,.002298,
.002298,.001928,
.002598,.0015,
.002819,.001026,
.002954,.000521,
.003,0.0,
.002954,-.000521,
.002819,-.001026,
.002598,-.0015,
.002298,-.001928,
.001928,-.002298,
.0015,-.002598,
.001026,-.002819,
.000521,-.002954,
0.0,-.003,
-.000521,-.002954,
-.001026,-.002819,
-.0015,-.002598,
-.001928,-.002298,
-.002298,-.001928,
-.002598,-.0015,
-.002819,-.001026,
-.002954,-.000521,
-.003,0.0,
270.*
%
%ADD73MACRO73*%
%ADD72C,.0435*%
%ADD62C,.06015*%
%ADD49C,.076*%
%ADD48C,.095*%
%ADD27C,.0257*%
%ADD75C,.087*%
%ADD35C,.03417*%
%ADD40C,.0259*%
%ADD22C,.0277*%
%AMMACRO39*
4,1,15,.06231,.03403,
.067273,.022693,
.070191,.010666,
.070977,-.001684,
.069606,-.013984,
.066121,-.025858,
.06231,-.03403,
.06745,-.03917,
.073227,-.026862,
.076779,-.013739,
.077998,-.000197,
.076848,.01335,
.073362,.026492,
.067647,.038828,
.06745,.03917,
.06231,.03403,
0.0*
4,1,15,.03403,-.06231,
.022693,-.067273,
.010666,-.070191,
-.001684,-.070977,
-.013984,-.069606,
-.025858,-.066121,
-.03403,-.06231,
-.03917,-.06745,
-.026862,-.073227,
-.013739,-.076779,
-.000197,-.077998,
.01335,-.076848,
.026492,-.073362,
.038828,-.067647,
.03917,-.06745,
.03403,-.06231,
0.0*
4,1,15,-.06231,-.03403,
-.067273,-.022693,
-.070191,-.010666,
-.070977,.001684,
-.069606,.013984,
-.066121,.025858,
-.06231,.03403,
-.06745,.03917,
-.073227,.026862,
-.076779,.013739,
-.077998,.000197,
-.076848,-.01335,
-.073362,-.026492,
-.067647,-.038828,
-.06745,-.03917,
-.06231,-.03403,
0.0*
4,1,15,-.03403,.06231,
-.022693,.067273,
-.010666,.070191,
.001684,.070977,
.013984,.069606,
.025858,.066121,
.03403,.06231,
.03917,.06745,
.026862,.073227,
.013739,.076779,
.000197,.077998,
-.01335,.076848,
-.026492,.073362,
-.038828,.067647,
-.03917,.06745,
-.03403,.06231,
0.0*
%
%ADD39MACRO39*%
%AMMACRO10*
4,1,18,.09673,.06845,
.107147,.050613,
.114308,.031238,
.117996,.010914,
.118098,-.009741,
.114613,-.030101,
.107644,-.049546,
.097406,-.067485,
.09673,-.06845,
.10175,-.07347,
.112962,-.054685,
.120742,-.034239,
.124853,-.012752,
.125171,.009122,
.121685,.030719,
.114502,.051383,
.10384,.070486,
.10175,.07347,
.09673,.06845,
0.0*
4,1,18,.06845,-.09673,
.050613,-.107147,
.031238,-.114308,
.010914,-.117996,
-.009741,-.118098,
-.030101,-.114613,
-.049546,-.107644,
-.067485,-.097406,
-.06845,-.09673,
-.07347,-.10175,
-.054685,-.112962,
-.034239,-.120742,
-.012752,-.124853,
.009122,-.125171,
.030719,-.121685,
.051383,-.114502,
.070486,-.10384,
.07347,-.10175,
.06845,-.09673,
0.0*
4,1,18,-.09673,-.06845,
-.107147,-.050613,
-.114308,-.031238,
-.117996,-.010914,
-.118098,.009741,
-.114613,.030101,
-.107644,.049546,
-.097406,.067485,
-.09673,.06845,
-.10175,.07347,
-.112962,.054685,
-.120742,.034239,
-.124853,.012752,
-.125171,-.009122,
-.121685,-.030719,
-.114502,-.051383,
-.10384,-.070486,
-.10175,-.07347,
-.09673,-.06845,
0.0*
4,1,18,-.06845,.09673,
-.050613,.107147,
-.031238,.114308,
-.010914,.117996,
.009741,.118098,
.030101,.114613,
.049546,.107644,
.067485,.097406,
.06845,.09673,
.07347,.10175,
.054685,.112962,
.034239,.120742,
.012752,.124853,
-.009122,.125171,
-.030719,.121685,
-.051383,.114502,
-.070486,.10384,
-.07347,.10175,
-.06845,.09673,
0.0*
%
%ADD10MACRO10*%
%AMMACRO36*
4,1,16,.0711,.04282,
.077455,.029823,
.081457,.01592,
.082984,.001533,
.08199,-.0129,
.078504,-.026942,
.072633,-.040164,
.0711,-.04282,
.07619,-.04791,
.083352,-.033952,
.087981,-.018962,
.089937,-.003396,
.089161,.012273,
.085675,.027569,
.079586,.042027,
.07619,.04791,
.0711,.04282,
0.0*
4,1,16,.04282,-.0711,
.029823,-.077455,
.01592,-.081457,
.001533,-.082984,
-.0129,-.08199,
-.026942,-.078504,
-.040164,-.072633,
-.04282,-.0711,
-.04791,-.07619,
-.033952,-.083352,
-.018962,-.087981,
-.003396,-.089937,
.012273,-.089161,
.027569,-.085675,
.042027,-.079586,
.04791,-.07619,
.04282,-.0711,
0.0*
4,1,16,-.0711,-.04282,
-.077455,-.029823,
-.081457,-.01592,
-.082984,-.001533,
-.08199,.0129,
-.078504,.026942,
-.072633,.040164,
-.0711,.04282,
-.07619,.04791,
-.083352,.033952,
-.087981,.018962,
-.089937,.003396,
-.089161,-.012273,
-.085675,-.027569,
-.079586,-.042027,
-.07619,-.04791,
-.0711,-.04282,
0.0*
4,1,16,-.04282,.0711,
-.029823,.077455,
-.01592,.081457,
-.001533,.082984,
.0129,.08199,
.026942,.078504,
.040164,.072633,
.04282,.0711,
.04791,.07619,
.033952,.083352,
.018962,.087981,
.003396,.089937,
-.012273,.089161,
-.027569,.085675,
-.042027,.079586,
-.04791,.07619,
-.04282,.0711,
0.0*
%
%ADD36MACRO36*%
%AMMACRO32*
4,1,15,.02438,.01377,
.026401,.009327,
.027619,.004601,
.027999,-.000265,
.027527,-.005123,
.02622,-.009825,
.02438,-.01377,
.02948,-.01887,
.032309,-.013464,
.034156,-.007649,
.034965,-.001602,
.034712,.004494,
.033405,.010454,
.031082,.016095,
.02948,.01887,
.02438,.01377,
90.*
4,1,15,.01377,-.02438,
.009327,-.026401,
.004601,-.027619,
-.000265,-.027999,
-.005123,-.027527,
-.009825,-.02622,
-.01377,-.02438,
-.01887,-.02948,
-.013464,-.032309,
-.007649,-.034156,
-.001602,-.034965,
.004494,-.034712,
.010454,-.033405,
.016095,-.031082,
.01887,-.02948,
.01377,-.02438,
90.*
4,1,15,-.02438,-.01377,
-.026401,-.009327,
-.027619,-.004601,
-.027999,.000265,
-.027527,.005123,
-.02622,.009825,
-.02438,.01377,
-.02948,.01887,
-.032309,.013464,
-.034156,.007649,
-.034965,.001602,
-.034712,-.004494,
-.033405,-.010454,
-.031082,-.016095,
-.02948,-.01887,
-.02438,-.01377,
90.*
4,1,15,-.01377,.02438,
-.009327,.026401,
-.004601,.027619,
.000265,.027999,
.005123,.027527,
.009825,.02622,
.01377,.02438,
.01887,.02948,
.013464,.032309,
.007649,.034156,
.001602,.034965,
-.004494,.034712,
-.010454,.033405,
-.016095,.031082,
-.01887,.02948,
-.01377,.02438,
90.*
%
%ADD32MACRO32*%
%AMMACRO30*
4,1,15,.02438,.01377,
.026401,.009327,
.027619,.004601,
.027999,-.000265,
.027527,-.005123,
.02622,-.009825,
.02438,-.01377,
.02948,-.01887,
.032309,-.013464,
.034156,-.007649,
.034965,-.001602,
.034712,.004494,
.033405,.010454,
.031082,.016095,
.02948,.01887,
.02438,.01377,
0.0*
4,1,15,.01377,-.02438,
.009327,-.026401,
.004601,-.027619,
-.000265,-.027999,
-.005123,-.027527,
-.009825,-.02622,
-.01377,-.02438,
-.01887,-.02948,
-.013464,-.032309,
-.007649,-.034156,
-.001602,-.034965,
.004494,-.034712,
.010454,-.033405,
.016095,-.031082,
.01887,-.02948,
.01377,-.02438,
0.0*
4,1,15,-.02438,-.01377,
-.026401,-.009327,
-.027619,-.004601,
-.027999,.000265,
-.027527,.005123,
-.02622,.009825,
-.02438,.01377,
-.02948,.01887,
-.032309,.013464,
-.034156,.007649,
-.034965,.001602,
-.034712,-.004494,
-.033405,-.010454,
-.031082,-.016095,
-.02948,-.01887,
-.02438,-.01377,
0.0*
4,1,15,-.01377,.02438,
-.009327,.026401,
-.004601,.027619,
.000265,.027999,
.005123,.027527,
.009825,.02622,
.01377,.02438,
.01887,.02948,
.013464,.032309,
.007649,.034156,
.001602,.034965,
-.004494,.034712,
-.010454,.033405,
-.016095,.031082,
-.01887,.02948,
-.01377,.02438,
0.0*
%
%ADD30MACRO30*%
%AMMACRO47*
4,1,15,.02475,.01414,
.026829,.009627,
.028094,.004822,
.028504,-.000129,
.028049,-.005077,
.026741,-.009871,
.02475,-.01414,
.02984,-.01923,
.032726,-.013756,
.034617,-.007864,
.035457,-.001734,
.03522,.00445,
.033912,.010498,
.031574,.016227,
.02984,.01923,
.02475,.01414,
90.*
4,1,15,.01414,-.02475,
.009627,-.026829,
.004822,-.028094,
-.000129,-.028504,
-.005077,-.028049,
-.009871,-.026741,
-.01414,-.02475,
-.01923,-.02984,
-.013756,-.032726,
-.007864,-.034617,
-.001734,-.035457,
.00445,-.03522,
.010498,-.033912,
.016227,-.031574,
.01923,-.02984,
.01414,-.02475,
90.*
4,1,15,-.02475,-.01414,
-.026829,-.009627,
-.028094,-.004822,
-.028504,.000129,
-.028049,.005077,
-.026741,.009871,
-.02475,.01414,
-.02984,.01923,
-.032726,.013756,
-.034617,.007864,
-.035457,.001734,
-.03522,-.00445,
-.033912,-.010498,
-.031574,-.016227,
-.02984,-.01923,
-.02475,-.01414,
90.*
4,1,15,-.01414,.02475,
-.009627,.026829,
-.004822,.028094,
.000129,.028504,
.005077,.028049,
.009871,.026741,
.01414,.02475,
.01923,.02984,
.013756,.032726,
.007864,.034617,
.001734,.035457,
-.00445,.03522,
-.010498,.033912,
-.016227,.031574,
-.01923,.02984,
-.01414,.02475,
90.*
%
%ADD47MACRO47*%
%AMMACRO65*
4,1,18,.07103,.05689,
.07983,.043691,
.086204,.029165,
.089959,.013753,
.09098,-.002077,
.089237,-.017844,
.084783,-.033069,
.077753,-.047289,
.07103,-.05689,
.07601,-.06186,
.085597,-.047721,
.092583,-.032132,
.096757,-.015567,
.09799,.001471,
.096246,.018464,
.091577,.034897,
.084126,.050269,
.07601,.06186,
.07103,.05689,
0.0*
4,1,18,.05689,-.07103,
.043691,-.07983,
.029165,-.086204,
.013753,-.089959,
-.002077,-.09098,
-.017844,-.089237,
-.033069,-.084783,
-.047289,-.077753,
-.05689,-.07103,
-.06186,-.07601,
-.047721,-.085597,
-.032132,-.092583,
-.015567,-.096757,
.001471,-.09799,
.018464,-.096246,
.034897,-.091577,
.050269,-.084126,
.06186,-.07601,
.05689,-.07103,
0.0*
4,1,18,-.07103,-.05689,
-.07983,-.043691,
-.086204,-.029165,
-.089959,-.013753,
-.09098,.002077,
-.089237,.017844,
-.084783,.033069,
-.077753,.047289,
-.07103,.05689,
-.07601,.06186,
-.085597,.047721,
-.092583,.032132,
-.096757,.015567,
-.09799,-.001471,
-.096246,-.018464,
-.091577,-.034897,
-.084126,-.050269,
-.07601,-.06186,
-.07103,-.05689,
0.0*
4,1,18,-.05689,.07103,
-.043691,.07983,
-.029165,.086204,
-.013753,.089959,
.002077,.09098,
.017844,.089237,
.033069,.084783,
.047289,.077753,
.05689,.07103,
.06186,.07601,
.047721,.085597,
.032132,.092583,
.015567,.096757,
-.001471,.09799,
-.018464,.096246,
-.034897,.091577,
-.050269,.084126,
-.06186,.07601,
-.05689,.07103,
0.0*
%
%ADD65MACRO65*%
%AMMACRO50*
4,1,15,.02475,.01414,
.026829,.009627,
.028094,.004822,
.028504,-.000129,
.028049,-.005077,
.026741,-.009871,
.02475,-.01414,
.02984,-.01923,
.032726,-.013756,
.034617,-.007864,
.035457,-.001734,
.03522,.00445,
.033912,.010498,
.031574,.016227,
.02984,.01923,
.02475,.01414,
0.0*
4,1,15,.01414,-.02475,
.009627,-.026829,
.004822,-.028094,
-.000129,-.028504,
-.005077,-.028049,
-.009871,-.026741,
-.01414,-.02475,
-.01923,-.02984,
-.013756,-.032726,
-.007864,-.034617,
-.001734,-.035457,
.00445,-.03522,
.010498,-.033912,
.016227,-.031574,
.01923,-.02984,
.01414,-.02475,
0.0*
4,1,15,-.02475,-.01414,
-.026829,-.009627,
-.028094,-.004822,
-.028504,.000129,
-.028049,.005077,
-.026741,.009871,
-.02475,.01414,
-.02984,.01923,
-.032726,.013756,
-.034617,.007864,
-.035457,.001734,
-.03522,-.00445,
-.033912,-.010498,
-.031574,-.016227,
-.02984,-.01923,
-.02475,-.01414,
0.0*
4,1,15,-.01414,.02475,
-.009627,.026829,
-.004822,.028094,
.000129,.028504,
.005077,.028049,
.009871,.026741,
.01414,.02475,
.01923,.02984,
.013756,.032726,
.007864,.034617,
.001734,.035457,
-.00445,.03522,
-.010498,.033912,
-.016227,.031574,
-.01923,.02984,
-.01414,.02475,
0.0*
%
%ADD50MACRO50*%
%AMMACRO37*
4,1,16,.02511,.01451,
.027248,.009929,
.028558,.005047,
.029001,.000011,
.028562,-.005025,
.027256,-.009909,
.025121,-.014491,
.02511,-.01451,
.0302,-.01959,
.033143,-.014048,
.035079,-.00808,
.035949,-.001865,
.035727,.004405,
.034419,.010542,
.032065,.016359,
.0302,.01959,
.02511,.01451,
90.*
4,1,16,.01451,-.02511,
.009929,-.027248,
.005047,-.028558,
.000011,-.029001,
-.005025,-.028562,
-.009909,-.027256,
-.014491,-.025121,
-.01451,-.02511,
-.01959,-.0302,
-.014048,-.033143,
-.00808,-.035079,
-.001865,-.035949,
.004405,-.035727,
.010542,-.034419,
.016359,-.032065,
.01959,-.0302,
.01451,-.02511,
90.*
4,1,16,-.02511,-.01451,
-.027248,-.009929,
-.028558,-.005047,
-.029001,-.000011,
-.028562,.005025,
-.027256,.009909,
-.025121,.014491,
-.02511,.01451,
-.0302,.01959,
-.033143,.014048,
-.035079,.00808,
-.035949,.001865,
-.035727,-.004405,
-.034419,-.010542,
-.032065,-.016359,
-.0302,-.01959,
-.02511,-.01451,
90.*
4,1,16,-.01451,.02511,
-.009929,.027248,
-.005047,.028558,
-.000011,.029001,
.005025,.028562,
.009909,.027256,
.014491,.025121,
.01451,.02511,
.01959,.0302,
.014048,.033143,
.00808,.035079,
.001865,.035949,
-.004405,.035727,
-.010542,.034419,
-.016359,.032065,
-.01959,.0302,
-.01451,.02511,
90.*
%
%ADD37MACRO37*%
%AMMACRO28*
4,1,16,.02511,.01451,
.027248,.009929,
.028558,.005047,
.029001,.000011,
.028562,-.005025,
.027256,-.009909,
.025121,-.014491,
.02511,-.01451,
.0302,-.01959,
.033143,-.014048,
.035079,-.00808,
.035949,-.001865,
.035727,.004405,
.034419,.010542,
.032065,.016359,
.0302,.01959,
.02511,.01451,
0.0*
4,1,16,.01451,-.02511,
.009929,-.027248,
.005047,-.028558,
.000011,-.029001,
-.005025,-.028562,
-.009909,-.027256,
-.014491,-.025121,
-.01451,-.02511,
-.01959,-.0302,
-.014048,-.033143,
-.00808,-.035079,
-.001865,-.035949,
.004405,-.035727,
.010542,-.034419,
.016359,-.032065,
.01959,-.0302,
.01451,-.02511,
0.0*
4,1,16,-.02511,-.01451,
-.027248,-.009929,
-.028558,-.005047,
-.029001,-.000011,
-.028562,.005025,
-.027256,.009909,
-.025121,.014491,
-.02511,.01451,
-.0302,.01959,
-.033143,.014048,
-.035079,.00808,
-.035949,.001865,
-.035727,-.004405,
-.034419,-.010542,
-.032065,-.016359,
-.0302,-.01959,
-.02511,-.01451,
0.0*
4,1,16,-.01451,.02511,
-.009929,.027248,
-.005047,.028558,
-.000011,.029001,
.005025,.028562,
.009909,.027256,
.014491,.025121,
.01451,.02511,
.01959,.0302,
.014048,.033143,
.00808,.035079,
.001865,.035949,
-.004405,.035727,
-.010542,.034419,
-.016359,.032065,
-.01959,.0302,
-.01451,.02511,
0.0*
%
%ADD28MACRO28*%
%AMMACRO77*
4,1,15,.03682,.01914,
.039584,.012455,
.041146,.005393,
.041457,-.001834,
.040509,-.009005,
.03833,-.015903,
.03682,-.01914,
.04197,-.0243,
.045552,-.016643,
.04775,-.00848,
.048497,-.000059,
.047771,.008363,
.045593,.016531,
.042029,.024197,
.04197,.0243,
.03682,.01914,
0.0*
4,1,15,.01914,-.03682,
.012455,-.039584,
.005393,-.041146,
-.001834,-.041457,
-.009005,-.040509,
-.015903,-.03833,
-.01914,-.03682,
-.0243,-.04197,
-.016643,-.045552,
-.00848,-.04775,
-.000059,-.048497,
.008363,-.047771,
.016531,-.045593,
.024197,-.042029,
.0243,-.04197,
.01914,-.03682,
0.0*
4,1,15,-.03682,-.01914,
-.039584,-.012455,
-.041146,-.005393,
-.041457,.001834,
-.040509,.009005,
-.03833,.015903,
-.03682,.01914,
-.04197,.0243,
-.045552,.016643,
-.04775,.00848,
-.048497,.000059,
-.047771,-.008363,
-.045593,-.016531,
-.042029,-.024197,
-.04197,-.0243,
-.03682,-.01914,
0.0*
4,1,15,-.01914,.03682,
-.012455,.039584,
-.005393,.041146,
.001834,.041457,
.009005,.040509,
.015903,.03833,
.01914,.03682,
.0243,.04197,
.016643,.045552,
.00848,.04775,
.000059,.048497,
-.008363,.047771,
-.016531,.045593,
-.024197,.042029,
-.0243,.04197,
-.01914,.03682,
0.0*
%
%ADD77MACRO77*%
%AMMACRO74*
4,1,15,-.03682,.01914,
-.039584,.012455,
-.041146,.005393,
-.041457,-.001834,
-.040509,-.009005,
-.03833,-.015903,
-.03682,-.01914,
-.04197,-.0243,
-.045552,-.016643,
-.04775,-.00848,
-.048497,-.000059,
-.047771,.008363,
-.045593,.016531,
-.042029,.024197,
-.04197,.0243,
-.03682,.01914,
0.0*
4,1,15,-.01914,-.03682,
-.012455,-.039584,
-.005393,-.041146,
.001834,-.041457,
.009005,-.040509,
.015903,-.03833,
.01914,-.03682,
.0243,-.04197,
.016643,-.045552,
.00848,-.04775,
.000059,-.048497,
-.008363,-.047771,
-.016531,-.045593,
-.024197,-.042029,
-.0243,-.04197,
-.01914,-.03682,
0.0*
4,1,15,.03682,-.01914,
.039584,-.012455,
.041146,-.005393,
.041457,.001834,
.040509,.009005,
.03833,.015903,
.03682,.01914,
.04197,.0243,
.045552,.016643,
.04775,.00848,
.048497,.000059,
.047771,-.008363,
.045593,-.016531,
.042029,-.024197,
.04197,-.0243,
.03682,-.01914,
0.0*
4,1,15,.01914,.03682,
.012455,.039584,
.005393,.041146,
-.001834,.041457,
-.009005,.040509,
-.015903,.03833,
-.01914,.03682,
-.0243,.04197,
-.016643,.045552,
-.00848,.04775,
-.000059,.048497,
.008363,.047771,
.016531,.045593,
.024197,.042029,
.0243,.04197,
.01914,.03682,
0.0*
%
%ADD74MACRO74*%
%AMMACRO23*
4,1,25,-.0605,.00499,
-.05909,.011105,
-.05664,.016881,
-.053224,.022145,
-.048946,.026736,
-.043935,.030513,
-.038345,.033364,
-.032345,.0352,
-.02985,.03564,
-.025195,.035958,
-.02422,.03599,
-.005,.03599,
-.005,.03099,
-.02474,.03099,
-.026534,.030943,
-.028322,.030793,
-.02985,.03058,
-.035086,.029247,
-.040011,.027025,
-.044475,.023982,
-.048343,.020209,
-.051497,.015823,
-.053842,.010955,
-.055305,.005754,
-.05544,.00499,
-.0605,.00499,
0.0*
4,1,27,.005,.03599,
.02451,.03599,
.026071,.035998,
.027631,.035916,
.029183,.035743,
.02985,.03564,
.035965,.03423,
.041741,.03178,
.047005,.028364,
.051596,.024086,
.055373,.019075,
.058224,.013485,
.06006,.007485,
.0605,.00499,
.05544,.00499,
.054107,.010226,
.051885,.015151,
.048842,.019615,
.045069,.023483,
.040683,.026637,
.035815,.028982,
.030614,.030445,
.02985,.03058,
.0281,.030818,
.02634,.030955,
.02482,.03099,
.005,.03099,
.005,.03599,
0.0*
4,1,25,-.0605,-.00501,
-.05544,-.00501,
-.054107,-.010246,
-.051885,-.015171,
-.048842,-.019635,
-.045069,-.023503,
-.040683,-.026657,
-.035815,-.029002,
-.030614,-.030465,
-.02985,-.0306,
-.028079,-.03084,
-.026298,-.030976,
-.02487,-.03101,
-.005,-.03101,
-.005,-.03601,
-.02375,-.03601,
-.028562,-.035772,
-.02985,-.03566,
-.035965,-.03425,
-.041741,-.0318,
-.047005,-.028384,
-.051596,-.024106,
-.055373,-.019095,
-.058224,-.013505,
-.06006,-.007505,
-.0605,-.00501,
0.0*
4,1,27,.005,-.03101,
.02485,-.03101,
.02659,-.030963,
.028324,-.030815,
.02985,-.0306,
.035086,-.029267,
.040011,-.027045,
.044475,-.024002,
.048343,-.020229,
.051497,-.015843,
.053842,-.010975,
.055305,-.005774,
.05544,-.00501,
.0605,-.00501,
.05909,-.011125,
.05664,-.016901,
.053224,-.022165,
.048946,-.026756,
.043935,-.030533,
.038345,-.033384,
.032345,-.03522,
.02985,-.03566,
.028758,-.035841,
.027658,-.035958,
.026553,-.036011,
.02578,-.03601,
.005,-.03601,
.005,-.03101,
0.0*
%
%ADD23MACRO23*%
%ADD60R,.285X.23*%
%ADD67C,.142*%
%AMMACRO61*
4,1,36,0.0,.01,
-.001736,.009848,
-.00342,.009397,
-.005,.00866,
-.006428,.00766,
-.00766,.006428,
-.00866,.005,
-.009397,.00342,
-.009848,.001736,
-.01,0.0,
-.009848,-.001736,
-.009397,-.00342,
-.00866,-.005,
-.00766,-.006428,
-.006428,-.00766,
-.005,-.00866,
-.00342,-.009397,
-.001736,-.009848,
0.0,-.01,
.001736,-.009848,
.00342,-.009397,
.005,-.00866,
.006428,-.00766,
.00766,-.006428,
.00866,-.005,
.009397,-.00342,
.009848,-.001736,
.01,0.0,
.009848,.001736,
.009397,.00342,
.00866,.005,
.00766,.006428,
.006428,.00766,
.005,.00866,
.00342,.009397,
.001736,.009848,
0.0,.01,
180.*
%
%ADD61MACRO61*%
%ADD33O,.219X.156*%
%ADD13C,.125*%
%AMMACRO68*
4,1,36,.0025,0.0,
.002462,.000434,
.002349,.000855,
.002165,.00125,
.001915,.001607,
.001607,.001915,
.00125,.002165,
.000855,.002349,
.000434,.002462,
0.0,.0025,
-.000434,.002462,
-.000855,.002349,
-.00125,.002165,
-.001607,.001915,
-.001915,.001607,
-.002165,.00125,
-.002349,.000855,
-.002462,.000434,
-.0025,0.0,
-.002462,-.000434,
-.002349,-.000855,
-.002165,-.00125,
-.001915,-.001607,
-.001607,-.001915,
-.00125,-.002165,
-.000855,-.002349,
-.000434,-.002462,
0.0,-.0025,
.000434,-.002462,
.000855,-.002349,
.00125,-.002165,
.001607,-.001915,
.001915,-.001607,
.002165,-.00125,
.002349,-.000855,
.002462,-.000434,
.0025,0.0,
30.*
%
%ADD68MACRO68*%
%ADD18C,.424*%
%ADD21C,.155*%
%ADD53C,.291*%
%ADD38C,.165*%
%ADD55C,.247*%
%ADD44C,.256*%
%AMMACRO34*
4,1,36,0.0,.0085,
.001476,.008371,
.002907,.007987,
.00425,.007361,
.005464,.006511,
.006511,.005464,
.007361,.00425,
.007987,.002907,
.008371,.001476,
.0085,0.0,
.008371,-.001476,
.007987,-.002907,
.007361,-.00425,
.006511,-.005464,
.005464,-.006511,
.00425,-.007361,
.002907,-.007987,
.001476,-.008371,
0.0,-.0085,
-.001476,-.008371,
-.002907,-.007987,
-.00425,-.007361,
-.005464,-.006511,
-.006511,-.005464,
-.007361,-.00425,
-.007987,-.002907,
-.008371,-.001476,
-.0085,0.0,
-.008371,.001476,
-.007987,.002907,
-.007361,.00425,
-.006511,.005464,
-.005464,.006511,
-.00425,.007361,
-.002907,.007987,
-.001476,.008371,
0.0,.0085,
180.*
%
%ADD34MACRO34*%
%AMMACRO59*
4,1,20,-.0075,-.05555,
-.0075,-.06273,
-.013677,-.060878,
-.019439,-.057981,
-.024611,-.054127,
-.029034,-.049434,
-.032576,-.044045,
-.035127,-.038122,
-.036612,-.031846,
-.037,-.0265,
-.037,-.0075,
-.03,-.0075,
-.03,-.0265,
-.029544,-.03171,
-.028191,-.036762,
-.02598,-.041502,
-.022981,-.045786,
-.019282,-.049484,
-.014998,-.052484,
-.010258,-.054694,
-.0075,-.05555,
90.*
4,1,20,.0075,-.06273,
.0075,-.05555,
.01243,-.053806,
.016983,-.051232,
.02102,-.047906,
.024418,-.043931,
.027073,-.039425,
.028906,-.034527,
.029861,-.029385,
.03,-.0265,
.03,-.0075,
.037,-.0075,
.037,-.0265,
.036438,-.032925,
.034769,-.039154,
.032043,-.044999,
.028344,-.050282,
.023784,-.054842,
.018501,-.058541,
.012656,-.061266,
.0075,-.06273,
90.*
4,1,20,-.0075,.06273,
-.0075,.05555,
-.01243,.053806,
-.016983,.051232,
-.02102,.047906,
-.024418,.043931,
-.027073,.039425,
-.028906,.034527,
-.029861,.029385,
-.03,.0265,
-.03,.0075,
-.037,.0075,
-.037,.0265,
-.036438,.032925,
-.034769,.039154,
-.032043,.044999,
-.028344,.050282,
-.023784,.054842,
-.018501,.058541,
-.012656,.061266,
-.0075,.06273,
90.*
4,1,20,.0075,.05555,
.0075,.06273,
.013677,.060878,
.019439,.057981,
.024611,.054127,
.029034,.049434,
.032576,.044045,
.035127,.038122,
.036612,.031846,
.037,.0265,
.037,.0075,
.03,.0075,
.03,.0265,
.029544,.03171,
.028191,.036762,
.02598,.041502,
.022981,.045786,
.019282,.049484,
.014998,.052484,
.010258,.054694,
.0075,.05555,
90.*
%
%ADD59MACRO59*%
%AMMACRO20*
4,1,36,.0025,0.0,
.002462,.000434,
.002349,.000855,
.002165,.00125,
.001915,.001607,
.001607,.001915,
.00125,.002165,
.000855,.002349,
.000434,.002462,
0.0,.0025,
-.000434,.002462,
-.000855,.002349,
-.00125,.002165,
-.001607,.001915,
-.001915,.001607,
-.002165,.00125,
-.002349,.000855,
-.002462,.000434,
-.0025,0.0,
-.002462,-.000434,
-.002349,-.000855,
-.002165,-.00125,
-.001915,-.001607,
-.001607,-.001915,
-.00125,-.002165,
-.000855,-.002349,
-.000434,-.002462,
0.0,-.0025,
.000434,-.002462,
.000855,-.002349,
.00125,-.002165,
.001607,-.001915,
.001915,-.001607,
.002165,-.00125,
.002349,-.000855,
.002462,-.000434,
.0025,0.0,
90.*
%
%ADD20MACRO20*%
%AMMACRO56*
4,1,36,0.0,.019,
-.003299,.018711,
-.006498,.017854,
-.0095,.016454,
-.012213,.014555,
-.014555,.012213,
-.016454,.0095,
-.017854,.006498,
-.018711,.003299,
-.019,0.0,
-.018711,-.003299,
-.017854,-.006498,
-.016454,-.0095,
-.014555,-.012213,
-.012213,-.014555,
-.0095,-.016454,
-.006498,-.017854,
-.003299,-.018711,
0.0,-.019,
.003299,-.018711,
.006498,-.017854,
.0095,-.016454,
.012213,-.014555,
.014555,-.012213,
.016454,-.0095,
.017854,-.006498,
.018711,-.003299,
.019,0.0,
.018711,.003299,
.017854,.006498,
.016454,.0095,
.014555,.012213,
.012213,.014555,
.0095,.016454,
.006498,.017854,
.003299,.018711,
0.0,.019,
270.*
%
%ADD56MACRO56*%
%AMMACRO42*
4,1,36,.003,0.0,
.002954,.000521,
.002819,.001026,
.002598,.0015,
.002298,.001928,
.001928,.002298,
.0015,.002598,
.001026,.002819,
.000521,.002954,
0.0,.003,
-.000521,.002954,
-.001026,.002819,
-.0015,.002598,
-.001928,.002298,
-.002298,.001928,
-.002598,.0015,
-.002819,.001026,
-.002954,.000521,
-.003,0.0,
-.002954,-.000521,
-.002819,-.001026,
-.002598,-.0015,
-.002298,-.001928,
-.001928,-.002298,
-.0015,-.002598,
-.001026,-.002819,
-.000521,-.002954,
0.0,-.003,
.000521,-.002954,
.001026,-.002819,
.0015,-.002598,
.001928,-.002298,
.002298,-.001928,
.002598,-.0015,
.002819,-.001026,
.002954,-.000521,
.003,0.0,
90.*
%
%ADD42MACRO42*%
%AMMACRO12*
4,1,36,.0025,0.0,
.002462,.000434,
.002349,.000855,
.002165,.00125,
.001915,.001607,
.001607,.001915,
.00125,.002165,
.000855,.002349,
.000434,.002462,
0.0,.0025,
-.000434,.002462,
-.000855,.002349,
-.00125,.002165,
-.001607,.001915,
-.001915,.001607,
-.002165,.00125,
-.002349,.000855,
-.002462,.000434,
-.0025,0.0,
-.002462,-.000434,
-.002349,-.000855,
-.002165,-.00125,
-.001915,-.001607,
-.001607,-.001915,
-.00125,-.002165,
-.000855,-.002349,
-.000434,-.002462,
0.0,-.0025,
.000434,-.002462,
.000855,-.002349,
.00125,-.002165,
.001607,-.001915,
.001915,-.001607,
.002165,-.00125,
.002349,-.000855,
.002462,-.000434,
.0025,0.0,
0.0*
%
%ADD12MACRO12*%
%AMMACRO71*
4,1,36,-.003,0.0,
-.002954,.000521,
-.002819,.001026,
-.002598,.0015,
-.002298,.001928,
-.001928,.002298,
-.0015,.002598,
-.001026,.002819,
-.000521,.002954,
0.0,.003,
.000521,.002954,
.001026,.002819,
.0015,.002598,
.001928,.002298,
.002298,.001928,
.002598,.0015,
.002819,.001026,
.002954,.000521,
.003,0.0,
.002954,-.000521,
.002819,-.001026,
.002598,-.0015,
.002298,-.001928,
.001928,-.002298,
.0015,-.002598,
.001026,-.002819,
.000521,-.002954,
0.0,-.003,
-.000521,-.002954,
-.001026,-.002819,
-.0015,-.002598,
-.001928,-.002298,
-.002298,-.001928,
-.002598,-.0015,
-.002819,-.001026,
-.002954,-.000521,
-.003,0.0,
90.*
%
%ADD71MACRO71*%
%AMMACRO63*
4,1,36,-.0025,0.0,
-.002462,.000434,
-.002349,.000855,
-.002165,.00125,
-.001915,.001607,
-.001607,.001915,
-.00125,.002165,
-.000855,.002349,
-.000434,.002462,
0.0,.0025,
.000434,.002462,
.000855,.002349,
.00125,.002165,
.001607,.001915,
.001915,.001607,
.002165,.00125,
.002349,.000855,
.002462,.000434,
.0025,0.0,
.002462,-.000434,
.002349,-.000855,
.002165,-.00125,
.001915,-.001607,
.001607,-.001915,
.00125,-.002165,
.000855,-.002349,
.000434,-.002462,
0.0,-.0025,
-.000434,-.002462,
-.000855,-.002349,
-.00125,-.002165,
-.001607,-.001915,
-.001915,-.001607,
-.002165,-.00125,
-.002349,-.000855,
-.002462,-.000434,
-.0025,0.0,
0.0*
%
%ADD63MACRO63*%
%ADD57C,.188*%
%AMMACRO16*
4,1,36,.003,0.0,
.002954,.000521,
.002819,.001026,
.002598,.0015,
.002298,.001928,
.001928,.002298,
.0015,.002598,
.001026,.002819,
.000521,.002954,
0.0,.003,
-.000521,.002954,
-.001026,.002819,
-.0015,.002598,
-.001928,.002298,
-.002298,.001928,
-.002598,.0015,
-.002819,.001026,
-.002954,.000521,
-.003,0.0,
-.002954,-.000521,
-.002819,-.001026,
-.002598,-.0015,
-.002298,-.001928,
-.001928,-.002298,
-.0015,-.002598,
-.001026,-.002819,
-.000521,-.002954,
0.0,-.003,
.000521,-.002954,
.001026,-.002819,
.0015,-.002598,
.001928,-.002298,
.002298,-.001928,
.002598,-.0015,
.002819,-.001026,
.002954,-.000521,
.003,0.0,
0.0*
%
%ADD16MACRO16*%
%AMMACRO24*
4,1,16,.02584,.01524,
.028094,.010521,
.029494,.005483,
.029998,.000278,
.029591,-.004935,
.028284,-.009999,
.026118,-.014758,
.02584,-.01524,
.03092,-.02032,
.033979,-.014642,
.036005,-.008519,
.036938,-.002138,
.036748,.004309,
.035441,.010625,
.033058,.016618,
.03092,.02032,
.02584,.01524,
180.*
4,1,16,.01524,-.02584,
.010521,-.028094,
.005483,-.029494,
.000278,-.029998,
-.004935,-.029591,
-.009999,-.028284,
-.014758,-.026118,
-.01524,-.02584,
-.02032,-.03092,
-.014642,-.033979,
-.008519,-.036005,
-.002138,-.036938,
.004309,-.036748,
.010625,-.035441,
.016618,-.033058,
.02032,-.03092,
.01524,-.02584,
180.*
4,1,16,-.02584,-.01524,
-.028094,-.010521,
-.029494,-.005483,
-.029998,-.000278,
-.029591,.004935,
-.028284,.009999,
-.026118,.014758,
-.02584,.01524,
-.03092,.02032,
-.033979,.014642,
-.036005,.008519,
-.036938,.002138,
-.036748,-.004309,
-.035441,-.010625,
-.033058,-.016618,
-.03092,-.02032,
-.02584,-.01524,
180.*
4,1,16,-.01524,.02584,
-.010521,.028094,
-.005483,.029494,
-.000278,.029998,
.004935,.029591,
.009999,.028284,
.014758,.026118,
.01524,.02584,
.02032,.03092,
.014642,.033979,
.008519,.036005,
.002138,.036938,
-.004309,.036748,
-.010625,.035441,
-.016618,.033058,
-.02032,.03092,
-.01524,.02584,
180.*
%
%ADD24MACRO24*%
%AMMACRO64*
4,1,15,.02438,.01377,
.026401,.009327,
.027619,.004601,
.027999,-.000265,
.027527,-.005123,
.02622,-.009825,
.02438,-.01377,
.02948,-.01887,
.032309,-.013464,
.034156,-.007649,
.034965,-.001602,
.034712,.004494,
.033405,.010454,
.031082,.016095,
.02948,.01887,
.02438,.01377,
270.*
4,1,15,.01377,-.02438,
.009327,-.026401,
.004601,-.027619,
-.000265,-.027999,
-.005123,-.027527,
-.009825,-.02622,
-.01377,-.02438,
-.01887,-.02948,
-.013464,-.032309,
-.007649,-.034156,
-.001602,-.034965,
.004494,-.034712,
.010454,-.033405,
.016095,-.031082,
.01887,-.02948,
.01377,-.02438,
270.*
4,1,15,-.02438,-.01377,
-.026401,-.009327,
-.027619,-.004601,
-.027999,.000265,
-.027527,.005123,
-.02622,.009825,
-.02438,.01377,
-.02948,.01887,
-.032309,.013464,
-.034156,.007649,
-.034965,.001602,
-.034712,-.004494,
-.033405,-.010454,
-.031082,-.016095,
-.02948,-.01887,
-.02438,-.01377,
270.*
4,1,15,-.01377,.02438,
-.009327,.026401,
-.004601,.027619,
.000265,.027999,
.005123,.027527,
.009825,.02622,
.01377,.02438,
.01887,.02948,
.013464,.032309,
.007649,.034156,
.001602,.034965,
-.004494,.034712,
-.010454,.033405,
-.016095,.031082,
-.01887,.02948,
-.01377,.02438,
270.*
%
%ADD64MACRO64*%
%AMMACRO69*
4,1,15,.02475,.01414,
.026829,.009627,
.028094,.004822,
.028504,-.000129,
.028049,-.005077,
.026741,-.009871,
.02475,-.01414,
.02984,-.01923,
.032726,-.013756,
.034617,-.007864,
.035457,-.001734,
.03522,.00445,
.033912,.010498,
.031574,.016227,
.02984,.01923,
.02475,.01414,
180.*
4,1,15,.01414,-.02475,
.009627,-.026829,
.004822,-.028094,
-.000129,-.028504,
-.005077,-.028049,
-.009871,-.026741,
-.01414,-.02475,
-.01923,-.02984,
-.013756,-.032726,
-.007864,-.034617,
-.001734,-.035457,
.00445,-.03522,
.010498,-.033912,
.016227,-.031574,
.01923,-.02984,
.01414,-.02475,
180.*
4,1,15,-.02475,-.01414,
-.026829,-.009627,
-.028094,-.004822,
-.028504,.000129,
-.028049,.005077,
-.026741,.009871,
-.02475,.01414,
-.02984,.01923,
-.032726,.013756,
-.034617,.007864,
-.035457,.001734,
-.03522,-.00445,
-.033912,-.010498,
-.031574,-.016227,
-.02984,-.01923,
-.02475,-.01414,
180.*
4,1,15,-.01414,.02475,
-.009627,.026829,
-.004822,.028094,
.000129,.028504,
.005077,.028049,
.009871,.026741,
.01414,.02475,
.01923,.02984,
.013756,.032726,
.007864,.034617,
.001734,.035457,
-.00445,.03522,
-.010498,.033912,
-.016227,.031574,
-.01923,.02984,
-.01414,.02475,
180.*
%
%ADD69MACRO69*%
%AMMACRO46*
4,1,15,.02475,.01414,
.026829,.009627,
.028094,.004822,
.028504,-.000129,
.028049,-.005077,
.026741,-.009871,
.02475,-.01414,
.02984,-.01923,
.032726,-.013756,
.034617,-.007864,
.035457,-.001734,
.03522,.00445,
.033912,.010498,
.031574,.016227,
.02984,.01923,
.02475,.01414,
270.*
4,1,15,.01414,-.02475,
.009627,-.026829,
.004822,-.028094,
-.000129,-.028504,
-.005077,-.028049,
-.009871,-.026741,
-.01414,-.02475,
-.01923,-.02984,
-.013756,-.032726,
-.007864,-.034617,
-.001734,-.035457,
.00445,-.03522,
.010498,-.033912,
.016227,-.031574,
.01923,-.02984,
.01414,-.02475,
270.*
4,1,15,-.02475,-.01414,
-.026829,-.009627,
-.028094,-.004822,
-.028504,.000129,
-.028049,.005077,
-.026741,.009871,
-.02475,.01414,
-.02984,.01923,
-.032726,.013756,
-.034617,.007864,
-.035457,.001734,
-.03522,-.00445,
-.033912,-.010498,
-.031574,-.016227,
-.02984,-.01923,
-.02475,-.01414,
270.*
4,1,15,-.01414,.02475,
-.009627,.026829,
-.004822,.028094,
.000129,.028504,
.005077,.028049,
.009871,.026741,
.01414,.02475,
.01923,.02984,
.013756,.032726,
.007864,.034617,
.001734,.035457,
-.00445,.03522,
-.010498,.033912,
-.016227,.031574,
-.01923,.02984,
-.01414,.02475,
270.*
%
%ADD46MACRO46*%
%AMMACRO58*
4,1,15,.04124,.02356,
.044705,.016041,
.046811,.008034,
.047495,-.000216,
.046736,-.008461,
.044557,-.016448,
.04124,-.02356,
.04635,-.02867,
.050624,-.020186,
.05336,-.011088,
.054475,-.001654,
.053935,.007831,
.051756,.017077,
.048004,.025805,
.04635,.02867,
.04124,.02356,
0.0*
4,1,15,.02356,-.04124,
.016041,-.044705,
.008034,-.046811,
-.000216,-.047495,
-.008461,-.046736,
-.016448,-.044557,
-.02356,-.04124,
-.02867,-.04635,
-.020186,-.050624,
-.011088,-.05336,
-.001654,-.054475,
.007831,-.053935,
.017077,-.051756,
.025805,-.048004,
.02867,-.04635,
.02356,-.04124,
0.0*
4,1,15,-.04124,-.02356,
-.044705,-.016041,
-.046811,-.008034,
-.047495,.000216,
-.046736,.008461,
-.044557,.016448,
-.04124,.02356,
-.04635,.02867,
-.050624,.020186,
-.05336,.011088,
-.054475,.001654,
-.053935,-.007831,
-.051756,-.017077,
-.048004,-.025805,
-.04635,-.02867,
-.04124,-.02356,
0.0*
4,1,15,-.02356,.04124,
-.016041,.044705,
-.008034,.046811,
.000216,.047495,
.008461,.046736,
.016448,.044557,
.02356,.04124,
.02867,.04635,
.020186,.050624,
.011088,.05336,
.001654,.054475,
-.007831,.053935,
-.017077,.051756,
-.025805,.048004,
-.02867,.04635,
-.02356,.04124,
0.0*
%
%ADD58MACRO58*%
%AMMACRO78*
4,1,15,.03682,.01914,
.039584,.012455,
.041146,.005393,
.041457,-.001834,
.040509,-.009005,
.03833,-.015903,
.03682,-.01914,
.04197,-.0243,
.045552,-.016643,
.04775,-.00848,
.048497,-.000059,
.047771,.008363,
.045593,.016531,
.042029,.024197,
.04197,.0243,
.03682,.01914,
180.*
4,1,15,.01914,-.03682,
.012455,-.039584,
.005393,-.041146,
-.001834,-.041457,
-.009005,-.040509,
-.015903,-.03833,
-.01914,-.03682,
-.0243,-.04197,
-.016643,-.045552,
-.00848,-.04775,
-.000059,-.048497,
.008363,-.047771,
.016531,-.045593,
.024197,-.042029,
.0243,-.04197,
.01914,-.03682,
180.*
4,1,15,-.03682,-.01914,
-.039584,-.012455,
-.041146,-.005393,
-.041457,.001834,
-.040509,.009005,
-.03833,.015903,
-.03682,.01914,
-.04197,.0243,
-.045552,.016643,
-.04775,.00848,
-.048497,.000059,
-.047771,-.008363,
-.045593,-.016531,
-.042029,-.024197,
-.04197,-.0243,
-.03682,-.01914,
180.*
4,1,15,-.01914,.03682,
-.012455,.039584,
-.005393,.041146,
.001834,.041457,
.009005,.040509,
.015903,.03833,
.01914,.03682,
.0243,.04197,
.016643,.045552,
.00848,.04775,
.000059,.048497,
-.008363,.047771,
-.016531,.045593,
-.024197,.042029,
-.0243,.04197,
-.01914,.03682,
180.*
%
%ADD78MACRO78*%
%AMMACRO76*
4,1,15,-.03682,.01914,
-.039584,.012455,
-.041146,.005393,
-.041457,-.001834,
-.040509,-.009005,
-.03833,-.015903,
-.03682,-.01914,
-.04197,-.0243,
-.045552,-.016643,
-.04775,-.00848,
-.048497,-.000059,
-.047771,.008363,
-.045593,.016531,
-.042029,.024197,
-.04197,.0243,
-.03682,.01914,
180.*
4,1,15,-.01914,-.03682,
-.012455,-.039584,
-.005393,-.041146,
.001834,-.041457,
.009005,-.040509,
.015903,-.03833,
.01914,-.03682,
.0243,-.04197,
.016643,-.045552,
.00848,-.04775,
.000059,-.048497,
-.008363,-.047771,
-.016531,-.045593,
-.024197,-.042029,
-.0243,-.04197,
-.01914,-.03682,
180.*
4,1,15,.03682,-.01914,
.039584,-.012455,
.041146,-.005393,
.041457,.001834,
.040509,.009005,
.03833,.015903,
.03682,.01914,
.04197,.0243,
.045552,.016643,
.04775,.00848,
.048497,.000059,
.047771,-.008363,
.045593,-.016531,
.042029,-.024197,
.04197,-.0243,
.03682,-.01914,
180.*
4,1,15,.01914,.03682,
.012455,.039584,
.005393,.041146,
-.001834,.041457,
-.009005,.040509,
-.015903,.03833,
-.01914,.03682,
-.0243,.04197,
-.016643,.045552,
-.00848,.04775,
-.000059,.048497,
.008363,.047771,
.016531,.045593,
.024197,.042029,
.0243,.04197,
.01914,.03682,
180.*
%
%ADD76MACRO76*%
%ADD79C,.006*%
%ADD104C,.04006*%
%ADD101C,.03016*%
%ADD97C,.03018*%
%ADD102C,.07008*%
%ADD82C,.07306*%
%ADD89C,.07208*%
%ADD93C,.07308*%
%ADD94C,.07608*%
%ADD92C,.07808*%
%ADD91C,.09708*%
%ADD88O,.1621X.2251*%
%ADD84C,.311*%
%ADD99C,.1621*%
%ADD81O,.03004X.06404*%
%ADD100C,.16211*%
%ADD96C,.1751*%
%ADD80O,.03006X.06406*%
%ADD95C,.43406*%
%ADD83C,.16506*%
%ADD90C,.25806*%
%ADD98C,.43376*%
%ADD103C,.19786*%
%ADD87O,.43374X.77626*%
%ADD85O,.43374X.69752*%
%ADD86O,.43376X.69754*%
G75*
%LPD*%
G75*
G36*
G01X-984580Y-698988D02*
X5868320D01*
Y4193602D01*
X-984580D01*
Y-698988D01*
G37*
%LPC*%
G75*
G36*
G01X1828062Y36504D02*
X1828081Y36500D01*
G03X1828470Y36462I388J1962D01*
G03X1828859Y36500I1J2000D01*
G01X1828878Y36504D01*
X1849606D01*
G02X1855480Y30630I0J-5874D01*
G01Y-40945D01*
G02X1849606Y-46819I-5874J0D01*
G01X7874D01*
G02X2000Y-40945I0J5874D01*
G01Y30630D01*
G02X7874Y36504I5874J0D01*
G01X35835D01*
G02X41709Y30630I0J-5874D01*
G01Y-3937D01*
G03X51583Y-13811I9874J0D01*
G01X321661D01*
G03X331535Y-3937I0J9874D01*
G01Y30630D01*
G02X337409Y36504I5874J0D01*
G01X480717D01*
G02X486591Y30630I0J-5874D01*
G01Y16850D01*
G03X496465Y6976I9874J0D01*
G01X766543D01*
G03X776417Y16850I0J9874D01*
G01Y30630D01*
G02X782291Y36504I5874J0D01*
G01X879134D01*
G03X889008Y46378I0J9874D01*
G01Y122824D01*
X895188Y129004D01*
X1002542D01*
X1009024Y122522D01*
Y46378D01*
G03X1018898Y36504I9874J0D01*
G01X1510244D01*
G02X1516118Y30630I0J-5874D01*
G01Y-3937D01*
G03X1525992Y-13811I9874J0D01*
G01X1796071D01*
G03X1805945Y-3937I0J9874D01*
G01Y30630D01*
G02X1811819Y36504I5874J0D01*
G01X1828062D01*
G37*
G36*
G01X1829886Y1650538D02*
X1829890D01*
Y1650237D01*
X1829888Y1650228D01*
G03X1829820Y1649712I1932J-517D01*
G03X1829886Y1649203I2000J1D01*
G01Y1612316D01*
G03X1832779Y1605332I9877J0D01*
G01X1839978Y1598133D01*
G02X1841697Y1593983I-4151J-4151D01*
G01Y326095D01*
G03X1844590Y319111I9878J1D01*
G01X1853757Y309944D01*
G02X1855476Y305794I-4151J-4151D01*
G01Y54252D01*
G02X1849606Y48382I-5870J0D01*
G01X1829186D01*
Y48378D01*
X1827844D01*
Y48382D01*
X1803945D01*
G03X1794067Y38504I0J-9878D01*
G01Y3937D01*
G02X1792134Y2004I-1933J0D01*
G01X1529929D01*
G02X1527996Y3937I0J1933D01*
G01Y38504D01*
G03X1518118Y48382I-9878J0D01*
G01X1026772D01*
G02X1020902Y54252I0J5870D01*
G01Y131004D01*
G03X1011024Y140882I-9878J0D01*
G01X887008D01*
G03X877130Y131004I0J-9878D01*
G01Y54252D01*
G02X871260Y48382I-5870J0D01*
G01X774417D01*
G03X764539Y38504I0J-9878D01*
G01Y24724D01*
G02X762606Y22791I-1933J0D01*
G01X500402D01*
G02X498469Y24724I0J1933D01*
G01Y38504D01*
G03X488591Y48382I-9878J0D01*
G01X329535D01*
G03X319657Y38504I0J-9878D01*
G01Y3937D01*
G02X317724Y2004I-1933J0D01*
G01X55520D01*
G02X53587Y3937I0J1933D01*
G01Y38504D01*
G03X43709Y48382I-9878J0D01*
G01X7874D01*
G02X2004Y54252I0J5870D01*
G01Y305794D01*
G02X3723Y309944I5870J-1D01*
G01X6985Y313206D01*
G03X9878Y320190I-6984J6984D01*
G01Y1588078D01*
G02X11597Y1592228I5870J-1D01*
G01X24701Y1605332D01*
G03X27595Y1612316I-6983J6985D01*
G01Y1732244D01*
G02X33465Y1738114I5870J0D01*
G01X765732D01*
Y1736890D01*
G03X769705Y1732917I3973J0D01*
G01X1087854D01*
G03X1091827Y1736890I0J3973D01*
G01Y1738114D01*
X1824016D01*
G02X1829886Y1732244I0J-5870D01*
G01Y1650538D01*
G37*
G36*
G01X1867354Y305795D02*
G03X1862156Y318343I-17746J-1D01*
G01X1855296Y325203D01*
G02X1853575Y329357I4153J4154D01*
G01Y1593984D01*
G03X1848377Y1606532I-17746J-1D01*
G01X1843484Y1611425D01*
G02X1841764Y1615579I4156J4154D01*
G01Y1732244D01*
G02X1847638Y1738118I5874J0D01*
G01X1857480D01*
G03X1867354Y1747992I0J9874D01*
G01Y1815072D01*
G02X1873228Y1820946I5874J0D01*
G01X2093700D01*
G02X2099574Y1815072I0J-5874D01*
G01Y1791450D01*
G02X2093700Y1785576I-5874J0D01*
G01X2031574D01*
G03X2021700Y1775702I0J-9874D01*
G01Y1229954D01*
G03X2031574Y1220080I9874J0D01*
G01X2093700D01*
G02X2099574Y1214206I0J-5874D01*
G01Y-40945D01*
G02X2093700Y-46819I-5874J0D01*
G01X1873228D01*
G02X1867354Y-40945I0J5874D01*
G01Y305795D01*
G37*
%LPD*%
G75*
G36*
G01X1758669Y52153D02*
G02X1760173Y50649I0J-1504D01*
G01Y50648D01*
G02X1760172Y50593I-1504J0D01*
G02X1758669Y49100I-1503J10D01*
G01X1755269D01*
G02X1753766Y50593I0J1503D01*
G02X1753765Y50648I1503J55D01*
G01Y50649D01*
G02X1755269Y52153I1504J0D01*
G02X1755620Y52112I2J-1504D01*
G01X1755643Y52106D01*
X1758295D01*
X1758318Y52112D01*
G02X1758669Y52153I349J-1463D01*
G37*
G36*
G01X1394374Y172851D02*
G02X1395334Y173198I960J-1154D01*
G01X1398734D01*
G02X1400236Y171696I0J-1502D01*
G02X1398743Y170194I-1502J0D01*
G02X1398182Y170076I-561J1276D01*
G02X1397656Y170179I0J1394D01*
G01X1397620Y170194D01*
X1395334D01*
G02X1394882Y170264I1J1502D01*
G02X1394184Y170076I-699J1206D01*
G01X1394182D01*
G02Y172864I0J1394D01*
G02X1394374Y172851I2J-1394D01*
G37*
G36*
G01X880168Y504762D02*
Y508162D01*
G02X881670Y509664I1502J0D01*
G02X882945Y508955I0J-1501D01*
G02X883184Y508142I-1265J-813D01*
G01Y508141D01*
G02X883173Y507963I-1504J4D01*
G01X883172Y507952D01*
Y504897D01*
X883173Y504888D01*
G02X883180Y504743I-1493J-145D01*
G01Y504742D01*
G02X881680Y503242I-1500J0D01*
G02X880398Y503963I0J1500D01*
G02X880168Y504762I1273J799D01*
G37*
G36*
G01X963269Y1556947D02*
G03X963539I135J148D01*
G02X965904Y1557866I2365J-2584D01*
G02X969115Y1555762I0J-3502D01*
G02X970504Y1554262I-115J-1500D01*
G02X969016Y1552758I-1504J0D01*
G02X965904Y1550862I-3112J1606D01*
G02X963539Y1551781I0J3503D01*
G03X963269I-135J-148D01*
G02X960904Y1550862I-2365J2584D01*
G02Y1557866I0J3502D01*
G02X963269Y1556947I0J-3503D01*
G37*
G36*
G01X1010001D02*
G03X1010271I135J148D01*
G02X1012636Y1557866I2365J-2584D01*
G02X1015849Y1555757I0J-3502D01*
G02X1016012Y1555766I164J-1495D01*
G02Y1552758I0J-1504D01*
G02X1015759Y1552779I-3J1504D01*
G02X1012636Y1550862I-3123J1585D01*
G02X1010271Y1551781I0J3503D01*
G03X1010001I-135J-148D01*
G02X1007636Y1550862I-2365J2584D01*
G02Y1557866I0J3502D01*
G02X1010001Y1556947I0J-3503D01*
G37*
G36*
G01X1056733D02*
G03X1057003I135J148D01*
G02X1059368Y1557866I2365J-2584D01*
G02X1062579Y1555762I0J-3502D01*
G02X1063968Y1554262I-115J-1500D01*
G02X1062480Y1552758I-1504J0D01*
G02X1059368Y1550862I-3112J1606D01*
G02X1057003Y1551781I0J3503D01*
G03X1056733I-135J-148D01*
G02X1054368Y1550862I-2365J2584D01*
G02Y1557866I0J3502D01*
G02X1056733Y1556947I0J-3503D01*
G37*
G36*
G01X1080099D02*
G03X1080369I135J148D01*
G02X1082734Y1557866I2365J-2584D01*
G02X1085945Y1555762I0J-3502D01*
G02X1087334Y1554262I-115J-1500D01*
G02X1085846Y1552758I-1504J0D01*
G02X1082734Y1550862I-3112J1606D01*
G02X1080369Y1551781I0J3503D01*
G03X1080099I-135J-148D01*
G02X1077734Y1550862I-2365J2584D01*
G02Y1557866I0J3502D01*
G02X1080099Y1556947I0J-3503D01*
G37*
G36*
G01X986635D02*
G03X986905I135J148D01*
G02X989270Y1557866I2365J-2584D01*
G02X992481Y1555762I0J-3502D01*
G02X993966Y1554262I-15J-1500D01*
G02X992466Y1552762I-1500J0D01*
G02X992385Y1552764I-3J1500D01*
G02X989270Y1550862I-3115J1600D01*
G02X986905Y1551781I0J3503D01*
G03X986635I-135J-148D01*
G02X984270Y1550862I-2365J2584D01*
G02Y1557866I0J3502D01*
G02X986635Y1556947I0J-3503D01*
G37*
G36*
G01X1033367D02*
G03X1033637I135J148D01*
G02X1036002Y1557866I2365J-2584D01*
G02X1039214Y1555760I0J-3502D01*
G02X1039298Y1555762I78J-1498D01*
G02Y1552762I0J-1500D01*
G02X1039121Y1552772I-4J1500D01*
G02X1036002Y1550862I-3119J1592D01*
G02X1033637Y1551781I0J3503D01*
G03X1033367I-135J-148D01*
G02X1031002Y1550862I-2365J2584D01*
G02Y1557866I0J3502D01*
G02X1033367Y1556947I0J-3503D01*
G37*
G36*
G01X229206Y1656840D02*
X232906D01*
G02X233208Y1656537I-1J-303D01*
G01Y1646531D01*
G02X232906Y1646228I-302J-1D01*
G01X229206D01*
G02X228904Y1646531I1J303D01*
G01Y1648936D01*
G02X228890Y1649173I2002J237D01*
G02X228904Y1649410I2016J0D01*
G01Y1653660D01*
G02X228890Y1653897I2002J237D01*
G02X228904Y1654134I2016J0D01*
G01Y1656537D01*
G02X229206Y1656840I302J1D01*
G37*
G36*
G01X276450D02*
X280150D01*
G02X280452Y1656537I-1J-303D01*
G01Y1646531D01*
G02X280150Y1646228I-302J-1D01*
G01X276450D01*
G02X276148Y1646531I1J303D01*
G01Y1648936D01*
G02X276134Y1649173I2002J237D01*
G02X276148Y1649410I2016J0D01*
G01Y1653660D01*
G02X276134Y1653897I2002J237D01*
G02X276148Y1654134I2016J0D01*
G01Y1656537D01*
G02X276450Y1656840I302J1D01*
G37*
G36*
G01X237080Y1660776D02*
X240780D01*
G02X241082Y1660474I0J-302D01*
G01Y1650468D01*
G02X240780Y1650166I-302J0D01*
G01X237080D01*
G02X236778Y1650468I0J302D01*
G01Y1652873D01*
G02X236764Y1653110I2002J237D01*
G02X236778Y1653347I2016J0D01*
G01Y1657597D01*
G02X236764Y1657834I2002J237D01*
G02X236778Y1658071I2016J0D01*
G01Y1660474D01*
G02X237080Y1660776I302J0D01*
G37*
G36*
G01X268576D02*
X272276D01*
G02X272578Y1660474I0J-302D01*
G01Y1650468D01*
G02X272276Y1650166I-302J0D01*
G01X268576D01*
G02X268274Y1650468I0J302D01*
G01Y1652873D01*
G02X268260Y1653110I2002J237D01*
G02X268274Y1653347I2016J0D01*
G01Y1657597D01*
G02X268260Y1657834I2002J237D01*
G02X268274Y1658071I2016J0D01*
G01Y1660474D01*
G02X268576Y1660776I302J0D01*
G37*
G36*
G01X284324D02*
X288024D01*
G02X288326Y1660474I0J-302D01*
G01Y1650468D01*
G02X288024Y1650166I-302J0D01*
G01X284324D01*
G02X284022Y1650468I0J302D01*
G01Y1652873D01*
G02X284008Y1653110I2002J237D01*
G02X284022Y1653347I2016J0D01*
G01Y1657597D01*
G02X284008Y1657834I2002J237D01*
G02X284022Y1658071I2016J0D01*
G01Y1660474D01*
G02X284324Y1660776I302J0D01*
G37*
G36*
G01X229206Y1671014D02*
X232906D01*
G02X233208Y1670711I-1J-303D01*
G01Y1660705D01*
G02X232906Y1660402I-302J-1D01*
G01X229206D01*
G02X228904Y1660705I1J303D01*
G01Y1663109D01*
G02X228890Y1663346I2002J237D01*
G02X228904Y1663583I2016J0D01*
G01Y1667833D01*
G02X228890Y1668070I2002J237D01*
G02X228904Y1668307I2016J0D01*
G01Y1670711D01*
G02X229206Y1671014I302J1D01*
G37*
G36*
G01X244954D02*
X248654D01*
G02X248956Y1670711I-1J-303D01*
G01Y1660705D01*
G02X248654Y1660402I-302J-1D01*
G01X244954D01*
G02X244652Y1660705I1J303D01*
G01Y1663109D01*
G02X244638Y1663346I2002J237D01*
G02X244652Y1663583I2016J0D01*
G01Y1667833D01*
G02X244638Y1668070I2002J237D01*
G02X244652Y1668307I2016J0D01*
G01Y1670711D01*
G02X244954Y1671014I302J1D01*
G37*
G36*
G01X276450D02*
X280150D01*
G02X280452Y1670711I-1J-303D01*
G01Y1660705D01*
G02X280150Y1660402I-302J-1D01*
G01X276450D01*
G02X276148Y1660705I1J303D01*
G01Y1663109D01*
G02X276134Y1663346I2002J237D01*
G02X276148Y1663583I2016J0D01*
G01Y1667833D01*
G02X276134Y1668070I2002J237D01*
G02X276148Y1668307I2016J0D01*
G01Y1670711D01*
G02X276450Y1671014I302J1D01*
G37*
G36*
G01X252828Y1674950D02*
X256528D01*
G02X256830Y1674648I0J-302D01*
G01Y1664642D01*
G02X256528Y1664340I-302J0D01*
G01X252828D01*
G02X252526Y1664642I0J302D01*
G01Y1667046D01*
G02X252512Y1667283I2002J237D01*
G02X252526Y1667520I2016J0D01*
G01Y1671770D01*
G02X252512Y1672007I2002J237D01*
G02X252526Y1672244I2016J0D01*
G01Y1674648D01*
G02X252828Y1674950I302J0D01*
G37*
G36*
G01X268576D02*
X272276D01*
G02X272578Y1674648I0J-302D01*
G01Y1664642D01*
G02X272276Y1664340I-302J0D01*
G01X268576D01*
G02X268274Y1664642I0J302D01*
G01Y1667046D01*
G02X268260Y1667283I2002J237D01*
G02X268274Y1667520I2016J0D01*
G01Y1671770D01*
G02X268260Y1672007I2002J237D01*
G02X268274Y1672244I2016J0D01*
G01Y1674648D01*
G02X268576Y1674950I302J0D01*
G37*
G36*
G01X284324D02*
X288024D01*
G02X288326Y1674648I0J-302D01*
G01Y1664642D01*
G02X288024Y1664340I-302J0D01*
G01X284324D01*
G02X284022Y1664642I0J302D01*
G01Y1667046D01*
G02X284008Y1667283I2002J237D01*
G02X284022Y1667520I2016J0D01*
G01Y1671770D01*
G02X284008Y1672007I2002J237D01*
G02X284022Y1672244I2016J0D01*
G01Y1674648D01*
G02X284324Y1674950I302J0D01*
G37*
G36*
G01X229206Y1685186D02*
X232906D01*
G02X233208Y1684884I0J-302D01*
G01Y1674878D01*
G02X232906Y1674576I-302J0D01*
G01X229206D01*
G02X228904Y1674878I0J302D01*
G01Y1676909D01*
G02X228813Y1677519I2002J610D01*
G02X229535Y1679101I2094J0D01*
G01X229854Y1679751D01*
G03Y1680013I-267J131D01*
G01X229536Y1680662D01*
G02X228813Y1682244I1369J1582D01*
G02X228904Y1682854I2093J0D01*
G01Y1684884D01*
G02X229206Y1685186I302J0D01*
G37*
G36*
G01X244954D02*
X248654D01*
G02X248956Y1684884I0J-302D01*
G01Y1674878D01*
G02X248654Y1674576I-302J0D01*
G01X244954D01*
G02X244652Y1674878I0J302D01*
G01Y1676909D01*
G02X244561Y1677519I2002J610D01*
G02X245283Y1679101I2094J0D01*
G01X245602Y1679751D01*
G03Y1680013I-267J131D01*
G01X245284Y1680662D01*
G02X244561Y1682244I1369J1582D01*
G02X244652Y1682854I2093J0D01*
G01Y1684884D01*
G02X244954Y1685186I302J0D01*
G37*
G36*
G01X260702D02*
X264402D01*
G02X264704Y1684884I0J-302D01*
G01Y1674878D01*
G02X264402Y1674576I-302J0D01*
G01X260702D01*
G02X260400Y1674878I0J302D01*
G01Y1676909D01*
G02X260309Y1677519I2002J610D01*
G02X261031Y1679101I2094J0D01*
G01X261350Y1679751D01*
G03Y1680013I-267J131D01*
G01X261032Y1680662D01*
G02X260309Y1682244I1369J1582D01*
G02X260400Y1682854I2093J0D01*
G01Y1684884D01*
G02X260702Y1685186I302J0D01*
G37*
G36*
G01X276450D02*
X280150D01*
G02X280452Y1684884I0J-302D01*
G01Y1674878D01*
G02X280150Y1674576I-302J0D01*
G01X276450D01*
G02X276148Y1674878I0J302D01*
G01Y1676909D01*
G02X276057Y1677519I2002J610D01*
G02X276779Y1679101I2094J0D01*
G01X277098Y1679751D01*
G03Y1680013I-267J131D01*
G01X276780Y1680662D01*
G02X276057Y1682244I1369J1582D01*
G02X276148Y1682854I2093J0D01*
G01Y1684884D01*
G02X276450Y1685186I302J0D01*
G37*
G36*
G01X560308D02*
X564008D01*
G02X564310Y1684884I0J-302D01*
G01Y1674878D01*
G02X564008Y1674576I-302J0D01*
G01X560308D01*
G02X560006Y1674878I0J302D01*
G01Y1677282D01*
G02X559992Y1677519I2002J237D01*
G02X560006Y1677756I2016J0D01*
G01Y1682007D01*
G02X559992Y1682244I2002J237D01*
G02X560006Y1682481I2016J0D01*
G01Y1684884D01*
G02X560308Y1685186I302J0D01*
G37*
G36*
G01X576056D02*
X579756D01*
G02X580058Y1684884I0J-302D01*
G01Y1674878D01*
G02X579756Y1674576I-302J0D01*
G01X576056D01*
G02X575754Y1674878I0J302D01*
G01Y1677282D01*
G02X575740Y1677519I2002J237D01*
G02X575754Y1677756I2016J0D01*
G01Y1682007D01*
G02X575740Y1682244I2002J237D01*
G02X575754Y1682481I2016J0D01*
G01Y1684884D01*
G02X576056Y1685186I302J0D01*
G37*
G36*
G01X591804D02*
X595504D01*
G02X595806Y1684884I0J-302D01*
G01Y1674878D01*
G02X595504Y1674576I-302J0D01*
G01X591804D01*
G02X591502Y1674878I0J302D01*
G01Y1677282D01*
G02X591488Y1677519I2002J237D01*
G02X591502Y1677756I2016J0D01*
G01Y1682007D01*
G02X591488Y1682244I2002J237D01*
G02X591502Y1682481I2016J0D01*
G01Y1684884D01*
G02X591804Y1685186I302J0D01*
G37*
G36*
G01X607552D02*
X611252D01*
G02X611554Y1684884I0J-302D01*
G01Y1674878D01*
G02X611252Y1674576I-302J0D01*
G01X607552D01*
G02X607250Y1674878I0J302D01*
G01Y1677282D01*
G02X607236Y1677519I2002J237D01*
G02X607250Y1677756I2016J0D01*
G01Y1682007D01*
G02X607236Y1682244I2002J237D01*
G02X607250Y1682481I2016J0D01*
G01Y1684884D01*
G02X607552Y1685186I302J0D01*
G37*
G36*
G01X1237080D02*
X1240780D01*
G02X1241082Y1684884I0J-302D01*
G01Y1674878D01*
G02X1240780Y1674576I-302J0D01*
G01X1237080D01*
G02X1236778Y1674878I0J302D01*
G01Y1676909D01*
G02X1236687Y1677519I2002J610D01*
G02X1237409Y1679101I2094J0D01*
G01X1237728Y1679751D01*
G03Y1680013I-267J131D01*
G01X1237410Y1680662D01*
G02X1236687Y1682244I1369J1582D01*
G02X1236778Y1682854I2093J0D01*
G01Y1684884D01*
G02X1237080Y1685186I302J0D01*
G37*
G36*
G01X1252828D02*
X1256528D01*
G02X1256830Y1684884I0J-302D01*
G01Y1674878D01*
G02X1256528Y1674576I-302J0D01*
G01X1252828D01*
G02X1252526Y1674878I0J302D01*
G01Y1676909D01*
G02X1252435Y1677519I2002J610D01*
G02X1253157Y1679101I2094J0D01*
G01X1253476Y1679751D01*
G03Y1680013I-267J131D01*
G01X1253158Y1680662D01*
G02X1252435Y1682244I1369J1582D01*
G02X1252526Y1682854I2093J0D01*
G01Y1684884D01*
G02X1252828Y1685186I302J0D01*
G37*
G36*
G01X1268576D02*
X1272276D01*
G02X1272578Y1684884I0J-302D01*
G01Y1674878D01*
G02X1272276Y1674576I-302J0D01*
G01X1268576D01*
G02X1268274Y1674878I0J302D01*
G01Y1676909D01*
G02X1268183Y1677519I2002J610D01*
G02X1268905Y1679101I2094J0D01*
G01X1269224Y1679751D01*
G03Y1680013I-267J131D01*
G01X1268906Y1680662D01*
G02X1268183Y1682244I1369J1582D01*
G02X1268274Y1682854I2093J0D01*
G01Y1684884D01*
G02X1268576Y1685186I302J0D01*
G37*
G36*
G01X1284324D02*
X1288024D01*
G02X1288326Y1684884I0J-302D01*
G01Y1674878D01*
G02X1288024Y1674576I-302J0D01*
G01X1284324D01*
G02X1284022Y1674878I0J302D01*
G01Y1676909D01*
G02X1283931Y1677519I2002J610D01*
G02X1284653Y1679101I2094J0D01*
G01X1284972Y1679751D01*
G03Y1680013I-267J131D01*
G01X1284654Y1680662D01*
G02X1283931Y1682244I1369J1582D01*
G02X1284022Y1682854I2093J0D01*
G01Y1684884D01*
G02X1284324Y1685186I302J0D01*
G37*
G36*
G01X1568182D02*
X1571882D01*
G02X1572184Y1684884I0J-302D01*
G01Y1674878D01*
G02X1571882Y1674576I-302J0D01*
G01X1568182D01*
G02X1567880Y1674878I0J302D01*
G01Y1677282D01*
G02X1567866Y1677519I2002J237D01*
G02X1567880Y1677756I2016J0D01*
G01Y1682007D01*
G02X1567866Y1682244I2002J237D01*
G02X1567880Y1682481I2016J0D01*
G01Y1684884D01*
G02X1568182Y1685186I302J0D01*
G37*
G36*
G01X1583930D02*
X1587630D01*
G02X1587932Y1684884I0J-302D01*
G01Y1674878D01*
G02X1587630Y1674576I-302J0D01*
G01X1583930D01*
G02X1583628Y1674878I0J302D01*
G01Y1677282D01*
G02X1583614Y1677519I2002J237D01*
G02X1583628Y1677756I2016J0D01*
G01Y1682007D01*
G02X1583614Y1682244I2002J237D01*
G02X1583628Y1682481I2016J0D01*
G01Y1684884D01*
G02X1583930Y1685186I302J0D01*
G37*
G36*
G01X1599678D02*
X1603378D01*
G02X1603680Y1684884I0J-302D01*
G01Y1674878D01*
G02X1603378Y1674576I-302J0D01*
G01X1599678D01*
G02X1599376Y1674878I0J302D01*
G01Y1677282D01*
G02X1599362Y1677519I2002J237D01*
G02X1599376Y1677756I2016J0D01*
G01Y1682007D01*
G02X1599362Y1682244I2002J237D01*
G02X1599376Y1682481I2016J0D01*
G01Y1684884D01*
G02X1599678Y1685186I302J0D01*
G37*
G36*
G01X1615426D02*
X1619126D01*
G02X1619428Y1684884I0J-302D01*
G01Y1674878D01*
G02X1619126Y1674576I-302J0D01*
G01X1615426D01*
G02X1615124Y1674878I0J302D01*
G01Y1677282D01*
G02X1615110Y1677519I2002J237D01*
G02X1615124Y1677756I2016J0D01*
G01Y1682007D01*
G02X1615110Y1682244I2002J237D01*
G02X1615124Y1682481I2016J0D01*
G01Y1684884D01*
G02X1615426Y1685186I302J0D01*
G37*
G36*
G01X296135D02*
X299835D01*
G02X300138Y1684884I1J-302D01*
G01Y1674878D01*
G02X299835Y1674576I-303J1D01*
G01X296135D01*
G02X295832Y1674878I-1J302D01*
G01Y1676912D01*
G02X295742Y1677519I2002J607D01*
G02X296464Y1679101I2094J0D01*
G01X296783Y1679751D01*
G03Y1680013I-267J131D01*
G01X296465Y1680662D01*
G02X295742Y1682244I1369J1582D01*
G02X295832Y1682851I2092J0D01*
G01Y1684884D01*
G02X296135Y1685186I303J-1D01*
G37*
G36*
G01X311883D02*
X315583D01*
G02X315886Y1684884I1J-302D01*
G01Y1674878D01*
G02X315583Y1674576I-303J1D01*
G01X311883D01*
G02X311580Y1674878I-1J302D01*
G01Y1676912D01*
G02X311490Y1677519I2002J607D01*
G02X312212Y1679101I2094J0D01*
G01X312531Y1679751D01*
G03Y1680013I-267J131D01*
G01X312213Y1680662D01*
G02X311490Y1682244I1369J1582D01*
G02X311580Y1682851I2092J0D01*
G01Y1684884D01*
G02X311883Y1685186I303J-1D01*
G37*
G36*
G01X327631D02*
X331331D01*
G02X331634Y1684884I1J-302D01*
G01Y1674878D01*
G02X331331Y1674576I-303J1D01*
G01X327631D01*
G02X327328Y1674878I-1J302D01*
G01Y1676912D01*
G02X327238Y1677519I2002J607D01*
G02X327960Y1679101I2094J0D01*
G01X328279Y1679751D01*
G03Y1680013I-267J131D01*
G01X327961Y1680662D01*
G02X327238Y1682244I1369J1582D01*
G02X327328Y1682851I2092J0D01*
G01Y1684884D01*
G02X327631Y1685186I303J-1D01*
G37*
G36*
G01X343379D02*
X347079D01*
G02X347382Y1684884I1J-302D01*
G01Y1674878D01*
G02X347079Y1674576I-303J1D01*
G01X343379D01*
G02X343076Y1674878I-1J302D01*
G01Y1676912D01*
G02X342986Y1677519I2002J607D01*
G02X343708Y1679101I2094J0D01*
G01X344027Y1679751D01*
G03Y1680013I-267J131D01*
G01X343709Y1680662D01*
G02X342986Y1682244I1369J1582D01*
G02X343076Y1682851I2092J0D01*
G01Y1684884D01*
G02X343379Y1685186I303J-1D01*
G37*
G36*
G01X493379D02*
X497079D01*
G02X497382Y1684884I1J-302D01*
G01Y1674878D01*
G02X497079Y1674576I-303J1D01*
G01X493379D01*
G02X493076Y1674878I-1J302D01*
G01Y1677290D01*
G02X493063Y1677519I2003J229D01*
G02X493076Y1677748I2016J0D01*
G01Y1682015D01*
G02X493063Y1682244I2003J229D01*
G02X493076Y1682473I2016J0D01*
G01Y1684884D01*
G02X493379Y1685186I303J-1D01*
G37*
G36*
G01X509127D02*
X512827D01*
G02X513130Y1684884I1J-302D01*
G01Y1674878D01*
G02X512827Y1674576I-303J1D01*
G01X509127D01*
G02X508824Y1674878I-1J302D01*
G01Y1677290D01*
G02X508811Y1677519I2003J229D01*
G02X508824Y1677748I2016J0D01*
G01Y1682015D01*
G02X508811Y1682244I2003J229D01*
G02X508824Y1682473I2016J0D01*
G01Y1684884D01*
G02X509127Y1685186I303J-1D01*
G37*
G36*
G01X524875D02*
X528575D01*
G02X528878Y1684884I1J-302D01*
G01Y1674878D01*
G02X528575Y1674576I-303J1D01*
G01X524875D01*
G02X524572Y1674878I-1J302D01*
G01Y1677290D01*
G02X524559Y1677519I2003J229D01*
G02X524572Y1677748I2016J0D01*
G01Y1682015D01*
G02X524559Y1682244I2003J229D01*
G02X524572Y1682473I2016J0D01*
G01Y1684884D01*
G02X524875Y1685186I303J-1D01*
G37*
G36*
G01X540623D02*
X544323D01*
G02X544626Y1684884I1J-302D01*
G01Y1674878D01*
G02X544323Y1674576I-303J1D01*
G01X540623D01*
G02X540320Y1674878I-1J302D01*
G01Y1677290D01*
G02X540307Y1677519I2003J229D01*
G02X540320Y1677748I2016J0D01*
G01Y1682015D01*
G02X540307Y1682244I2003J229D01*
G02X540320Y1682473I2016J0D01*
G01Y1684884D01*
G02X540623Y1685186I303J-1D01*
G37*
G36*
G01X1304009D02*
X1307709D01*
G02X1308012Y1684884I1J-302D01*
G01Y1674878D01*
G02X1307709Y1674576I-303J1D01*
G01X1304009D01*
G02X1303706Y1674878I-1J302D01*
G01Y1676912D01*
G02X1303616Y1677519I2002J607D01*
G02X1304338Y1679101I2094J0D01*
G01X1304657Y1679751D01*
G03Y1680013I-267J131D01*
G01X1304339Y1680662D01*
G02X1303616Y1682244I1369J1582D01*
G02X1303706Y1682851I2092J0D01*
G01Y1684884D01*
G02X1304009Y1685186I303J-1D01*
G37*
G36*
G01X1319757D02*
X1323457D01*
G02X1323760Y1684884I1J-302D01*
G01Y1674878D01*
G02X1323457Y1674576I-303J1D01*
G01X1319757D01*
G02X1319454Y1674878I-1J302D01*
G01Y1676912D01*
G02X1319364Y1677519I2002J607D01*
G02X1320086Y1679101I2094J0D01*
G01X1320405Y1679751D01*
G03Y1680013I-267J131D01*
G01X1320087Y1680662D01*
G02X1319364Y1682244I1369J1582D01*
G02X1319454Y1682851I2092J0D01*
G01Y1684884D01*
G02X1319757Y1685186I303J-1D01*
G37*
G36*
G01X1335505D02*
X1339205D01*
G02X1339508Y1684884I1J-302D01*
G01Y1674878D01*
G02X1339205Y1674576I-303J1D01*
G01X1335505D01*
G02X1335202Y1674878I-1J302D01*
G01Y1676912D01*
G02X1335112Y1677519I2002J607D01*
G02X1335834Y1679101I2094J0D01*
G01X1336153Y1679751D01*
G03Y1680013I-267J131D01*
G01X1335835Y1680662D01*
G02X1335112Y1682244I1369J1582D01*
G02X1335202Y1682851I2092J0D01*
G01Y1684884D01*
G02X1335505Y1685186I303J-1D01*
G37*
G36*
G01X1351253D02*
X1354953D01*
G02X1355256Y1684884I1J-302D01*
G01Y1674878D01*
G02X1354953Y1674576I-303J1D01*
G01X1351253D01*
G02X1350950Y1674878I-1J302D01*
G01Y1676912D01*
G02X1350860Y1677519I2002J607D01*
G02X1351582Y1679101I2094J0D01*
G01X1351901Y1679751D01*
G03Y1680013I-267J131D01*
G01X1351583Y1680662D01*
G02X1350860Y1682244I1369J1582D01*
G02X1350950Y1682851I2092J0D01*
G01Y1684884D01*
G02X1351253Y1685186I303J-1D01*
G37*
G36*
G01X1501253D02*
X1504953D01*
G02X1505256Y1684884I1J-302D01*
G01Y1674878D01*
G02X1504953Y1674576I-303J1D01*
G01X1501253D01*
G02X1500950Y1674878I-1J302D01*
G01Y1677290D01*
G02X1500937Y1677519I2003J229D01*
G02X1500950Y1677748I2016J0D01*
G01Y1682015D01*
G02X1500937Y1682244I2003J229D01*
G02X1500950Y1682473I2016J0D01*
G01Y1684884D01*
G02X1501253Y1685186I303J-1D01*
G37*
G36*
G01X1517001D02*
X1520701D01*
G02X1521004Y1684884I1J-302D01*
G01Y1674878D01*
G02X1520701Y1674576I-303J1D01*
G01X1517001D01*
G02X1516698Y1674878I-1J302D01*
G01Y1677290D01*
G02X1516685Y1677519I2003J229D01*
G02X1516698Y1677748I2016J0D01*
G01Y1682015D01*
G02X1516685Y1682244I2003J229D01*
G02X1516698Y1682473I2016J0D01*
G01Y1684884D01*
G02X1517001Y1685186I303J-1D01*
G37*
G36*
G01X1532749D02*
X1536449D01*
G02X1536752Y1684884I1J-302D01*
G01Y1674878D01*
G02X1536449Y1674576I-303J1D01*
G01X1532749D01*
G02X1532446Y1674878I-1J302D01*
G01Y1677290D01*
G02X1532433Y1677519I2003J229D01*
G02X1532446Y1677748I2016J0D01*
G01Y1682015D01*
G02X1532433Y1682244I2003J229D01*
G02X1532446Y1682473I2016J0D01*
G01Y1684884D01*
G02X1532749Y1685186I303J-1D01*
G37*
G36*
G01X1548497D02*
X1552197D01*
G02X1552500Y1684884I1J-302D01*
G01Y1674878D01*
G02X1552197Y1674576I-303J1D01*
G01X1548497D01*
G02X1548194Y1674878I-1J302D01*
G01Y1677290D01*
G02X1548181Y1677519I2003J229D01*
G02X1548194Y1677748I2016J0D01*
G01Y1682015D01*
G02X1548181Y1682244I2003J229D01*
G02X1548194Y1682473I2016J0D01*
G01Y1684884D01*
G02X1548497Y1685186I303J-1D01*
G37*
G36*
G01X1343379Y1689122D02*
X1347079D01*
G02X1347382Y1688820I1J-302D01*
G01Y1678814D01*
G02X1347079Y1678512I-303J1D01*
G01X1343379D01*
G02X1343076Y1678814I-1J302D01*
G01Y1680849D01*
G02X1342986Y1681456I2002J607D01*
G02X1343709Y1683038I2092J0D01*
G01X1344027Y1683687D01*
G03Y1683949I-267J131D01*
G01X1343709Y1684598D01*
G02X1342986Y1686180I1369J1582D01*
G02X1343076Y1686787I2092J0D01*
G01Y1688820D01*
G02X1343379Y1689122I303J-1D01*
G37*
G36*
G01X237080Y1689124D02*
X240780D01*
G02X241082Y1688821I-1J-303D01*
G01Y1678815D01*
G02X240780Y1678512I-302J-1D01*
G01X237080D01*
G02X236778Y1678815I1J303D01*
G01Y1680846D01*
G02X236687Y1681456I2002J610D01*
G02X237409Y1683038I2094J0D01*
G01X237728Y1683688D01*
G03Y1683950I-267J131D01*
G01X237411Y1684597D01*
G02X236687Y1686180I1369J1583D01*
G02X236778Y1686790I2093J0D01*
G01Y1688821D01*
G02X237080Y1689124I302J1D01*
G37*
G36*
G01X252828D02*
X256528D01*
G02X256830Y1688821I-1J-303D01*
G01Y1678815D01*
G02X256528Y1678512I-302J-1D01*
G01X252828D01*
G02X252526Y1678815I1J303D01*
G01Y1680846D01*
G02X252435Y1681456I2002J610D01*
G02X253157Y1683038I2094J0D01*
G01X253476Y1683688D01*
G03Y1683950I-267J131D01*
G01X253159Y1684597D01*
G02X252435Y1686180I1369J1583D01*
G02X252526Y1686790I2093J0D01*
G01Y1688821D01*
G02X252828Y1689124I302J1D01*
G37*
G36*
G01X268576D02*
X272276D01*
G02X272578Y1688821I-1J-303D01*
G01Y1678815D01*
G02X272276Y1678512I-302J-1D01*
G01X268576D01*
G02X268274Y1678815I1J303D01*
G01Y1680846D01*
G02X268183Y1681456I2002J610D01*
G02X268905Y1683038I2094J0D01*
G01X269224Y1683688D01*
G03Y1683950I-267J131D01*
G01X268907Y1684597D01*
G02X268183Y1686180I1369J1583D01*
G02X268274Y1686790I2093J0D01*
G01Y1688821D01*
G02X268576Y1689124I302J1D01*
G37*
G36*
G01X284324D02*
X288024D01*
G02X288326Y1688821I-1J-303D01*
G01Y1678815D01*
G02X288024Y1678512I-302J-1D01*
G01X284324D01*
G02X284022Y1678815I1J303D01*
G01Y1680846D01*
G02X283931Y1681456I2002J610D01*
G02X284653Y1683038I2094J0D01*
G01X284972Y1683688D01*
G03Y1683950I-267J131D01*
G01X284655Y1684597D01*
G02X283931Y1686180I1369J1583D01*
G02X284022Y1686790I2093J0D01*
G01Y1688821D01*
G02X284324Y1689124I302J1D01*
G37*
G36*
G01X304009D02*
X307709D01*
G02X308012Y1688821I0J-303D01*
G01Y1678815D01*
G02X307709Y1678512I-303J0D01*
G01X304009D01*
G02X303706Y1678815I0J303D01*
G01Y1680849D01*
G02X303616Y1681456I2002J607D01*
G02X304338Y1683038I2094J0D01*
G01X304657Y1683688D01*
G03Y1683950I-267J131D01*
G01X304340Y1684597D01*
G02X303616Y1686180I1369J1583D01*
G02X303706Y1686787I2092J0D01*
G01Y1688821D01*
G02X304009Y1689124I303J0D01*
G37*
G36*
G01X319757D02*
X323457D01*
G02X323760Y1688821I0J-303D01*
G01Y1678815D01*
G02X323457Y1678512I-303J0D01*
G01X319757D01*
G02X319454Y1678815I0J303D01*
G01Y1680849D01*
G02X319364Y1681456I2002J607D01*
G02X320086Y1683038I2094J0D01*
G01X320405Y1683688D01*
G03Y1683950I-267J131D01*
G01X320088Y1684597D01*
G02X319364Y1686180I1369J1583D01*
G02X319454Y1686787I2092J0D01*
G01Y1688821D01*
G02X319757Y1689124I303J0D01*
G37*
G36*
G01X335505D02*
X339205D01*
G02X339508Y1688821I0J-303D01*
G01Y1678815D01*
G02X339205Y1678512I-303J0D01*
G01X335505D01*
G02X335202Y1678815I0J303D01*
G01Y1680849D01*
G02X335112Y1681456I2002J607D01*
G02X335834Y1683038I2094J0D01*
G01X336153Y1683688D01*
G03Y1683950I-267J131D01*
G01X335836Y1684597D01*
G02X335112Y1686180I1369J1583D01*
G02X335202Y1686787I2092J0D01*
G01Y1688821D01*
G02X335505Y1689124I303J0D01*
G37*
G36*
G01X351253D02*
X354953D01*
G02X355256Y1688821I0J-303D01*
G01Y1678815D01*
G02X354953Y1678512I-303J0D01*
G01X351253D01*
G02X350950Y1678815I0J303D01*
G01Y1680849D01*
G02X350860Y1681456I2002J607D01*
G02X351582Y1683038I2094J0D01*
G01X351901Y1683688D01*
G03Y1683950I-267J131D01*
G01X351584Y1684597D01*
G02X350860Y1686180I1369J1583D01*
G02X350950Y1686787I2092J0D01*
G01Y1688821D01*
G02X351253Y1689124I303J0D01*
G37*
G36*
G01X501253D02*
X504953D01*
G02X505256Y1688821I0J-303D01*
G01Y1678815D01*
G02X504953Y1678512I-303J0D01*
G01X501253D01*
G02X500950Y1678815I0J303D01*
G01Y1681227D01*
G02X500937Y1681456I2003J229D01*
G02X500950Y1681685I2016J0D01*
G01Y1685951D01*
G02X500937Y1686180I2003J229D01*
G02X500950Y1686409I2016J0D01*
G01Y1688821D01*
G02X501253Y1689124I303J0D01*
G37*
G36*
G01X517001D02*
X520701D01*
G02X521004Y1688821I0J-303D01*
G01Y1678815D01*
G02X520701Y1678512I-303J0D01*
G01X517001D01*
G02X516698Y1678815I0J303D01*
G01Y1681227D01*
G02X516685Y1681456I2003J229D01*
G02X516698Y1681685I2016J0D01*
G01Y1685951D01*
G02X516685Y1686180I2003J229D01*
G02X516698Y1686409I2016J0D01*
G01Y1688821D01*
G02X517001Y1689124I303J0D01*
G37*
G36*
G01X532749D02*
X536449D01*
G02X536752Y1688821I0J-303D01*
G01Y1678815D01*
G02X536449Y1678512I-303J0D01*
G01X532749D01*
G02X532446Y1678815I0J303D01*
G01Y1681227D01*
G02X532433Y1681456I2003J229D01*
G02X532446Y1681685I2016J0D01*
G01Y1685951D01*
G02X532433Y1686180I2003J229D01*
G02X532446Y1686409I2016J0D01*
G01Y1688821D01*
G02X532749Y1689124I303J0D01*
G37*
G36*
G01X548497D02*
X552197D01*
G02X552500Y1688821I0J-303D01*
G01Y1678815D01*
G02X552197Y1678512I-303J0D01*
G01X548497D01*
G02X548194Y1678815I0J303D01*
G01Y1681227D01*
G02X548181Y1681456I2003J229D01*
G02X548194Y1681685I2016J0D01*
G01Y1685951D01*
G02X548181Y1686180I2003J229D01*
G02X548194Y1686409I2016J0D01*
G01Y1688821D01*
G02X548497Y1689124I303J0D01*
G37*
G36*
G01X568182D02*
X571882D01*
G02X572184Y1688821I-1J-303D01*
G01Y1678815D01*
G02X571882Y1678512I-302J-1D01*
G01X568182D01*
G02X567880Y1678815I1J303D01*
G01Y1681219D01*
G02X567866Y1681456I2002J237D01*
G02X567880Y1681693I2016J0D01*
G01Y1685943D01*
G02X567866Y1686180I2002J237D01*
G02X567880Y1686417I2016J0D01*
G01Y1688821D01*
G02X568182Y1689124I302J1D01*
G37*
G36*
G01X583930D02*
X587630D01*
G02X587932Y1688821I-1J-303D01*
G01Y1678815D01*
G02X587630Y1678512I-302J-1D01*
G01X583930D01*
G02X583628Y1678815I1J303D01*
G01Y1681219D01*
G02X583614Y1681456I2002J237D01*
G02X583628Y1681693I2016J0D01*
G01Y1685943D01*
G02X583614Y1686180I2002J237D01*
G02X583628Y1686417I2016J0D01*
G01Y1688821D01*
G02X583930Y1689124I302J1D01*
G37*
G36*
G01X599678D02*
X603378D01*
G02X603680Y1688821I-1J-303D01*
G01Y1678815D01*
G02X603378Y1678512I-302J-1D01*
G01X599678D01*
G02X599376Y1678815I1J303D01*
G01Y1681219D01*
G02X599362Y1681456I2002J237D01*
G02X599376Y1681693I2016J0D01*
G01Y1685943D01*
G02X599362Y1686180I2002J237D01*
G02X599376Y1686417I2016J0D01*
G01Y1688821D01*
G02X599678Y1689124I302J1D01*
G37*
G36*
G01X615426D02*
X619126D01*
G02X619428Y1688821I-1J-303D01*
G01Y1678815D01*
G02X619126Y1678512I-302J-1D01*
G01X615426D01*
G02X615124Y1678815I1J303D01*
G01Y1681219D01*
G02X615110Y1681456I2002J237D01*
G02X615124Y1681693I2016J0D01*
G01Y1685943D01*
G02X615110Y1686180I2002J237D01*
G02X615124Y1686417I2016J0D01*
G01Y1688821D01*
G02X615426Y1689124I302J1D01*
G37*
G36*
G01X1244954D02*
X1248654D01*
G02X1248956Y1688821I-1J-303D01*
G01Y1678815D01*
G02X1248654Y1678512I-302J-1D01*
G01X1244954D01*
G02X1244652Y1678815I1J303D01*
G01Y1680846D01*
G02X1244561Y1681456I2002J610D01*
G02X1245283Y1683038I2094J0D01*
G01X1245602Y1683688D01*
G03Y1683950I-267J131D01*
G01X1245285Y1684597D01*
G02X1244561Y1686180I1369J1583D01*
G02X1244652Y1686790I2093J0D01*
G01Y1688821D01*
G02X1244954Y1689124I302J1D01*
G37*
G36*
G01X1260702D02*
X1264402D01*
G02X1264704Y1688821I-1J-303D01*
G01Y1678815D01*
G02X1264402Y1678512I-302J-1D01*
G01X1260702D01*
G02X1260400Y1678815I1J303D01*
G01Y1680846D01*
G02X1260309Y1681456I2002J610D01*
G02X1261031Y1683038I2094J0D01*
G01X1261350Y1683688D01*
G03Y1683950I-267J131D01*
G01X1261033Y1684597D01*
G02X1260309Y1686180I1369J1583D01*
G02X1260400Y1686790I2093J0D01*
G01Y1688821D01*
G02X1260702Y1689124I302J1D01*
G37*
G36*
G01X1276450D02*
X1280150D01*
G02X1280452Y1688821I-1J-303D01*
G01Y1678815D01*
G02X1280150Y1678512I-302J-1D01*
G01X1276450D01*
G02X1276148Y1678815I1J303D01*
G01Y1680846D01*
G02X1276057Y1681456I2002J610D01*
G02X1276779Y1683038I2094J0D01*
G01X1277098Y1683688D01*
G03Y1683950I-267J131D01*
G01X1276781Y1684597D01*
G02X1276057Y1686180I1369J1583D01*
G02X1276148Y1686790I2093J0D01*
G01Y1688821D01*
G02X1276450Y1689124I302J1D01*
G37*
G36*
G01X1292198D02*
X1295898D01*
G02X1296200Y1688821I-1J-303D01*
G01Y1678815D01*
G02X1295898Y1678512I-302J-1D01*
G01X1292198D01*
G02X1291896Y1678815I1J303D01*
G01Y1680846D01*
G02X1291805Y1681456I2002J610D01*
G02X1292527Y1683038I2094J0D01*
G01X1292846Y1683688D01*
G03Y1683950I-267J131D01*
G01X1292529Y1684597D01*
G02X1291805Y1686180I1369J1583D01*
G02X1291896Y1686790I2093J0D01*
G01Y1688821D01*
G02X1292198Y1689124I302J1D01*
G37*
G36*
G01X1311883D02*
X1315583D01*
G02X1315886Y1688821I0J-303D01*
G01Y1678815D01*
G02X1315583Y1678512I-303J0D01*
G01X1311883D01*
G02X1311580Y1678815I0J303D01*
G01Y1680849D01*
G02X1311490Y1681456I2002J607D01*
G02X1312212Y1683038I2094J0D01*
G01X1312531Y1683688D01*
G03Y1683950I-267J131D01*
G01X1312214Y1684597D01*
G02X1311490Y1686180I1369J1583D01*
G02X1311580Y1686787I2092J0D01*
G01Y1688821D01*
G02X1311883Y1689124I303J0D01*
G37*
G36*
G01X1327631D02*
X1331331D01*
G02X1331634Y1688821I0J-303D01*
G01Y1678815D01*
G02X1331331Y1678512I-303J0D01*
G01X1327631D01*
G02X1327328Y1678815I0J303D01*
G01Y1680849D01*
G02X1327238Y1681456I2002J607D01*
G02X1327960Y1683038I2094J0D01*
G01X1328279Y1683688D01*
G03Y1683950I-267J131D01*
G01X1327962Y1684597D01*
G02X1327238Y1686180I1369J1583D01*
G02X1327328Y1686787I2092J0D01*
G01Y1688821D01*
G02X1327631Y1689124I303J0D01*
G37*
G36*
G01X1359127D02*
X1362827D01*
G02X1363130Y1688821I0J-303D01*
G01Y1678815D01*
G02X1362827Y1678512I-303J0D01*
G01X1359127D01*
G02X1358824Y1678815I0J303D01*
G01Y1680849D01*
G02X1358734Y1681456I2002J607D01*
G02X1359456Y1683038I2094J0D01*
G01X1359775Y1683688D01*
G03Y1683950I-267J131D01*
G01X1359458Y1684597D01*
G02X1358734Y1686180I1369J1583D01*
G02X1358824Y1686787I2092J0D01*
G01Y1688821D01*
G02X1359127Y1689124I303J0D01*
G37*
G36*
G01X1509127D02*
X1512827D01*
G02X1513130Y1688821I0J-303D01*
G01Y1678815D01*
G02X1512827Y1678512I-303J0D01*
G01X1509127D01*
G02X1508824Y1678815I0J303D01*
G01Y1681227D01*
G02X1508811Y1681456I2003J229D01*
G02X1508824Y1681685I2016J0D01*
G01Y1685951D01*
G02X1508811Y1686180I2003J229D01*
G02X1508824Y1686409I2016J0D01*
G01Y1688821D01*
G02X1509127Y1689124I303J0D01*
G37*
G36*
G01X1524875D02*
X1528575D01*
G02X1528878Y1688821I0J-303D01*
G01Y1678815D01*
G02X1528575Y1678512I-303J0D01*
G01X1524875D01*
G02X1524572Y1678815I0J303D01*
G01Y1681227D01*
G02X1524559Y1681456I2003J229D01*
G02X1524572Y1681685I2016J0D01*
G01Y1685951D01*
G02X1524559Y1686180I2003J229D01*
G02X1524572Y1686409I2016J0D01*
G01Y1688821D01*
G02X1524875Y1689124I303J0D01*
G37*
G36*
G01X1540623D02*
X1544323D01*
G02X1544626Y1688821I0J-303D01*
G01Y1678815D01*
G02X1544323Y1678512I-303J0D01*
G01X1540623D01*
G02X1540320Y1678815I0J303D01*
G01Y1681227D01*
G02X1540307Y1681456I2003J229D01*
G02X1540320Y1681685I2016J0D01*
G01Y1685951D01*
G02X1540307Y1686180I2003J229D01*
G02X1540320Y1686409I2016J0D01*
G01Y1688821D01*
G02X1540623Y1689124I303J0D01*
G37*
G36*
G01X1556371D02*
X1560071D01*
G02X1560374Y1688821I0J-303D01*
G01Y1678815D01*
G02X1560071Y1678512I-303J0D01*
G01X1556371D01*
G02X1556068Y1678815I0J303D01*
G01Y1681227D01*
G02X1556055Y1681456I2003J229D01*
G02X1556068Y1681685I2016J0D01*
G01Y1685951D01*
G02X1556055Y1686180I2003J229D01*
G02X1556068Y1686409I2016J0D01*
G01Y1688821D01*
G02X1556371Y1689124I303J0D01*
G37*
G36*
G01X1576056D02*
X1579756D01*
G02X1580058Y1688821I-1J-303D01*
G01Y1678815D01*
G02X1579756Y1678512I-302J-1D01*
G01X1576056D01*
G02X1575754Y1678815I1J303D01*
G01Y1681219D01*
G02X1575740Y1681456I2002J237D01*
G02X1575754Y1681693I2016J0D01*
G01Y1685943D01*
G02X1575740Y1686180I2002J237D01*
G02X1575754Y1686417I2016J0D01*
G01Y1688821D01*
G02X1576056Y1689124I302J1D01*
G37*
G36*
G01X1591804D02*
X1595504D01*
G02X1595806Y1688821I-1J-303D01*
G01Y1678815D01*
G02X1595504Y1678512I-302J-1D01*
G01X1591804D01*
G02X1591502Y1678815I1J303D01*
G01Y1681219D01*
G02X1591488Y1681456I2002J237D01*
G02X1591502Y1681693I2016J0D01*
G01Y1685943D01*
G02X1591488Y1686180I2002J237D01*
G02X1591502Y1686417I2016J0D01*
G01Y1688821D01*
G02X1591804Y1689124I302J1D01*
G37*
G36*
G01X1607552D02*
X1611252D01*
G02X1611554Y1688821I-1J-303D01*
G01Y1678815D01*
G02X1611252Y1678512I-302J-1D01*
G01X1607552D01*
G02X1607250Y1678815I1J303D01*
G01Y1681219D01*
G02X1607236Y1681456I2002J237D01*
G02X1607250Y1681693I2016J0D01*
G01Y1685943D01*
G02X1607236Y1686180I2002J237D01*
G02X1607250Y1686417I2016J0D01*
G01Y1688821D01*
G02X1607552Y1689124I302J1D01*
G37*
G36*
G01X1623300D02*
X1627000D01*
G02X1627302Y1688821I-1J-303D01*
G01Y1678815D01*
G02X1627000Y1678512I-302J-1D01*
G01X1623300D01*
G02X1622998Y1678815I1J303D01*
G01Y1681219D01*
G02X1622984Y1681456I2002J237D01*
G02X1622998Y1681693I2016J0D01*
G01Y1685943D01*
G02X1622984Y1686180I2002J237D01*
G02X1622998Y1686417I2016J0D01*
G01Y1688821D01*
G02X1623300Y1689124I302J1D01*
G37*
G36*
G01X229206Y1699360D02*
X232906D01*
G02X233208Y1699057I-1J-303D01*
G01Y1689051D01*
G02X232906Y1688748I-302J-1D01*
G01X229206D01*
G02X228904Y1689051I1J303D01*
G01Y1691455D01*
G02X228890Y1691692I2002J237D01*
G02X228904Y1691929I2016J0D01*
G01Y1696180D01*
G02X228890Y1696417I2002J237D01*
G02X228904Y1696654I2016J0D01*
G01Y1699057D01*
G02X229206Y1699360I302J1D01*
G37*
G36*
G01X244954D02*
X248654D01*
G02X248956Y1699057I-1J-303D01*
G01Y1689051D01*
G02X248654Y1688748I-302J-1D01*
G01X244954D01*
G02X244652Y1689051I1J303D01*
G01Y1691455D01*
G02X244638Y1691692I2002J237D01*
G02X244652Y1691929I2016J0D01*
G01Y1696180D01*
G02X244638Y1696417I2002J237D01*
G02X244652Y1696654I2016J0D01*
G01Y1699057D01*
G02X244954Y1699360I302J1D01*
G37*
G36*
G01X260702D02*
X264402D01*
G02X264704Y1699057I-1J-303D01*
G01Y1689051D01*
G02X264402Y1688748I-302J-1D01*
G01X260702D01*
G02X260400Y1689051I1J303D01*
G01Y1691455D01*
G02X260386Y1691692I2002J237D01*
G02X260400Y1691929I2016J0D01*
G01Y1696180D01*
G02X260386Y1696417I2002J237D01*
G02X260400Y1696654I2016J0D01*
G01Y1699057D01*
G02X260702Y1699360I302J1D01*
G37*
G36*
G01X276450D02*
X280150D01*
G02X280452Y1699057I-1J-303D01*
G01Y1689051D01*
G02X280150Y1688748I-302J-1D01*
G01X276450D01*
G02X276148Y1689051I1J303D01*
G01Y1691455D01*
G02X276134Y1691692I2002J237D01*
G02X276148Y1691929I2016J0D01*
G01Y1696180D01*
G02X276134Y1696417I2002J237D01*
G02X276148Y1696654I2016J0D01*
G01Y1699057D01*
G02X276450Y1699360I302J1D01*
G37*
G36*
G01X296135D02*
X299835D01*
G02X300138Y1699057I0J-303D01*
G01Y1689051D01*
G02X299835Y1688748I-303J0D01*
G01X296135D01*
G02X295832Y1689051I0J303D01*
G01Y1691463D01*
G02X295819Y1691692I2003J229D01*
G02X295832Y1691921I2016J0D01*
G01Y1696188D01*
G02X295819Y1696417I2003J229D01*
G02X295832Y1696646I2016J0D01*
G01Y1699057D01*
G02X296135Y1699360I303J0D01*
G37*
G36*
G01X311883D02*
X315583D01*
G02X315886Y1699057I0J-303D01*
G01Y1689051D01*
G02X315583Y1688748I-303J0D01*
G01X311883D01*
G02X311580Y1689051I0J303D01*
G01Y1691463D01*
G02X311567Y1691692I2003J229D01*
G02X311580Y1691921I2016J0D01*
G01Y1696188D01*
G02X311567Y1696417I2003J229D01*
G02X311580Y1696646I2016J0D01*
G01Y1699057D01*
G02X311883Y1699360I303J0D01*
G37*
G36*
G01X327631D02*
X331331D01*
G02X331634Y1699057I0J-303D01*
G01Y1689051D01*
G02X331331Y1688748I-303J0D01*
G01X327631D01*
G02X327328Y1689051I0J303D01*
G01Y1691463D01*
G02X327315Y1691692I2003J229D01*
G02X327328Y1691921I2016J0D01*
G01Y1696188D01*
G02X327315Y1696417I2003J229D01*
G02X327328Y1696646I2016J0D01*
G01Y1699057D01*
G02X327631Y1699360I303J0D01*
G37*
G36*
G01X343379D02*
X347079D01*
G02X347382Y1699057I0J-303D01*
G01Y1689051D01*
G02X347079Y1688748I-303J0D01*
G01X343379D01*
G02X343076Y1689051I0J303D01*
G01Y1691463D01*
G02X343063Y1691692I2003J229D01*
G02X343076Y1691921I2016J0D01*
G01Y1696188D01*
G02X343063Y1696417I2003J229D01*
G02X343076Y1696646I2016J0D01*
G01Y1699057D01*
G02X343379Y1699360I303J0D01*
G37*
G36*
G01X493379D02*
X497079D01*
G02X497382Y1699057I0J-303D01*
G01Y1689051D01*
G02X497079Y1688748I-303J0D01*
G01X493379D01*
G02X493076Y1689051I0J303D01*
G01Y1691085D01*
G02X492986Y1691692I2002J607D01*
G02X493708Y1693274I2094J0D01*
G01X494027Y1693924D01*
G03Y1694186I-267J131D01*
G01X493709Y1694835D01*
G02X492986Y1696417I1369J1582D01*
G02X493076Y1697024I2092J0D01*
G01Y1699057D01*
G02X493379Y1699360I303J0D01*
G37*
G36*
G01X509127D02*
X512827D01*
G02X513130Y1699057I0J-303D01*
G01Y1689051D01*
G02X512827Y1688748I-303J0D01*
G01X509127D01*
G02X508824Y1689051I0J303D01*
G01Y1691085D01*
G02X508734Y1691692I2002J607D01*
G02X509456Y1693274I2094J0D01*
G01X509775Y1693924D01*
G03Y1694186I-267J131D01*
G01X509457Y1694835D01*
G02X508734Y1696417I1369J1582D01*
G02X508824Y1697024I2092J0D01*
G01Y1699057D01*
G02X509127Y1699360I303J0D01*
G37*
G36*
G01X524875D02*
X528575D01*
G02X528878Y1699057I0J-303D01*
G01Y1689051D01*
G02X528575Y1688748I-303J0D01*
G01X524875D01*
G02X524572Y1689051I0J303D01*
G01Y1691085D01*
G02X524482Y1691692I2002J607D01*
G02X525204Y1693274I2094J0D01*
G01X525523Y1693924D01*
G03Y1694186I-267J131D01*
G01X525205Y1694835D01*
G02X524482Y1696417I1369J1582D01*
G02X524572Y1697024I2092J0D01*
G01Y1699057D01*
G02X524875Y1699360I303J0D01*
G37*
G36*
G01X540623D02*
X544323D01*
G02X544626Y1699057I0J-303D01*
G01Y1689051D01*
G02X544323Y1688748I-303J0D01*
G01X540623D01*
G02X540320Y1689051I0J303D01*
G01Y1691085D01*
G02X540230Y1691692I2002J607D01*
G02X540952Y1693274I2094J0D01*
G01X541271Y1693924D01*
G03Y1694186I-267J131D01*
G01X540953Y1694835D01*
G02X540230Y1696417I1369J1582D01*
G02X540320Y1697024I2092J0D01*
G01Y1699057D01*
G02X540623Y1699360I303J0D01*
G37*
G36*
G01X560308D02*
X564008D01*
G02X564310Y1699057I-1J-303D01*
G01Y1689051D01*
G02X564008Y1688748I-302J-1D01*
G01X560308D01*
G02X560006Y1689051I1J303D01*
G01Y1691082D01*
G02X559915Y1691692I2002J610D01*
G02X560637Y1693274I2094J0D01*
G01X560956Y1693924D01*
G03Y1694186I-267J131D01*
G01X560638Y1694835D01*
G02X559915Y1696417I1369J1582D01*
G02X560006Y1697027I2093J0D01*
G01Y1699057D01*
G02X560308Y1699360I302J1D01*
G37*
G36*
G01X576056D02*
X579756D01*
G02X580058Y1699057I-1J-303D01*
G01Y1689051D01*
G02X579756Y1688748I-302J-1D01*
G01X576056D01*
G02X575754Y1689051I1J303D01*
G01Y1691082D01*
G02X575663Y1691692I2002J610D01*
G02X576385Y1693274I2094J0D01*
G01X576704Y1693924D01*
G03Y1694186I-267J131D01*
G01X576386Y1694835D01*
G02X575663Y1696417I1369J1582D01*
G02X575754Y1697027I2093J0D01*
G01Y1699057D01*
G02X576056Y1699360I302J1D01*
G37*
G36*
G01X591804D02*
X595504D01*
G02X595806Y1699057I-1J-303D01*
G01Y1689051D01*
G02X595504Y1688748I-302J-1D01*
G01X591804D01*
G02X591502Y1689051I1J303D01*
G01Y1691082D01*
G02X591411Y1691692I2002J610D01*
G02X592133Y1693274I2094J0D01*
G01X592452Y1693924D01*
G03Y1694186I-267J131D01*
G01X592134Y1694835D01*
G02X591411Y1696417I1369J1582D01*
G02X591502Y1697027I2093J0D01*
G01Y1699057D01*
G02X591804Y1699360I302J1D01*
G37*
G36*
G01X607552D02*
X611252D01*
G02X611554Y1699057I-1J-303D01*
G01Y1689051D01*
G02X611252Y1688748I-302J-1D01*
G01X607552D01*
G02X607250Y1689051I1J303D01*
G01Y1691082D01*
G02X607159Y1691692I2002J610D01*
G02X607881Y1693274I2094J0D01*
G01X608200Y1693924D01*
G03Y1694186I-267J131D01*
G01X607882Y1694835D01*
G02X607159Y1696417I1369J1582D01*
G02X607250Y1697027I2093J0D01*
G01Y1699057D01*
G02X607552Y1699360I302J1D01*
G37*
G36*
G01X1237080D02*
X1240780D01*
G02X1241082Y1699057I-1J-303D01*
G01Y1689051D01*
G02X1240780Y1688748I-302J-1D01*
G01X1237080D01*
G02X1236778Y1689051I1J303D01*
G01Y1691455D01*
G02X1236764Y1691692I2002J237D01*
G02X1236778Y1691929I2016J0D01*
G01Y1696180D01*
G02X1236764Y1696417I2002J237D01*
G02X1236778Y1696654I2016J0D01*
G01Y1699057D01*
G02X1237080Y1699360I302J1D01*
G37*
G36*
G01X1252828D02*
X1256528D01*
G02X1256830Y1699057I-1J-303D01*
G01Y1689051D01*
G02X1256528Y1688748I-302J-1D01*
G01X1252828D01*
G02X1252526Y1689051I1J303D01*
G01Y1691455D01*
G02X1252512Y1691692I2002J237D01*
G02X1252526Y1691929I2016J0D01*
G01Y1696180D01*
G02X1252512Y1696417I2002J237D01*
G02X1252526Y1696654I2016J0D01*
G01Y1699057D01*
G02X1252828Y1699360I302J1D01*
G37*
G36*
G01X1268576D02*
X1272276D01*
G02X1272578Y1699057I-1J-303D01*
G01Y1689051D01*
G02X1272276Y1688748I-302J-1D01*
G01X1268576D01*
G02X1268274Y1689051I1J303D01*
G01Y1691455D01*
G02X1268260Y1691692I2002J237D01*
G02X1268274Y1691929I2016J0D01*
G01Y1696180D01*
G02X1268260Y1696417I2002J237D01*
G02X1268274Y1696654I2016J0D01*
G01Y1699057D01*
G02X1268576Y1699360I302J1D01*
G37*
G36*
G01X1284324D02*
X1288024D01*
G02X1288326Y1699057I-1J-303D01*
G01Y1689051D01*
G02X1288024Y1688748I-302J-1D01*
G01X1284324D01*
G02X1284022Y1689051I1J303D01*
G01Y1691455D01*
G02X1284008Y1691692I2002J237D01*
G02X1284022Y1691929I2016J0D01*
G01Y1696180D01*
G02X1284008Y1696417I2002J237D01*
G02X1284022Y1696654I2016J0D01*
G01Y1699057D01*
G02X1284324Y1699360I302J1D01*
G37*
G36*
G01X1304009D02*
X1307709D01*
G02X1308012Y1699057I0J-303D01*
G01Y1689051D01*
G02X1307709Y1688748I-303J0D01*
G01X1304009D01*
G02X1303706Y1689051I0J303D01*
G01Y1691463D01*
G02X1303693Y1691692I2003J229D01*
G02X1303706Y1691921I2016J0D01*
G01Y1696188D01*
G02X1303693Y1696417I2003J229D01*
G02X1303706Y1696646I2016J0D01*
G01Y1699057D01*
G02X1304009Y1699360I303J0D01*
G37*
G36*
G01X1319757D02*
X1323457D01*
G02X1323760Y1699057I0J-303D01*
G01Y1689051D01*
G02X1323457Y1688748I-303J0D01*
G01X1319757D01*
G02X1319454Y1689051I0J303D01*
G01Y1691463D01*
G02X1319441Y1691692I2003J229D01*
G02X1319454Y1691921I2016J0D01*
G01Y1696188D01*
G02X1319441Y1696417I2003J229D01*
G02X1319454Y1696646I2016J0D01*
G01Y1699057D01*
G02X1319757Y1699360I303J0D01*
G37*
G36*
G01X1335505D02*
X1339205D01*
G02X1339508Y1699057I0J-303D01*
G01Y1689051D01*
G02X1339205Y1688748I-303J0D01*
G01X1335505D01*
G02X1335202Y1689051I0J303D01*
G01Y1691463D01*
G02X1335189Y1691692I2003J229D01*
G02X1335202Y1691921I2016J0D01*
G01Y1696188D01*
G02X1335189Y1696417I2003J229D01*
G02X1335202Y1696646I2016J0D01*
G01Y1699057D01*
G02X1335505Y1699360I303J0D01*
G37*
G36*
G01X1351253D02*
X1354953D01*
G02X1355256Y1699057I0J-303D01*
G01Y1689051D01*
G02X1354953Y1688748I-303J0D01*
G01X1351253D01*
G02X1350950Y1689051I0J303D01*
G01Y1691463D01*
G02X1350937Y1691692I2003J229D01*
G02X1350950Y1691921I2016J0D01*
G01Y1696188D01*
G02X1350937Y1696417I2003J229D01*
G02X1350950Y1696646I2016J0D01*
G01Y1699057D01*
G02X1351253Y1699360I303J0D01*
G37*
G36*
G01X1501253D02*
X1504953D01*
G02X1505256Y1699057I0J-303D01*
G01Y1689051D01*
G02X1504953Y1688748I-303J0D01*
G01X1501253D01*
G02X1500950Y1689051I0J303D01*
G01Y1691085D01*
G02X1500860Y1691692I2002J607D01*
G02X1501582Y1693274I2094J0D01*
G01X1501901Y1693924D01*
G03Y1694186I-267J131D01*
G01X1501583Y1694835D01*
G02X1500860Y1696417I1369J1582D01*
G02X1500950Y1697024I2092J0D01*
G01Y1699057D01*
G02X1501253Y1699360I303J0D01*
G37*
G36*
G01X1517001D02*
X1520701D01*
G02X1521004Y1699057I0J-303D01*
G01Y1689051D01*
G02X1520701Y1688748I-303J0D01*
G01X1517001D01*
G02X1516698Y1689051I0J303D01*
G01Y1691085D01*
G02X1516608Y1691692I2002J607D01*
G02X1517330Y1693274I2094J0D01*
G01X1517649Y1693924D01*
G03Y1694186I-267J131D01*
G01X1517331Y1694835D01*
G02X1516608Y1696417I1369J1582D01*
G02X1516698Y1697024I2092J0D01*
G01Y1699057D01*
G02X1517001Y1699360I303J0D01*
G37*
G36*
G01X1532749D02*
X1536449D01*
G02X1536752Y1699057I0J-303D01*
G01Y1689051D01*
G02X1536449Y1688748I-303J0D01*
G01X1532749D01*
G02X1532446Y1689051I0J303D01*
G01Y1691085D01*
G02X1532356Y1691692I2002J607D01*
G02X1533078Y1693274I2094J0D01*
G01X1533397Y1693924D01*
G03Y1694186I-267J131D01*
G01X1533079Y1694835D01*
G02X1532356Y1696417I1369J1582D01*
G02X1532446Y1697024I2092J0D01*
G01Y1699057D01*
G02X1532749Y1699360I303J0D01*
G37*
G36*
G01X1548497D02*
X1552197D01*
G02X1552500Y1699057I0J-303D01*
G01Y1689051D01*
G02X1552197Y1688748I-303J0D01*
G01X1548497D01*
G02X1548194Y1689051I0J303D01*
G01Y1691085D01*
G02X1548104Y1691692I2002J607D01*
G02X1548826Y1693274I2094J0D01*
G01X1549145Y1693924D01*
G03Y1694186I-267J131D01*
G01X1548827Y1694835D01*
G02X1548104Y1696417I1369J1582D01*
G02X1548194Y1697024I2092J0D01*
G01Y1699057D01*
G02X1548497Y1699360I303J0D01*
G37*
G36*
G01X1568182D02*
X1571882D01*
G02X1572184Y1699057I-1J-303D01*
G01Y1689051D01*
G02X1571882Y1688748I-302J-1D01*
G01X1568182D01*
G02X1567880Y1689051I1J303D01*
G01Y1691082D01*
G02X1567789Y1691692I2002J610D01*
G02X1568511Y1693274I2094J0D01*
G01X1568830Y1693924D01*
G03Y1694186I-267J131D01*
G01X1568512Y1694835D01*
G02X1567789Y1696417I1369J1582D01*
G02X1567880Y1697027I2093J0D01*
G01Y1699057D01*
G02X1568182Y1699360I302J1D01*
G37*
G36*
G01X1583930D02*
X1587630D01*
G02X1587932Y1699057I-1J-303D01*
G01Y1689051D01*
G02X1587630Y1688748I-302J-1D01*
G01X1583930D01*
G02X1583628Y1689051I1J303D01*
G01Y1691082D01*
G02X1583537Y1691692I2002J610D01*
G02X1584259Y1693274I2094J0D01*
G01X1584578Y1693924D01*
G03Y1694186I-267J131D01*
G01X1584260Y1694835D01*
G02X1583537Y1696417I1369J1582D01*
G02X1583628Y1697027I2093J0D01*
G01Y1699057D01*
G02X1583930Y1699360I302J1D01*
G37*
G36*
G01X1599678D02*
X1603378D01*
G02X1603680Y1699057I-1J-303D01*
G01Y1689051D01*
G02X1603378Y1688748I-302J-1D01*
G01X1599678D01*
G02X1599376Y1689051I1J303D01*
G01Y1691082D01*
G02X1599285Y1691692I2002J610D01*
G02X1600007Y1693274I2094J0D01*
G01X1600326Y1693924D01*
G03Y1694186I-267J131D01*
G01X1600008Y1694835D01*
G02X1599285Y1696417I1369J1582D01*
G02X1599376Y1697027I2093J0D01*
G01Y1699057D01*
G02X1599678Y1699360I302J1D01*
G37*
G36*
G01X1615426D02*
X1619126D01*
G02X1619428Y1699057I-1J-303D01*
G01Y1689051D01*
G02X1619126Y1688748I-302J-1D01*
G01X1615426D01*
G02X1615124Y1689051I1J303D01*
G01Y1691082D01*
G02X1615033Y1691692I2002J610D01*
G02X1615755Y1693274I2094J0D01*
G01X1616074Y1693924D01*
G03Y1694186I-267J131D01*
G01X1615756Y1694835D01*
G02X1615033Y1696417I1369J1582D01*
G02X1615124Y1697027I2093J0D01*
G01Y1699057D01*
G02X1615426Y1699360I302J1D01*
G37*
G36*
G01X237080Y1703296D02*
X240780D01*
G02X241082Y1702994I0J-302D01*
G01Y1692988D01*
G02X240780Y1692686I-302J0D01*
G01X237080D01*
G02X236778Y1692988I0J302D01*
G01Y1695392D01*
G02X236764Y1695629I2002J237D01*
G02X236778Y1695866I2016J0D01*
G01Y1700117D01*
G02X236764Y1700354I2002J237D01*
G02X236778Y1700591I2016J0D01*
G01Y1702994D01*
G02X237080Y1703296I302J0D01*
G37*
G36*
G01X252828D02*
X256528D01*
G02X256830Y1702994I0J-302D01*
G01Y1692988D01*
G02X256528Y1692686I-302J0D01*
G01X252828D01*
G02X252526Y1692988I0J302D01*
G01Y1695392D01*
G02X252512Y1695629I2002J237D01*
G02X252526Y1695866I2016J0D01*
G01Y1700117D01*
G02X252512Y1700354I2002J237D01*
G02X252526Y1700591I2016J0D01*
G01Y1702994D01*
G02X252828Y1703296I302J0D01*
G37*
G36*
G01X268576D02*
X272276D01*
G02X272578Y1702994I0J-302D01*
G01Y1692988D01*
G02X272276Y1692686I-302J0D01*
G01X268576D01*
G02X268274Y1692988I0J302D01*
G01Y1695392D01*
G02X268260Y1695629I2002J237D01*
G02X268274Y1695866I2016J0D01*
G01Y1700117D01*
G02X268260Y1700354I2002J237D01*
G02X268274Y1700591I2016J0D01*
G01Y1702994D01*
G02X268576Y1703296I302J0D01*
G37*
G36*
G01X284324D02*
X288024D01*
G02X288326Y1702994I0J-302D01*
G01Y1692988D01*
G02X288024Y1692686I-302J0D01*
G01X284324D01*
G02X284022Y1692988I0J302D01*
G01Y1695392D01*
G02X284008Y1695629I2002J237D01*
G02X284022Y1695866I2016J0D01*
G01Y1700117D01*
G02X284008Y1700354I2002J237D01*
G02X284022Y1700591I2016J0D01*
G01Y1702994D01*
G02X284324Y1703296I302J0D01*
G37*
G36*
G01X568182D02*
X571882D01*
G02X572184Y1702994I0J-302D01*
G01Y1692988D01*
G02X571882Y1692686I-302J0D01*
G01X568182D01*
G02X567880Y1692988I0J302D01*
G01Y1695019D01*
G02X567789Y1695629I2002J610D01*
G02X568511Y1697211I2094J0D01*
G01X568830Y1697861D01*
G03Y1698123I-267J131D01*
G01X568512Y1698772D01*
G02X567789Y1700354I1369J1582D01*
G02X567880Y1700964I2093J0D01*
G01Y1702994D01*
G02X568182Y1703296I302J0D01*
G37*
G36*
G01X583930D02*
X587630D01*
G02X587932Y1702994I0J-302D01*
G01Y1692988D01*
G02X587630Y1692686I-302J0D01*
G01X583930D01*
G02X583628Y1692988I0J302D01*
G01Y1695019D01*
G02X583537Y1695629I2002J610D01*
G02X584259Y1697211I2094J0D01*
G01X584578Y1697861D01*
G03Y1698123I-267J131D01*
G01X584260Y1698772D01*
G02X583537Y1700354I1369J1582D01*
G02X583628Y1700964I2093J0D01*
G01Y1702994D01*
G02X583930Y1703296I302J0D01*
G37*
G36*
G01X599678D02*
X603378D01*
G02X603680Y1702994I0J-302D01*
G01Y1692988D01*
G02X603378Y1692686I-302J0D01*
G01X599678D01*
G02X599376Y1692988I0J302D01*
G01Y1695019D01*
G02X599285Y1695629I2002J610D01*
G02X600007Y1697211I2094J0D01*
G01X600326Y1697861D01*
G03Y1698123I-267J131D01*
G01X600008Y1698772D01*
G02X599285Y1700354I1369J1582D01*
G02X599376Y1700964I2093J0D01*
G01Y1702994D01*
G02X599678Y1703296I302J0D01*
G37*
G36*
G01X615426D02*
X619126D01*
G02X619428Y1702994I0J-302D01*
G01Y1692988D01*
G02X619126Y1692686I-302J0D01*
G01X615426D01*
G02X615124Y1692988I0J302D01*
G01Y1695019D01*
G02X615033Y1695629I2002J610D01*
G02X615755Y1697211I2094J0D01*
G01X616074Y1697861D01*
G03Y1698123I-267J131D01*
G01X615756Y1698772D01*
G02X615033Y1700354I1369J1582D01*
G02X615124Y1700964I2093J0D01*
G01Y1702994D01*
G02X615426Y1703296I302J0D01*
G37*
G36*
G01X1244954D02*
X1248654D01*
G02X1248956Y1702994I0J-302D01*
G01Y1692988D01*
G02X1248654Y1692686I-302J0D01*
G01X1244954D01*
G02X1244652Y1692988I0J302D01*
G01Y1695392D01*
G02X1244638Y1695629I2002J237D01*
G02X1244652Y1695866I2016J0D01*
G01Y1700117D01*
G02X1244638Y1700354I2002J237D01*
G02X1244652Y1700591I2016J0D01*
G01Y1702994D01*
G02X1244954Y1703296I302J0D01*
G37*
G36*
G01X1260702D02*
X1264402D01*
G02X1264704Y1702994I0J-302D01*
G01Y1692988D01*
G02X1264402Y1692686I-302J0D01*
G01X1260702D01*
G02X1260400Y1692988I0J302D01*
G01Y1695392D01*
G02X1260386Y1695629I2002J237D01*
G02X1260400Y1695866I2016J0D01*
G01Y1700117D01*
G02X1260386Y1700354I2002J237D01*
G02X1260400Y1700591I2016J0D01*
G01Y1702994D01*
G02X1260702Y1703296I302J0D01*
G37*
G36*
G01X1276450D02*
X1280150D01*
G02X1280452Y1702994I0J-302D01*
G01Y1692988D01*
G02X1280150Y1692686I-302J0D01*
G01X1276450D01*
G02X1276148Y1692988I0J302D01*
G01Y1695392D01*
G02X1276134Y1695629I2002J237D01*
G02X1276148Y1695866I2016J0D01*
G01Y1700117D01*
G02X1276134Y1700354I2002J237D01*
G02X1276148Y1700591I2016J0D01*
G01Y1702994D01*
G02X1276450Y1703296I302J0D01*
G37*
G36*
G01X1292198D02*
X1295898D01*
G02X1296200Y1702994I0J-302D01*
G01Y1692988D01*
G02X1295898Y1692686I-302J0D01*
G01X1292198D01*
G02X1291896Y1692988I0J302D01*
G01Y1695392D01*
G02X1291882Y1695629I2002J237D01*
G02X1291896Y1695866I2016J0D01*
G01Y1700117D01*
G02X1291882Y1700354I2002J237D01*
G02X1291896Y1700591I2016J0D01*
G01Y1702994D01*
G02X1292198Y1703296I302J0D01*
G37*
G36*
G01X1576056D02*
X1579756D01*
G02X1580058Y1702994I0J-302D01*
G01Y1692988D01*
G02X1579756Y1692686I-302J0D01*
G01X1576056D01*
G02X1575754Y1692988I0J302D01*
G01Y1695019D01*
G02X1575663Y1695629I2002J610D01*
G02X1576385Y1697211I2094J0D01*
G01X1576704Y1697861D01*
G03Y1698123I-267J131D01*
G01X1576386Y1698772D01*
G02X1575663Y1700354I1369J1582D01*
G02X1575754Y1700964I2093J0D01*
G01Y1702994D01*
G02X1576056Y1703296I302J0D01*
G37*
G36*
G01X1591804D02*
X1595504D01*
G02X1595806Y1702994I0J-302D01*
G01Y1692988D01*
G02X1595504Y1692686I-302J0D01*
G01X1591804D01*
G02X1591502Y1692988I0J302D01*
G01Y1695019D01*
G02X1591411Y1695629I2002J610D01*
G02X1592133Y1697211I2094J0D01*
G01X1592452Y1697861D01*
G03Y1698123I-267J131D01*
G01X1592134Y1698772D01*
G02X1591411Y1700354I1369J1582D01*
G02X1591502Y1700964I2093J0D01*
G01Y1702994D01*
G02X1591804Y1703296I302J0D01*
G37*
G36*
G01X1607552D02*
X1611252D01*
G02X1611554Y1702994I0J-302D01*
G01Y1692988D01*
G02X1611252Y1692686I-302J0D01*
G01X1607552D01*
G02X1607250Y1692988I0J302D01*
G01Y1695019D01*
G02X1607159Y1695629I2002J610D01*
G02X1607881Y1697211I2094J0D01*
G01X1608200Y1697861D01*
G03Y1698123I-267J131D01*
G01X1607882Y1698772D01*
G02X1607159Y1700354I1369J1582D01*
G02X1607250Y1700964I2093J0D01*
G01Y1702994D01*
G02X1607552Y1703296I302J0D01*
G37*
G36*
G01X1623300D02*
X1627000D01*
G02X1627302Y1702994I0J-302D01*
G01Y1692988D01*
G02X1627000Y1692686I-302J0D01*
G01X1623300D01*
G02X1622998Y1692988I0J302D01*
G01Y1695019D01*
G02X1622907Y1695629I2002J610D01*
G02X1623629Y1697211I2094J0D01*
G01X1623948Y1697861D01*
G03Y1698123I-267J131D01*
G01X1623630Y1698772D01*
G02X1622907Y1700354I1369J1582D01*
G02X1622998Y1700964I2093J0D01*
G01Y1702994D01*
G02X1623300Y1703296I302J0D01*
G37*
G36*
G01X304009D02*
X307709D01*
G02X308012Y1702994I1J-302D01*
G01Y1692988D01*
G02X307709Y1692686I-303J1D01*
G01X304009D01*
G02X303706Y1692988I-1J302D01*
G01Y1695400D01*
G02X303693Y1695629I2003J229D01*
G02X303706Y1695858I2016J0D01*
G01Y1700125D01*
G02X303693Y1700354I2003J229D01*
G02X303706Y1700583I2016J0D01*
G01Y1702994D01*
G02X304009Y1703296I303J-1D01*
G37*
G36*
G01X319757D02*
X323457D01*
G02X323760Y1702994I1J-302D01*
G01Y1692988D01*
G02X323457Y1692686I-303J1D01*
G01X319757D01*
G02X319454Y1692988I-1J302D01*
G01Y1695400D01*
G02X319441Y1695629I2003J229D01*
G02X319454Y1695858I2016J0D01*
G01Y1700125D01*
G02X319441Y1700354I2003J229D01*
G02X319454Y1700583I2016J0D01*
G01Y1702994D01*
G02X319757Y1703296I303J-1D01*
G37*
G36*
G01X335505D02*
X339205D01*
G02X339508Y1702994I1J-302D01*
G01Y1692988D01*
G02X339205Y1692686I-303J1D01*
G01X335505D01*
G02X335202Y1692988I-1J302D01*
G01Y1695400D01*
G02X335189Y1695629I2003J229D01*
G02X335202Y1695858I2016J0D01*
G01Y1700125D01*
G02X335189Y1700354I2003J229D01*
G02X335202Y1700583I2016J0D01*
G01Y1702994D01*
G02X335505Y1703296I303J-1D01*
G37*
G36*
G01X351253D02*
X354953D01*
G02X355256Y1702994I1J-302D01*
G01Y1692988D01*
G02X354953Y1692686I-303J1D01*
G01X351253D01*
G02X350950Y1692988I-1J302D01*
G01Y1695400D01*
G02X350937Y1695629I2003J229D01*
G02X350950Y1695858I2016J0D01*
G01Y1700125D01*
G02X350937Y1700354I2003J229D01*
G02X350950Y1700583I2016J0D01*
G01Y1702994D01*
G02X351253Y1703296I303J-1D01*
G37*
G36*
G01X501253D02*
X504953D01*
G02X505256Y1702994I1J-302D01*
G01Y1692988D01*
G02X504953Y1692686I-303J1D01*
G01X501253D01*
G02X500950Y1692988I-1J302D01*
G01Y1695022D01*
G02X500860Y1695629I2002J607D01*
G02X501582Y1697211I2094J0D01*
G01X501901Y1697861D01*
G03Y1698123I-267J131D01*
G01X501583Y1698772D01*
G02X500860Y1700354I1369J1582D01*
G02X500950Y1700961I2092J0D01*
G01Y1702994D01*
G02X501253Y1703296I303J-1D01*
G37*
G36*
G01X517001D02*
X520701D01*
G02X521004Y1702994I1J-302D01*
G01Y1692988D01*
G02X520701Y1692686I-303J1D01*
G01X517001D01*
G02X516698Y1692988I-1J302D01*
G01Y1695022D01*
G02X516608Y1695629I2002J607D01*
G02X517330Y1697211I2094J0D01*
G01X517649Y1697861D01*
G03Y1698123I-267J131D01*
G01X517331Y1698772D01*
G02X516608Y1700354I1369J1582D01*
G02X516698Y1700961I2092J0D01*
G01Y1702994D01*
G02X517001Y1703296I303J-1D01*
G37*
G36*
G01X532749D02*
X536449D01*
G02X536752Y1702994I1J-302D01*
G01Y1692988D01*
G02X536449Y1692686I-303J1D01*
G01X532749D01*
G02X532446Y1692988I-1J302D01*
G01Y1695022D01*
G02X532356Y1695629I2002J607D01*
G02X533078Y1697211I2094J0D01*
G01X533397Y1697861D01*
G03Y1698123I-267J131D01*
G01X533079Y1698772D01*
G02X532356Y1700354I1369J1582D01*
G02X532446Y1700961I2092J0D01*
G01Y1702994D01*
G02X532749Y1703296I303J-1D01*
G37*
G36*
G01X548497D02*
X552197D01*
G02X552500Y1702994I1J-302D01*
G01Y1692988D01*
G02X552197Y1692686I-303J1D01*
G01X548497D01*
G02X548194Y1692988I-1J302D01*
G01Y1695022D01*
G02X548104Y1695629I2002J607D01*
G02X548826Y1697211I2094J0D01*
G01X549145Y1697861D01*
G03Y1698123I-267J131D01*
G01X548827Y1698772D01*
G02X548104Y1700354I1369J1582D01*
G02X548194Y1700961I2092J0D01*
G01Y1702994D01*
G02X548497Y1703296I303J-1D01*
G37*
G36*
G01X1311883D02*
X1315583D01*
G02X1315886Y1702994I1J-302D01*
G01Y1692988D01*
G02X1315583Y1692686I-303J1D01*
G01X1311883D01*
G02X1311580Y1692988I-1J302D01*
G01Y1695400D01*
G02X1311567Y1695629I2003J229D01*
G02X1311580Y1695858I2016J0D01*
G01Y1700125D01*
G02X1311567Y1700354I2003J229D01*
G02X1311580Y1700583I2016J0D01*
G01Y1702994D01*
G02X1311883Y1703296I303J-1D01*
G37*
G36*
G01X1327631D02*
X1331331D01*
G02X1331634Y1702994I1J-302D01*
G01Y1692988D01*
G02X1331331Y1692686I-303J1D01*
G01X1327631D01*
G02X1327328Y1692988I-1J302D01*
G01Y1695400D01*
G02X1327315Y1695629I2003J229D01*
G02X1327328Y1695858I2016J0D01*
G01Y1700125D01*
G02X1327315Y1700354I2003J229D01*
G02X1327328Y1700583I2016J0D01*
G01Y1702994D01*
G02X1327631Y1703296I303J-1D01*
G37*
G36*
G01X1343379D02*
X1347079D01*
G02X1347382Y1702994I1J-302D01*
G01Y1692988D01*
G02X1347079Y1692686I-303J1D01*
G01X1343379D01*
G02X1343076Y1692988I-1J302D01*
G01Y1695400D01*
G02X1343063Y1695629I2003J229D01*
G02X1343076Y1695858I2016J0D01*
G01Y1700125D01*
G02X1343063Y1700354I2003J229D01*
G02X1343076Y1700583I2016J0D01*
G01Y1702994D01*
G02X1343379Y1703296I303J-1D01*
G37*
G36*
G01X1359127D02*
X1362827D01*
G02X1363130Y1702994I1J-302D01*
G01Y1692988D01*
G02X1362827Y1692686I-303J1D01*
G01X1359127D01*
G02X1358824Y1692988I-1J302D01*
G01Y1695400D01*
G02X1358811Y1695629I2003J229D01*
G02X1358824Y1695858I2016J0D01*
G01Y1700125D01*
G02X1358811Y1700354I2003J229D01*
G02X1358824Y1700583I2016J0D01*
G01Y1702994D01*
G02X1359127Y1703296I303J-1D01*
G37*
G36*
G01X1509127D02*
X1512827D01*
G02X1513130Y1702994I1J-302D01*
G01Y1692988D01*
G02X1512827Y1692686I-303J1D01*
G01X1509127D01*
G02X1508824Y1692988I-1J302D01*
G01Y1695022D01*
G02X1508734Y1695629I2002J607D01*
G02X1509456Y1697211I2094J0D01*
G01X1509775Y1697861D01*
G03Y1698123I-267J131D01*
G01X1509457Y1698772D01*
G02X1508734Y1700354I1369J1582D01*
G02X1508824Y1700961I2092J0D01*
G01Y1702994D01*
G02X1509127Y1703296I303J-1D01*
G37*
G36*
G01X1524875D02*
X1528575D01*
G02X1528878Y1702994I1J-302D01*
G01Y1692988D01*
G02X1528575Y1692686I-303J1D01*
G01X1524875D01*
G02X1524572Y1692988I-1J302D01*
G01Y1695022D01*
G02X1524482Y1695629I2002J607D01*
G02X1525204Y1697211I2094J0D01*
G01X1525523Y1697861D01*
G03Y1698123I-267J131D01*
G01X1525205Y1698772D01*
G02X1524482Y1700354I1369J1582D01*
G02X1524572Y1700961I2092J0D01*
G01Y1702994D01*
G02X1524875Y1703296I303J-1D01*
G37*
G36*
G01X1540623D02*
X1544323D01*
G02X1544626Y1702994I1J-302D01*
G01Y1692988D01*
G02X1544323Y1692686I-303J1D01*
G01X1540623D01*
G02X1540320Y1692988I-1J302D01*
G01Y1695022D01*
G02X1540230Y1695629I2002J607D01*
G02X1540952Y1697211I2094J0D01*
G01X1541271Y1697861D01*
G03Y1698123I-267J131D01*
G01X1540953Y1698772D01*
G02X1540230Y1700354I1369J1582D01*
G02X1540320Y1700961I2092J0D01*
G01Y1702994D01*
G02X1540623Y1703296I303J-1D01*
G37*
G36*
G01X1556371D02*
X1560071D01*
G02X1560374Y1702994I1J-302D01*
G01Y1692988D01*
G02X1560071Y1692686I-303J1D01*
G01X1556371D01*
G02X1556068Y1692988I-1J302D01*
G01Y1695022D01*
G02X1555978Y1695629I2002J607D01*
G02X1556700Y1697211I2094J0D01*
G01X1557019Y1697861D01*
G03Y1698123I-267J131D01*
G01X1556701Y1698772D01*
G02X1555978Y1700354I1369J1582D01*
G02X1556068Y1700961I2092J0D01*
G01Y1702994D01*
G02X1556371Y1703296I303J-1D01*
G37*
G36*
G01X229206Y1713532D02*
X232906D01*
G02X233208Y1713230I0J-302D01*
G01Y1703224D01*
G02X232906Y1702922I-302J0D01*
G01X229206D01*
G02X228904Y1703224I0J302D01*
G01Y1705256D01*
G02X228813Y1705866I2002J610D01*
G02X229536Y1707448I2092J0D01*
G01X229854Y1708097D01*
G03Y1708359I-267J131D01*
G01X229536Y1709008D01*
G02X228813Y1710590I1369J1582D01*
G02X228904Y1711200I2093J0D01*
G01Y1713230D01*
G02X229206Y1713532I302J0D01*
G37*
G36*
G01X244954D02*
X248654D01*
G02X248956Y1713230I0J-302D01*
G01Y1703224D01*
G02X248654Y1702922I-302J0D01*
G01X244954D01*
G02X244652Y1703224I0J302D01*
G01Y1705256D01*
G02X244561Y1705866I2002J610D01*
G02X245284Y1707448I2092J0D01*
G01X245602Y1708097D01*
G03Y1708359I-267J131D01*
G01X245284Y1709008D01*
G02X244561Y1710590I1369J1582D01*
G02X244652Y1711200I2093J0D01*
G01Y1713230D01*
G02X244954Y1713532I302J0D01*
G37*
G36*
G01X260702D02*
X264402D01*
G02X264704Y1713230I0J-302D01*
G01Y1703224D01*
G02X264402Y1702922I-302J0D01*
G01X260702D01*
G02X260400Y1703224I0J302D01*
G01Y1705256D01*
G02X260309Y1705866I2002J610D01*
G02X261032Y1707448I2092J0D01*
G01X261350Y1708097D01*
G03Y1708359I-267J131D01*
G01X261032Y1709008D01*
G02X260309Y1710590I1369J1582D01*
G02X260400Y1711200I2093J0D01*
G01Y1713230D01*
G02X260702Y1713532I302J0D01*
G37*
G36*
G01X276450D02*
X280150D01*
G02X280452Y1713230I0J-302D01*
G01Y1703224D01*
G02X280150Y1702922I-302J0D01*
G01X276450D01*
G02X276148Y1703224I0J302D01*
G01Y1705256D01*
G02X276057Y1705866I2002J610D01*
G02X276780Y1707448I2092J0D01*
G01X277098Y1708097D01*
G03Y1708359I-267J131D01*
G01X276780Y1709008D01*
G02X276057Y1710590I1369J1582D01*
G02X276148Y1711200I2093J0D01*
G01Y1713230D01*
G02X276450Y1713532I302J0D01*
G37*
G36*
G01X560308D02*
X564008D01*
G02X564310Y1713230I0J-302D01*
G01Y1703224D01*
G02X564008Y1702922I-302J0D01*
G01X560308D01*
G02X560006Y1703224I0J302D01*
G01Y1705629D01*
G02X559992Y1705866I2002J237D01*
G02X560006Y1706103I2016J0D01*
G01Y1710353D01*
G02X559992Y1710590I2002J237D01*
G02X560006Y1710827I2016J0D01*
G01Y1713230D01*
G02X560308Y1713532I302J0D01*
G37*
G36*
G01X576056D02*
X579756D01*
G02X580058Y1713230I0J-302D01*
G01Y1703224D01*
G02X579756Y1702922I-302J0D01*
G01X576056D01*
G02X575754Y1703224I0J302D01*
G01Y1705629D01*
G02X575740Y1705866I2002J237D01*
G02X575754Y1706103I2016J0D01*
G01Y1710353D01*
G02X575740Y1710590I2002J237D01*
G02X575754Y1710827I2016J0D01*
G01Y1713230D01*
G02X576056Y1713532I302J0D01*
G37*
G36*
G01X591804D02*
X595504D01*
G02X595806Y1713230I0J-302D01*
G01Y1703224D01*
G02X595504Y1702922I-302J0D01*
G01X591804D01*
G02X591502Y1703224I0J302D01*
G01Y1705629D01*
G02X591488Y1705866I2002J237D01*
G02X591502Y1706103I2016J0D01*
G01Y1710353D01*
G02X591488Y1710590I2002J237D01*
G02X591502Y1710827I2016J0D01*
G01Y1713230D01*
G02X591804Y1713532I302J0D01*
G37*
G36*
G01X607552D02*
X611252D01*
G02X611554Y1713230I0J-302D01*
G01Y1703224D01*
G02X611252Y1702922I-302J0D01*
G01X607552D01*
G02X607250Y1703224I0J302D01*
G01Y1705629D01*
G02X607236Y1705866I2002J237D01*
G02X607250Y1706103I2016J0D01*
G01Y1710353D01*
G02X607236Y1710590I2002J237D01*
G02X607250Y1710827I2016J0D01*
G01Y1713230D01*
G02X607552Y1713532I302J0D01*
G37*
G36*
G01X1237080D02*
X1240780D01*
G02X1241082Y1713230I0J-302D01*
G01Y1703224D01*
G02X1240780Y1702922I-302J0D01*
G01X1237080D01*
G02X1236778Y1703224I0J302D01*
G01Y1705256D01*
G02X1236687Y1705866I2002J610D01*
G02X1237410Y1707448I2092J0D01*
G01X1237728Y1708097D01*
G03Y1708359I-267J131D01*
G01X1237410Y1709008D01*
G02X1236687Y1710590I1369J1582D01*
G02X1236778Y1711200I2093J0D01*
G01Y1713230D01*
G02X1237080Y1713532I302J0D01*
G37*
G36*
G01X1252828D02*
X1256528D01*
G02X1256830Y1713230I0J-302D01*
G01Y1703224D01*
G02X1256528Y1702922I-302J0D01*
G01X1252828D01*
G02X1252526Y1703224I0J302D01*
G01Y1705256D01*
G02X1252435Y1705866I2002J610D01*
G02X1253158Y1707448I2092J0D01*
G01X1253476Y1708097D01*
G03Y1708359I-267J131D01*
G01X1253158Y1709008D01*
G02X1252435Y1710590I1369J1582D01*
G02X1252526Y1711200I2093J0D01*
G01Y1713230D01*
G02X1252828Y1713532I302J0D01*
G37*
G36*
G01X1268576D02*
X1272276D01*
G02X1272578Y1713230I0J-302D01*
G01Y1703224D01*
G02X1272276Y1702922I-302J0D01*
G01X1268576D01*
G02X1268274Y1703224I0J302D01*
G01Y1705256D01*
G02X1268183Y1705866I2002J610D01*
G02X1268906Y1707448I2092J0D01*
G01X1269224Y1708097D01*
G03Y1708359I-267J131D01*
G01X1268906Y1709008D01*
G02X1268183Y1710590I1369J1582D01*
G02X1268274Y1711200I2093J0D01*
G01Y1713230D01*
G02X1268576Y1713532I302J0D01*
G37*
G36*
G01X1284324D02*
X1288024D01*
G02X1288326Y1713230I0J-302D01*
G01Y1703224D01*
G02X1288024Y1702922I-302J0D01*
G01X1284324D01*
G02X1284022Y1703224I0J302D01*
G01Y1705256D01*
G02X1283931Y1705866I2002J610D01*
G02X1284654Y1707448I2092J0D01*
G01X1284972Y1708097D01*
G03Y1708359I-267J131D01*
G01X1284654Y1709008D01*
G02X1283931Y1710590I1369J1582D01*
G02X1284022Y1711200I2093J0D01*
G01Y1713230D01*
G02X1284324Y1713532I302J0D01*
G37*
G36*
G01X1568182D02*
X1571882D01*
G02X1572184Y1713230I0J-302D01*
G01Y1703224D01*
G02X1571882Y1702922I-302J0D01*
G01X1568182D01*
G02X1567880Y1703224I0J302D01*
G01Y1705629D01*
G02X1567866Y1705866I2002J237D01*
G02X1567880Y1706103I2016J0D01*
G01Y1710353D01*
G02X1567866Y1710590I2002J237D01*
G02X1567880Y1710827I2016J0D01*
G01Y1713230D01*
G02X1568182Y1713532I302J0D01*
G37*
G36*
G01X1583930D02*
X1587630D01*
G02X1587932Y1713230I0J-302D01*
G01Y1703224D01*
G02X1587630Y1702922I-302J0D01*
G01X1583930D01*
G02X1583628Y1703224I0J302D01*
G01Y1705629D01*
G02X1583614Y1705866I2002J237D01*
G02X1583628Y1706103I2016J0D01*
G01Y1710353D01*
G02X1583614Y1710590I2002J237D01*
G02X1583628Y1710827I2016J0D01*
G01Y1713230D01*
G02X1583930Y1713532I302J0D01*
G37*
G36*
G01X1599678D02*
X1603378D01*
G02X1603680Y1713230I0J-302D01*
G01Y1703224D01*
G02X1603378Y1702922I-302J0D01*
G01X1599678D01*
G02X1599376Y1703224I0J302D01*
G01Y1705629D01*
G02X1599362Y1705866I2002J237D01*
G02X1599376Y1706103I2016J0D01*
G01Y1710353D01*
G02X1599362Y1710590I2002J237D01*
G02X1599376Y1710827I2016J0D01*
G01Y1713230D01*
G02X1599678Y1713532I302J0D01*
G37*
G36*
G01X1615426D02*
X1619126D01*
G02X1619428Y1713230I0J-302D01*
G01Y1703224D01*
G02X1619126Y1702922I-302J0D01*
G01X1615426D01*
G02X1615124Y1703224I0J302D01*
G01Y1705629D01*
G02X1615110Y1705866I2002J237D01*
G02X1615124Y1706103I2016J0D01*
G01Y1710353D01*
G02X1615110Y1710590I2002J237D01*
G02X1615124Y1710827I2016J0D01*
G01Y1713230D01*
G02X1615426Y1713532I302J0D01*
G37*
G36*
G01X296135D02*
X299835D01*
G02X300138Y1713230I1J-302D01*
G01Y1703224D01*
G02X299835Y1702922I-303J1D01*
G01X296135D01*
G02X295832Y1703224I-1J302D01*
G01Y1705259D01*
G02X295742Y1705866I2002J607D01*
G02X296465Y1707448I2092J0D01*
G01X296783Y1708097D01*
G03Y1708359I-267J131D01*
G01X296465Y1709008D01*
G02X295742Y1710590I1369J1582D01*
G02X295832Y1711197I2092J0D01*
G01Y1713230D01*
G02X296135Y1713532I303J-1D01*
G37*
G36*
G01X311883D02*
X315583D01*
G02X315886Y1713230I1J-302D01*
G01Y1703224D01*
G02X315583Y1702922I-303J1D01*
G01X311883D01*
G02X311580Y1703224I-1J302D01*
G01Y1705259D01*
G02X311490Y1705866I2002J607D01*
G02X312213Y1707448I2092J0D01*
G01X312531Y1708097D01*
G03Y1708359I-267J131D01*
G01X312213Y1709008D01*
G02X311490Y1710590I1369J1582D01*
G02X311580Y1711197I2092J0D01*
G01Y1713230D01*
G02X311883Y1713532I303J-1D01*
G37*
G36*
G01X327631D02*
X331331D01*
G02X331634Y1713230I1J-302D01*
G01Y1703224D01*
G02X331331Y1702922I-303J1D01*
G01X327631D01*
G02X327328Y1703224I-1J302D01*
G01Y1705259D01*
G02X327238Y1705866I2002J607D01*
G02X327961Y1707448I2092J0D01*
G01X328279Y1708097D01*
G03Y1708359I-267J131D01*
G01X327961Y1709008D01*
G02X327238Y1710590I1369J1582D01*
G02X327328Y1711197I2092J0D01*
G01Y1713230D01*
G02X327631Y1713532I303J-1D01*
G37*
G36*
G01X343379D02*
X347079D01*
G02X347382Y1713230I1J-302D01*
G01Y1703224D01*
G02X347079Y1702922I-303J1D01*
G01X343379D01*
G02X343076Y1703224I-1J302D01*
G01Y1705259D01*
G02X342986Y1705866I2002J607D01*
G02X343709Y1707448I2092J0D01*
G01X344027Y1708097D01*
G03Y1708359I-267J131D01*
G01X343709Y1709008D01*
G02X342986Y1710590I1369J1582D01*
G02X343076Y1711197I2092J0D01*
G01Y1713230D01*
G02X343379Y1713532I303J-1D01*
G37*
G36*
G01X493379D02*
X497079D01*
G02X497382Y1713230I1J-302D01*
G01Y1703224D01*
G02X497079Y1702922I-303J1D01*
G01X493379D01*
G02X493076Y1703224I-1J302D01*
G01Y1705637D01*
G02X493063Y1705866I2003J229D01*
G02X493076Y1706095I2016J0D01*
G01Y1710361D01*
G02X493063Y1710590I2003J229D01*
G02X493076Y1710819I2016J0D01*
G01Y1713230D01*
G02X493379Y1713532I303J-1D01*
G37*
G36*
G01X509127D02*
X512827D01*
G02X513130Y1713230I1J-302D01*
G01Y1703224D01*
G02X512827Y1702922I-303J1D01*
G01X509127D01*
G02X508824Y1703224I-1J302D01*
G01Y1705637D01*
G02X508811Y1705866I2003J229D01*
G02X508824Y1706095I2016J0D01*
G01Y1710361D01*
G02X508811Y1710590I2003J229D01*
G02X508824Y1710819I2016J0D01*
G01Y1713230D01*
G02X509127Y1713532I303J-1D01*
G37*
G36*
G01X524875D02*
X528575D01*
G02X528878Y1713230I1J-302D01*
G01Y1703224D01*
G02X528575Y1702922I-303J1D01*
G01X524875D01*
G02X524572Y1703224I-1J302D01*
G01Y1705637D01*
G02X524559Y1705866I2003J229D01*
G02X524572Y1706095I2016J0D01*
G01Y1710361D01*
G02X524559Y1710590I2003J229D01*
G02X524572Y1710819I2016J0D01*
G01Y1713230D01*
G02X524875Y1713532I303J-1D01*
G37*
G36*
G01X540623D02*
X544323D01*
G02X544626Y1713230I1J-302D01*
G01Y1703224D01*
G02X544323Y1702922I-303J1D01*
G01X540623D01*
G02X540320Y1703224I-1J302D01*
G01Y1705637D01*
G02X540307Y1705866I2003J229D01*
G02X540320Y1706095I2016J0D01*
G01Y1710361D01*
G02X540307Y1710590I2003J229D01*
G02X540320Y1710819I2016J0D01*
G01Y1713230D01*
G02X540623Y1713532I303J-1D01*
G37*
G36*
G01X1304009D02*
X1307709D01*
G02X1308012Y1713230I1J-302D01*
G01Y1703224D01*
G02X1307709Y1702922I-303J1D01*
G01X1304009D01*
G02X1303706Y1703224I-1J302D01*
G01Y1705259D01*
G02X1303616Y1705866I2002J607D01*
G02X1304339Y1707448I2092J0D01*
G01X1304657Y1708097D01*
G03Y1708359I-267J131D01*
G01X1304339Y1709008D01*
G02X1303616Y1710590I1369J1582D01*
G02X1303706Y1711197I2092J0D01*
G01Y1713230D01*
G02X1304009Y1713532I303J-1D01*
G37*
G36*
G01X1319757D02*
X1323457D01*
G02X1323760Y1713230I1J-302D01*
G01Y1703224D01*
G02X1323457Y1702922I-303J1D01*
G01X1319757D01*
G02X1319454Y1703224I-1J302D01*
G01Y1705259D01*
G02X1319364Y1705866I2002J607D01*
G02X1320087Y1707448I2092J0D01*
G01X1320405Y1708097D01*
G03Y1708359I-267J131D01*
G01X1320087Y1709008D01*
G02X1319364Y1710590I1369J1582D01*
G02X1319454Y1711197I2092J0D01*
G01Y1713230D01*
G02X1319757Y1713532I303J-1D01*
G37*
G36*
G01X1335505D02*
X1339205D01*
G02X1339508Y1713230I1J-302D01*
G01Y1703224D01*
G02X1339205Y1702922I-303J1D01*
G01X1335505D01*
G02X1335202Y1703224I-1J302D01*
G01Y1705259D01*
G02X1335112Y1705866I2002J607D01*
G02X1335835Y1707448I2092J0D01*
G01X1336153Y1708097D01*
G03Y1708359I-267J131D01*
G01X1335835Y1709008D01*
G02X1335112Y1710590I1369J1582D01*
G02X1335202Y1711197I2092J0D01*
G01Y1713230D01*
G02X1335505Y1713532I303J-1D01*
G37*
G36*
G01X1351253D02*
X1354953D01*
G02X1355256Y1713230I1J-302D01*
G01Y1703224D01*
G02X1354953Y1702922I-303J1D01*
G01X1351253D01*
G02X1350950Y1703224I-1J302D01*
G01Y1705259D01*
G02X1350860Y1705866I2002J607D01*
G02X1351583Y1707448I2092J0D01*
G01X1351901Y1708097D01*
G03Y1708359I-267J131D01*
G01X1351583Y1709008D01*
G02X1350860Y1710590I1369J1582D01*
G02X1350950Y1711197I2092J0D01*
G01Y1713230D01*
G02X1351253Y1713532I303J-1D01*
G37*
G36*
G01X1501253D02*
X1504953D01*
G02X1505256Y1713230I1J-302D01*
G01Y1703224D01*
G02X1504953Y1702922I-303J1D01*
G01X1501253D01*
G02X1500950Y1703224I-1J302D01*
G01Y1705637D01*
G02X1500937Y1705866I2003J229D01*
G02X1500950Y1706095I2016J0D01*
G01Y1710361D01*
G02X1500937Y1710590I2003J229D01*
G02X1500950Y1710819I2016J0D01*
G01Y1713230D01*
G02X1501253Y1713532I303J-1D01*
G37*
G36*
G01X1517001D02*
X1520701D01*
G02X1521004Y1713230I1J-302D01*
G01Y1703224D01*
G02X1520701Y1702922I-303J1D01*
G01X1517001D01*
G02X1516698Y1703224I-1J302D01*
G01Y1705637D01*
G02X1516685Y1705866I2003J229D01*
G02X1516698Y1706095I2016J0D01*
G01Y1710361D01*
G02X1516685Y1710590I2003J229D01*
G02X1516698Y1710819I2016J0D01*
G01Y1713230D01*
G02X1517001Y1713532I303J-1D01*
G37*
G36*
G01X1532749D02*
X1536449D01*
G02X1536752Y1713230I1J-302D01*
G01Y1703224D01*
G02X1536449Y1702922I-303J1D01*
G01X1532749D01*
G02X1532446Y1703224I-1J302D01*
G01Y1705637D01*
G02X1532433Y1705866I2003J229D01*
G02X1532446Y1706095I2016J0D01*
G01Y1710361D01*
G02X1532433Y1710590I2003J229D01*
G02X1532446Y1710819I2016J0D01*
G01Y1713230D01*
G02X1532749Y1713532I303J-1D01*
G37*
G36*
G01X1548497D02*
X1552197D01*
G02X1552500Y1713230I1J-302D01*
G01Y1703224D01*
G02X1552197Y1702922I-303J1D01*
G01X1548497D01*
G02X1548194Y1703224I-1J302D01*
G01Y1705637D01*
G02X1548181Y1705866I2003J229D01*
G02X1548194Y1706095I2016J0D01*
G01Y1710361D01*
G02X1548181Y1710590I2003J229D01*
G02X1548194Y1710819I2016J0D01*
G01Y1713230D01*
G02X1548497Y1713532I303J-1D01*
G37*
G36*
G01X237080Y1717470D02*
X240780D01*
G02X241082Y1717167I-1J-303D01*
G01Y1707161D01*
G02X240780Y1706858I-302J-1D01*
G01X237080D01*
G02X236778Y1707161I1J303D01*
G01Y1709193D01*
G02X236687Y1709803I2002J610D01*
G02X237410Y1711385I2092J0D01*
G01X237728Y1712034D01*
G03Y1712296I-267J131D01*
G01X237410Y1712945D01*
G02X236687Y1714527I1369J1582D01*
G02X236778Y1715137I2093J0D01*
G01Y1717167D01*
G02X237080Y1717470I302J1D01*
G37*
G36*
G01X252828D02*
X256528D01*
G02X256830Y1717167I-1J-303D01*
G01Y1707161D01*
G02X256528Y1706858I-302J-1D01*
G01X252828D01*
G02X252526Y1707161I1J303D01*
G01Y1709193D01*
G02X252435Y1709803I2002J610D01*
G02X253158Y1711385I2092J0D01*
G01X253476Y1712034D01*
G03Y1712296I-267J131D01*
G01X253158Y1712945D01*
G02X252435Y1714527I1369J1582D01*
G02X252526Y1715137I2093J0D01*
G01Y1717167D01*
G02X252828Y1717470I302J1D01*
G37*
G36*
G01X268576D02*
X272276D01*
G02X272578Y1717167I-1J-303D01*
G01Y1707161D01*
G02X272276Y1706858I-302J-1D01*
G01X268576D01*
G02X268274Y1707161I1J303D01*
G01Y1709193D01*
G02X268183Y1709803I2002J610D01*
G02X268906Y1711385I2092J0D01*
G01X269224Y1712034D01*
G03Y1712296I-267J131D01*
G01X268906Y1712945D01*
G02X268183Y1714527I1369J1582D01*
G02X268274Y1715137I2093J0D01*
G01Y1717167D01*
G02X268576Y1717470I302J1D01*
G37*
G36*
G01X284324D02*
X288024D01*
G02X288326Y1717167I-1J-303D01*
G01Y1707161D01*
G02X288024Y1706858I-302J-1D01*
G01X284324D01*
G02X284022Y1707161I1J303D01*
G01Y1709193D01*
G02X283931Y1709803I2002J610D01*
G02X284654Y1711385I2092J0D01*
G01X284972Y1712034D01*
G03Y1712296I-267J131D01*
G01X284654Y1712945D01*
G02X283931Y1714527I1369J1582D01*
G02X284022Y1715137I2093J0D01*
G01Y1717167D01*
G02X284324Y1717470I302J1D01*
G37*
G36*
G01X304009D02*
X307709D01*
G02X308012Y1717167I0J-303D01*
G01Y1707161D01*
G02X307709Y1706858I-303J0D01*
G01X304009D01*
G02X303706Y1707161I0J303D01*
G01Y1709196D01*
G02X303616Y1709803I2002J607D01*
G02X304339Y1711385I2092J0D01*
G01X304657Y1712034D01*
G03Y1712296I-267J131D01*
G01X304339Y1712945D01*
G02X303616Y1714527I1369J1582D01*
G02X303706Y1715134I2092J0D01*
G01Y1717167D01*
G02X304009Y1717470I303J0D01*
G37*
G36*
G01X319757D02*
X323457D01*
G02X323760Y1717167I0J-303D01*
G01Y1707161D01*
G02X323457Y1706858I-303J0D01*
G01X319757D01*
G02X319454Y1707161I0J303D01*
G01Y1709196D01*
G02X319364Y1709803I2002J607D01*
G02X320087Y1711385I2092J0D01*
G01X320405Y1712034D01*
G03Y1712296I-267J131D01*
G01X320087Y1712945D01*
G02X319364Y1714527I1369J1582D01*
G02X319454Y1715134I2092J0D01*
G01Y1717167D01*
G02X319757Y1717470I303J0D01*
G37*
G36*
G01X335505D02*
X339205D01*
G02X339508Y1717167I0J-303D01*
G01Y1707161D01*
G02X339205Y1706858I-303J0D01*
G01X335505D01*
G02X335202Y1707161I0J303D01*
G01Y1709196D01*
G02X335112Y1709803I2002J607D01*
G02X335835Y1711385I2092J0D01*
G01X336153Y1712034D01*
G03Y1712296I-267J131D01*
G01X335835Y1712945D01*
G02X335112Y1714527I1369J1582D01*
G02X335202Y1715134I2092J0D01*
G01Y1717167D01*
G02X335505Y1717470I303J0D01*
G37*
G36*
G01X351253D02*
X354953D01*
G02X355256Y1717167I0J-303D01*
G01Y1707161D01*
G02X354953Y1706858I-303J0D01*
G01X351253D01*
G02X350950Y1707161I0J303D01*
G01Y1709196D01*
G02X350860Y1709803I2002J607D01*
G02X351583Y1711385I2092J0D01*
G01X351901Y1712034D01*
G03Y1712296I-267J131D01*
G01X351583Y1712945D01*
G02X350860Y1714527I1369J1582D01*
G02X350950Y1715134I2092J0D01*
G01Y1717167D01*
G02X351253Y1717470I303J0D01*
G37*
G36*
G01X501253D02*
X504953D01*
G02X505256Y1717167I0J-303D01*
G01Y1707161D01*
G02X504953Y1706858I-303J0D01*
G01X501253D01*
G02X500950Y1707161I0J303D01*
G01Y1709574D01*
G02X500937Y1709803I2003J229D01*
G02X500950Y1710032I2016J0D01*
G01Y1714298D01*
G02X500937Y1714527I2003J229D01*
G02X500950Y1714756I2016J0D01*
G01Y1717167D01*
G02X501253Y1717470I303J0D01*
G37*
G36*
G01X517001D02*
X520701D01*
G02X521004Y1717167I0J-303D01*
G01Y1707161D01*
G02X520701Y1706858I-303J0D01*
G01X517001D01*
G02X516698Y1707161I0J303D01*
G01Y1709574D01*
G02X516685Y1709803I2003J229D01*
G02X516698Y1710032I2016J0D01*
G01Y1714298D01*
G02X516685Y1714527I2003J229D01*
G02X516698Y1714756I2016J0D01*
G01Y1717167D01*
G02X517001Y1717470I303J0D01*
G37*
G36*
G01X532749D02*
X536449D01*
G02X536752Y1717167I0J-303D01*
G01Y1707161D01*
G02X536449Y1706858I-303J0D01*
G01X532749D01*
G02X532446Y1707161I0J303D01*
G01Y1709574D01*
G02X532433Y1709803I2003J229D01*
G02X532446Y1710032I2016J0D01*
G01Y1714298D01*
G02X532433Y1714527I2003J229D01*
G02X532446Y1714756I2016J0D01*
G01Y1717167D01*
G02X532749Y1717470I303J0D01*
G37*
G36*
G01X548497D02*
X552197D01*
G02X552500Y1717167I0J-303D01*
G01Y1707161D01*
G02X552197Y1706858I-303J0D01*
G01X548497D01*
G02X548194Y1707161I0J303D01*
G01Y1709574D01*
G02X548181Y1709803I2003J229D01*
G02X548194Y1710032I2016J0D01*
G01Y1714298D01*
G02X548181Y1714527I2003J229D01*
G02X548194Y1714756I2016J0D01*
G01Y1717167D01*
G02X548497Y1717470I303J0D01*
G37*
G36*
G01X568182D02*
X571882D01*
G02X572184Y1717167I-1J-303D01*
G01Y1707161D01*
G02X571882Y1706858I-302J-1D01*
G01X568182D01*
G02X567880Y1707161I1J303D01*
G01Y1709566D01*
G02X567866Y1709803I2002J237D01*
G02X567880Y1710040I2016J0D01*
G01Y1714290D01*
G02X567866Y1714527I2002J237D01*
G02X567880Y1714764I2016J0D01*
G01Y1717167D01*
G02X568182Y1717470I302J1D01*
G37*
G36*
G01X583930D02*
X587630D01*
G02X587932Y1717167I-1J-303D01*
G01Y1707161D01*
G02X587630Y1706858I-302J-1D01*
G01X583930D01*
G02X583628Y1707161I1J303D01*
G01Y1709566D01*
G02X583614Y1709803I2002J237D01*
G02X583628Y1710040I2016J0D01*
G01Y1714290D01*
G02X583614Y1714527I2002J237D01*
G02X583628Y1714764I2016J0D01*
G01Y1717167D01*
G02X583930Y1717470I302J1D01*
G37*
G36*
G01X599678D02*
X603378D01*
G02X603680Y1717167I-1J-303D01*
G01Y1707161D01*
G02X603378Y1706858I-302J-1D01*
G01X599678D01*
G02X599376Y1707161I1J303D01*
G01Y1709566D01*
G02X599362Y1709803I2002J237D01*
G02X599376Y1710040I2016J0D01*
G01Y1714290D01*
G02X599362Y1714527I2002J237D01*
G02X599376Y1714764I2016J0D01*
G01Y1717167D01*
G02X599678Y1717470I302J1D01*
G37*
G36*
G01X615426D02*
X619126D01*
G02X619428Y1717167I-1J-303D01*
G01Y1707161D01*
G02X619126Y1706858I-302J-1D01*
G01X615426D01*
G02X615124Y1707161I1J303D01*
G01Y1709566D01*
G02X615110Y1709803I2002J237D01*
G02X615124Y1710040I2016J0D01*
G01Y1714290D01*
G02X615110Y1714527I2002J237D01*
G02X615124Y1714764I2016J0D01*
G01Y1717167D01*
G02X615426Y1717470I302J1D01*
G37*
G36*
G01X1244954D02*
X1248654D01*
G02X1248956Y1717167I-1J-303D01*
G01Y1707161D01*
G02X1248654Y1706858I-302J-1D01*
G01X1244954D01*
G02X1244652Y1707161I1J303D01*
G01Y1709193D01*
G02X1244561Y1709803I2002J610D01*
G02X1245284Y1711385I2092J0D01*
G01X1245602Y1712034D01*
G03Y1712296I-267J131D01*
G01X1245284Y1712945D01*
G02X1244561Y1714527I1369J1582D01*
G02X1244652Y1715137I2093J0D01*
G01Y1717167D01*
G02X1244954Y1717470I302J1D01*
G37*
G36*
G01X1260702D02*
X1264402D01*
G02X1264704Y1717167I-1J-303D01*
G01Y1707161D01*
G02X1264402Y1706858I-302J-1D01*
G01X1260702D01*
G02X1260400Y1707161I1J303D01*
G01Y1709193D01*
G02X1260309Y1709803I2002J610D01*
G02X1261032Y1711385I2092J0D01*
G01X1261350Y1712034D01*
G03Y1712296I-267J131D01*
G01X1261032Y1712945D01*
G02X1260309Y1714527I1369J1582D01*
G02X1260400Y1715137I2093J0D01*
G01Y1717167D01*
G02X1260702Y1717470I302J1D01*
G37*
G36*
G01X1276450D02*
X1280150D01*
G02X1280452Y1717167I-1J-303D01*
G01Y1707161D01*
G02X1280150Y1706858I-302J-1D01*
G01X1276450D01*
G02X1276148Y1707161I1J303D01*
G01Y1709193D01*
G02X1276057Y1709803I2002J610D01*
G02X1276780Y1711385I2092J0D01*
G01X1277098Y1712034D01*
G03Y1712296I-267J131D01*
G01X1276780Y1712945D01*
G02X1276057Y1714527I1369J1582D01*
G02X1276148Y1715137I2093J0D01*
G01Y1717167D01*
G02X1276450Y1717470I302J1D01*
G37*
G36*
G01X1292198D02*
X1295898D01*
G02X1296200Y1717167I-1J-303D01*
G01Y1707161D01*
G02X1295898Y1706858I-302J-1D01*
G01X1292198D01*
G02X1291896Y1707161I1J303D01*
G01Y1709193D01*
G02X1291805Y1709803I2002J610D01*
G02X1292528Y1711385I2092J0D01*
G01X1292846Y1712034D01*
G03Y1712296I-267J131D01*
G01X1292528Y1712945D01*
G02X1291805Y1714527I1369J1582D01*
G02X1291896Y1715137I2093J0D01*
G01Y1717167D01*
G02X1292198Y1717470I302J1D01*
G37*
G36*
G01X1311883D02*
X1315583D01*
G02X1315886Y1717167I0J-303D01*
G01Y1707161D01*
G02X1315583Y1706858I-303J0D01*
G01X1311883D01*
G02X1311580Y1707161I0J303D01*
G01Y1709196D01*
G02X1311490Y1709803I2002J607D01*
G02X1312213Y1711385I2092J0D01*
G01X1312531Y1712034D01*
G03Y1712296I-267J131D01*
G01X1312213Y1712945D01*
G02X1311490Y1714527I1369J1582D01*
G02X1311580Y1715134I2092J0D01*
G01Y1717167D01*
G02X1311883Y1717470I303J0D01*
G37*
G36*
G01X1327631D02*
X1331331D01*
G02X1331634Y1717167I0J-303D01*
G01Y1707161D01*
G02X1331331Y1706858I-303J0D01*
G01X1327631D01*
G02X1327328Y1707161I0J303D01*
G01Y1709196D01*
G02X1327238Y1709803I2002J607D01*
G02X1327961Y1711385I2092J0D01*
G01X1328279Y1712034D01*
G03Y1712296I-267J131D01*
G01X1327961Y1712945D01*
G02X1327238Y1714527I1369J1582D01*
G02X1327328Y1715134I2092J0D01*
G01Y1717167D01*
G02X1327631Y1717470I303J0D01*
G37*
G36*
G01X1343379D02*
X1347079D01*
G02X1347382Y1717167I0J-303D01*
G01Y1707161D01*
G02X1347079Y1706858I-303J0D01*
G01X1343379D01*
G02X1343076Y1707161I0J303D01*
G01Y1709196D01*
G02X1342986Y1709803I2002J607D01*
G02X1343709Y1711385I2092J0D01*
G01X1344027Y1712034D01*
G03Y1712296I-267J131D01*
G01X1343709Y1712945D01*
G02X1342986Y1714527I1369J1582D01*
G02X1343076Y1715134I2092J0D01*
G01Y1717167D01*
G02X1343379Y1717470I303J0D01*
G37*
G36*
G01X1359127D02*
X1362827D01*
G02X1363130Y1717167I0J-303D01*
G01Y1707161D01*
G02X1362827Y1706858I-303J0D01*
G01X1359127D01*
G02X1358824Y1707161I0J303D01*
G01Y1709196D01*
G02X1358734Y1709803I2002J607D01*
G02X1359457Y1711385I2092J0D01*
G01X1359775Y1712034D01*
G03Y1712296I-267J131D01*
G01X1359457Y1712945D01*
G02X1358734Y1714527I1369J1582D01*
G02X1358824Y1715134I2092J0D01*
G01Y1717167D01*
G02X1359127Y1717470I303J0D01*
G37*
G36*
G01X1509127D02*
X1512827D01*
G02X1513130Y1717167I0J-303D01*
G01Y1707161D01*
G02X1512827Y1706858I-303J0D01*
G01X1509127D01*
G02X1508824Y1707161I0J303D01*
G01Y1709574D01*
G02X1508811Y1709803I2003J229D01*
G02X1508824Y1710032I2016J0D01*
G01Y1714298D01*
G02X1508811Y1714527I2003J229D01*
G02X1508824Y1714756I2016J0D01*
G01Y1717167D01*
G02X1509127Y1717470I303J0D01*
G37*
G36*
G01X1524875D02*
X1528575D01*
G02X1528878Y1717167I0J-303D01*
G01Y1707161D01*
G02X1528575Y1706858I-303J0D01*
G01X1524875D01*
G02X1524572Y1707161I0J303D01*
G01Y1709574D01*
G02X1524559Y1709803I2003J229D01*
G02X1524572Y1710032I2016J0D01*
G01Y1714298D01*
G02X1524559Y1714527I2003J229D01*
G02X1524572Y1714756I2016J0D01*
G01Y1717167D01*
G02X1524875Y1717470I303J0D01*
G37*
G36*
G01X1540623D02*
X1544323D01*
G02X1544626Y1717167I0J-303D01*
G01Y1707161D01*
G02X1544323Y1706858I-303J0D01*
G01X1540623D01*
G02X1540320Y1707161I0J303D01*
G01Y1709574D01*
G02X1540307Y1709803I2003J229D01*
G02X1540320Y1710032I2016J0D01*
G01Y1714298D01*
G02X1540307Y1714527I2003J229D01*
G02X1540320Y1714756I2016J0D01*
G01Y1717167D01*
G02X1540623Y1717470I303J0D01*
G37*
G36*
G01X1556371D02*
X1560071D01*
G02X1560374Y1717167I0J-303D01*
G01Y1707161D01*
G02X1560071Y1706858I-303J0D01*
G01X1556371D01*
G02X1556068Y1707161I0J303D01*
G01Y1709574D01*
G02X1556055Y1709803I2003J229D01*
G02X1556068Y1710032I2016J0D01*
G01Y1714298D01*
G02X1556055Y1714527I2003J229D01*
G02X1556068Y1714756I2016J0D01*
G01Y1717167D01*
G02X1556371Y1717470I303J0D01*
G37*
G36*
G01X1576056D02*
X1579756D01*
G02X1580058Y1717167I-1J-303D01*
G01Y1707161D01*
G02X1579756Y1706858I-302J-1D01*
G01X1576056D01*
G02X1575754Y1707161I1J303D01*
G01Y1709566D01*
G02X1575740Y1709803I2002J237D01*
G02X1575754Y1710040I2016J0D01*
G01Y1714290D01*
G02X1575740Y1714527I2002J237D01*
G02X1575754Y1714764I2016J0D01*
G01Y1717167D01*
G02X1576056Y1717470I302J1D01*
G37*
G36*
G01X1591804D02*
X1595504D01*
G02X1595806Y1717167I-1J-303D01*
G01Y1707161D01*
G02X1595504Y1706858I-302J-1D01*
G01X1591804D01*
G02X1591502Y1707161I1J303D01*
G01Y1709566D01*
G02X1591488Y1709803I2002J237D01*
G02X1591502Y1710040I2016J0D01*
G01Y1714290D01*
G02X1591488Y1714527I2002J237D01*
G02X1591502Y1714764I2016J0D01*
G01Y1717167D01*
G02X1591804Y1717470I302J1D01*
G37*
G36*
G01X1607552D02*
X1611252D01*
G02X1611554Y1717167I-1J-303D01*
G01Y1707161D01*
G02X1611252Y1706858I-302J-1D01*
G01X1607552D01*
G02X1607250Y1707161I1J303D01*
G01Y1709566D01*
G02X1607236Y1709803I2002J237D01*
G02X1607250Y1710040I2016J0D01*
G01Y1714290D01*
G02X1607236Y1714527I2002J237D01*
G02X1607250Y1714764I2016J0D01*
G01Y1717167D01*
G02X1607552Y1717470I302J1D01*
G37*
G36*
G01X1623300D02*
X1627000D01*
G02X1627302Y1717167I-1J-303D01*
G01Y1707161D01*
G02X1627000Y1706858I-302J-1D01*
G01X1623300D01*
G02X1622998Y1707161I1J303D01*
G01Y1709566D01*
G02X1622984Y1709803I2002J237D01*
G02X1622998Y1710040I2016J0D01*
G01Y1714290D01*
G02X1622984Y1714527I2002J237D01*
G02X1622998Y1714764I2016J0D01*
G01Y1717167D01*
G02X1623300Y1717470I302J1D01*
G37*
G36*
G01X229206Y1727706D02*
X232906D01*
G02X233208Y1727404I0J-302D01*
G01Y1717398D01*
G02X232906Y1717096I-302J0D01*
G01X229206D01*
G02X228904Y1717398I0J302D01*
G01Y1719802D01*
G02X228890Y1720039I2002J237D01*
G02X228904Y1720276I2016J0D01*
G01Y1724526D01*
G02X228890Y1724763I2002J237D01*
G02X228904Y1725000I2016J0D01*
G01Y1727404D01*
G02X229206Y1727706I302J0D01*
G37*
G36*
G01X244954D02*
X248654D01*
G02X248956Y1727404I0J-302D01*
G01Y1717398D01*
G02X248654Y1717096I-302J0D01*
G01X244954D01*
G02X244652Y1717398I0J302D01*
G01Y1719802D01*
G02X244638Y1720039I2002J237D01*
G02X244652Y1720276I2016J0D01*
G01Y1724526D01*
G02X244638Y1724763I2002J237D01*
G02X244652Y1725000I2016J0D01*
G01Y1727404D01*
G02X244954Y1727706I302J0D01*
G37*
G36*
G01X260702D02*
X264402D01*
G02X264704Y1727404I0J-302D01*
G01Y1717398D01*
G02X264402Y1717096I-302J0D01*
G01X260702D01*
G02X260400Y1717398I0J302D01*
G01Y1719802D01*
G02X260386Y1720039I2002J237D01*
G02X260400Y1720276I2016J0D01*
G01Y1724526D01*
G02X260386Y1724763I2002J237D01*
G02X260400Y1725000I2016J0D01*
G01Y1727404D01*
G02X260702Y1727706I302J0D01*
G37*
G36*
G01X276450D02*
X280150D01*
G02X280452Y1727404I0J-302D01*
G01Y1717398D01*
G02X280150Y1717096I-302J0D01*
G01X276450D01*
G02X276148Y1717398I0J302D01*
G01Y1719802D01*
G02X276134Y1720039I2002J237D01*
G02X276148Y1720276I2016J0D01*
G01Y1724526D01*
G02X276134Y1724763I2002J237D01*
G02X276148Y1725000I2016J0D01*
G01Y1727404D01*
G02X276450Y1727706I302J0D01*
G37*
G36*
G01X560308D02*
X564008D01*
G02X564310Y1727404I0J-302D01*
G01Y1717398D01*
G02X564008Y1717096I-302J0D01*
G01X560308D01*
G02X560006Y1717398I0J302D01*
G01Y1719429D01*
G02X559915Y1720039I2002J610D01*
G02X560637Y1721621I2094J0D01*
G01X560956Y1722271D01*
G03Y1722533I-267J131D01*
G01X560639Y1723180D01*
G02X559915Y1724763I1369J1583D01*
G02X560006Y1725373I2093J0D01*
G01Y1727404D01*
G02X560308Y1727706I302J0D01*
G37*
G36*
G01X576056D02*
X579756D01*
G02X580058Y1727404I0J-302D01*
G01Y1717398D01*
G02X579756Y1717096I-302J0D01*
G01X576056D01*
G02X575754Y1717398I0J302D01*
G01Y1719429D01*
G02X575663Y1720039I2002J610D01*
G02X576385Y1721621I2094J0D01*
G01X576704Y1722271D01*
G03Y1722533I-267J131D01*
G01X576387Y1723180D01*
G02X575663Y1724763I1369J1583D01*
G02X575754Y1725373I2093J0D01*
G01Y1727404D01*
G02X576056Y1727706I302J0D01*
G37*
G36*
G01X591804D02*
X595504D01*
G02X595806Y1727404I0J-302D01*
G01Y1717398D01*
G02X595504Y1717096I-302J0D01*
G01X591804D01*
G02X591502Y1717398I0J302D01*
G01Y1719429D01*
G02X591411Y1720039I2002J610D01*
G02X592133Y1721621I2094J0D01*
G01X592452Y1722271D01*
G03Y1722533I-267J131D01*
G01X592135Y1723180D01*
G02X591411Y1724763I1369J1583D01*
G02X591502Y1725373I2093J0D01*
G01Y1727404D01*
G02X591804Y1727706I302J0D01*
G37*
G36*
G01X607552D02*
X611252D01*
G02X611554Y1727404I0J-302D01*
G01Y1717398D01*
G02X611252Y1717096I-302J0D01*
G01X607552D01*
G02X607250Y1717398I0J302D01*
G01Y1719429D01*
G02X607159Y1720039I2002J610D01*
G02X607881Y1721621I2094J0D01*
G01X608200Y1722271D01*
G03Y1722533I-267J131D01*
G01X607883Y1723180D01*
G02X607159Y1724763I1369J1583D01*
G02X607250Y1725373I2093J0D01*
G01Y1727404D01*
G02X607552Y1727706I302J0D01*
G37*
G36*
G01X1237080D02*
X1240780D01*
G02X1241082Y1727404I0J-302D01*
G01Y1717398D01*
G02X1240780Y1717096I-302J0D01*
G01X1237080D01*
G02X1236778Y1717398I0J302D01*
G01Y1719802D01*
G02X1236764Y1720039I2002J237D01*
G02X1236778Y1720276I2016J0D01*
G01Y1724526D01*
G02X1236764Y1724763I2002J237D01*
G02X1236778Y1725000I2016J0D01*
G01Y1727404D01*
G02X1237080Y1727706I302J0D01*
G37*
G36*
G01X1252828D02*
X1256528D01*
G02X1256830Y1727404I0J-302D01*
G01Y1717398D01*
G02X1256528Y1717096I-302J0D01*
G01X1252828D01*
G02X1252526Y1717398I0J302D01*
G01Y1719802D01*
G02X1252512Y1720039I2002J237D01*
G02X1252526Y1720276I2016J0D01*
G01Y1724526D01*
G02X1252512Y1724763I2002J237D01*
G02X1252526Y1725000I2016J0D01*
G01Y1727404D01*
G02X1252828Y1727706I302J0D01*
G37*
G36*
G01X1268576D02*
X1272276D01*
G02X1272578Y1727404I0J-302D01*
G01Y1717398D01*
G02X1272276Y1717096I-302J0D01*
G01X1268576D01*
G02X1268274Y1717398I0J302D01*
G01Y1719802D01*
G02X1268260Y1720039I2002J237D01*
G02X1268274Y1720276I2016J0D01*
G01Y1724526D01*
G02X1268260Y1724763I2002J237D01*
G02X1268274Y1725000I2016J0D01*
G01Y1727404D01*
G02X1268576Y1727706I302J0D01*
G37*
G36*
G01X1284324D02*
X1288024D01*
G02X1288326Y1727404I0J-302D01*
G01Y1717398D01*
G02X1288024Y1717096I-302J0D01*
G01X1284324D01*
G02X1284022Y1717398I0J302D01*
G01Y1719802D01*
G02X1284008Y1720039I2002J237D01*
G02X1284022Y1720276I2016J0D01*
G01Y1724526D01*
G02X1284008Y1724763I2002J237D01*
G02X1284022Y1725000I2016J0D01*
G01Y1727404D01*
G02X1284324Y1727706I302J0D01*
G37*
G36*
G01X1568182D02*
X1571882D01*
G02X1572184Y1727404I0J-302D01*
G01Y1717398D01*
G02X1571882Y1717096I-302J0D01*
G01X1568182D01*
G02X1567880Y1717398I0J302D01*
G01Y1719429D01*
G02X1567789Y1720039I2002J610D01*
G02X1568511Y1721621I2094J0D01*
G01X1568830Y1722271D01*
G03Y1722533I-267J131D01*
G01X1568513Y1723180D01*
G02X1567789Y1724763I1369J1583D01*
G02X1567880Y1725373I2093J0D01*
G01Y1727404D01*
G02X1568182Y1727706I302J0D01*
G37*
G36*
G01X1583930D02*
X1587630D01*
G02X1587932Y1727404I0J-302D01*
G01Y1717398D01*
G02X1587630Y1717096I-302J0D01*
G01X1583930D01*
G02X1583628Y1717398I0J302D01*
G01Y1719429D01*
G02X1583537Y1720039I2002J610D01*
G02X1584259Y1721621I2094J0D01*
G01X1584578Y1722271D01*
G03Y1722533I-267J131D01*
G01X1584261Y1723180D01*
G02X1583537Y1724763I1369J1583D01*
G02X1583628Y1725373I2093J0D01*
G01Y1727404D01*
G02X1583930Y1727706I302J0D01*
G37*
G36*
G01X1599678D02*
X1603378D01*
G02X1603680Y1727404I0J-302D01*
G01Y1717398D01*
G02X1603378Y1717096I-302J0D01*
G01X1599678D01*
G02X1599376Y1717398I0J302D01*
G01Y1719429D01*
G02X1599285Y1720039I2002J610D01*
G02X1600007Y1721621I2094J0D01*
G01X1600326Y1722271D01*
G03Y1722533I-267J131D01*
G01X1600009Y1723180D01*
G02X1599285Y1724763I1369J1583D01*
G02X1599376Y1725373I2093J0D01*
G01Y1727404D01*
G02X1599678Y1727706I302J0D01*
G37*
G36*
G01X1615426D02*
X1619126D01*
G02X1619428Y1727404I0J-302D01*
G01Y1717398D01*
G02X1619126Y1717096I-302J0D01*
G01X1615426D01*
G02X1615124Y1717398I0J302D01*
G01Y1719429D01*
G02X1615033Y1720039I2002J610D01*
G02X1615755Y1721621I2094J0D01*
G01X1616074Y1722271D01*
G03Y1722533I-267J131D01*
G01X1615757Y1723180D01*
G02X1615033Y1724763I1369J1583D01*
G02X1615124Y1725373I2093J0D01*
G01Y1727404D01*
G02X1615426Y1727706I302J0D01*
G37*
G36*
G01X296135D02*
X299835D01*
G02X300138Y1727404I1J-302D01*
G01Y1717398D01*
G02X299835Y1717096I-303J1D01*
G01X296135D01*
G02X295832Y1717398I-1J302D01*
G01Y1719810D01*
G02X295819Y1720039I2003J229D01*
G02X295832Y1720268I2016J0D01*
G01Y1724534D01*
G02X295819Y1724763I2003J229D01*
G02X295832Y1724992I2016J0D01*
G01Y1727404D01*
G02X296135Y1727706I303J-1D01*
G37*
G36*
G01X311883D02*
X315583D01*
G02X315886Y1727404I1J-302D01*
G01Y1717398D01*
G02X315583Y1717096I-303J1D01*
G01X311883D01*
G02X311580Y1717398I-1J302D01*
G01Y1719810D01*
G02X311567Y1720039I2003J229D01*
G02X311580Y1720268I2016J0D01*
G01Y1724534D01*
G02X311567Y1724763I2003J229D01*
G02X311580Y1724992I2016J0D01*
G01Y1727404D01*
G02X311883Y1727706I303J-1D01*
G37*
G36*
G01X327631D02*
X331331D01*
G02X331634Y1727404I1J-302D01*
G01Y1717398D01*
G02X331331Y1717096I-303J1D01*
G01X327631D01*
G02X327328Y1717398I-1J302D01*
G01Y1719810D01*
G02X327315Y1720039I2003J229D01*
G02X327328Y1720268I2016J0D01*
G01Y1724534D01*
G02X327315Y1724763I2003J229D01*
G02X327328Y1724992I2016J0D01*
G01Y1727404D01*
G02X327631Y1727706I303J-1D01*
G37*
G36*
G01X343379D02*
X347079D01*
G02X347382Y1727404I1J-302D01*
G01Y1717398D01*
G02X347079Y1717096I-303J1D01*
G01X343379D01*
G02X343076Y1717398I-1J302D01*
G01Y1719810D01*
G02X343063Y1720039I2003J229D01*
G02X343076Y1720268I2016J0D01*
G01Y1724534D01*
G02X343063Y1724763I2003J229D01*
G02X343076Y1724992I2016J0D01*
G01Y1727404D01*
G02X343379Y1727706I303J-1D01*
G37*
G36*
G01X493379D02*
X497079D01*
G02X497382Y1727404I1J-302D01*
G01Y1717398D01*
G02X497079Y1717096I-303J1D01*
G01X493379D01*
G02X493076Y1717398I-1J302D01*
G01Y1719432D01*
G02X492986Y1720039I2002J607D01*
G02X493708Y1721621I2094J0D01*
G01X494027Y1722271D01*
G03Y1722533I-267J131D01*
G01X493710Y1723180D01*
G02X492986Y1724763I1369J1583D01*
G02X493076Y1725370I2092J0D01*
G01Y1727404D01*
G02X493379Y1727706I303J-1D01*
G37*
G36*
G01X509127D02*
X512827D01*
G02X513130Y1727404I1J-302D01*
G01Y1717398D01*
G02X512827Y1717096I-303J1D01*
G01X509127D01*
G02X508824Y1717398I-1J302D01*
G01Y1719432D01*
G02X508734Y1720039I2002J607D01*
G02X509456Y1721621I2094J0D01*
G01X509775Y1722271D01*
G03Y1722533I-267J131D01*
G01X509458Y1723180D01*
G02X508734Y1724763I1369J1583D01*
G02X508824Y1725370I2092J0D01*
G01Y1727404D01*
G02X509127Y1727706I303J-1D01*
G37*
G36*
G01X524875D02*
X528575D01*
G02X528878Y1727404I1J-302D01*
G01Y1717398D01*
G02X528575Y1717096I-303J1D01*
G01X524875D01*
G02X524572Y1717398I-1J302D01*
G01Y1719432D01*
G02X524482Y1720039I2002J607D01*
G02X525204Y1721621I2094J0D01*
G01X525523Y1722271D01*
G03Y1722533I-267J131D01*
G01X525206Y1723180D01*
G02X524482Y1724763I1369J1583D01*
G02X524572Y1725370I2092J0D01*
G01Y1727404D01*
G02X524875Y1727706I303J-1D01*
G37*
G36*
G01X540623D02*
X544323D01*
G02X544626Y1727404I1J-302D01*
G01Y1717398D01*
G02X544323Y1717096I-303J1D01*
G01X540623D01*
G02X540320Y1717398I-1J302D01*
G01Y1719432D01*
G02X540230Y1720039I2002J607D01*
G02X540952Y1721621I2094J0D01*
G01X541271Y1722271D01*
G03Y1722533I-267J131D01*
G01X540954Y1723180D01*
G02X540230Y1724763I1369J1583D01*
G02X540320Y1725370I2092J0D01*
G01Y1727404D01*
G02X540623Y1727706I303J-1D01*
G37*
G36*
G01X1304009D02*
X1307709D01*
G02X1308012Y1727404I1J-302D01*
G01Y1717398D01*
G02X1307709Y1717096I-303J1D01*
G01X1304009D01*
G02X1303706Y1717398I-1J302D01*
G01Y1719810D01*
G02X1303693Y1720039I2003J229D01*
G02X1303706Y1720268I2016J0D01*
G01Y1724534D01*
G02X1303693Y1724763I2003J229D01*
G02X1303706Y1724992I2016J0D01*
G01Y1727404D01*
G02X1304009Y1727706I303J-1D01*
G37*
G36*
G01X1319757D02*
X1323457D01*
G02X1323760Y1727404I1J-302D01*
G01Y1717398D01*
G02X1323457Y1717096I-303J1D01*
G01X1319757D01*
G02X1319454Y1717398I-1J302D01*
G01Y1719810D01*
G02X1319441Y1720039I2003J229D01*
G02X1319454Y1720268I2016J0D01*
G01Y1724534D01*
G02X1319441Y1724763I2003J229D01*
G02X1319454Y1724992I2016J0D01*
G01Y1727404D01*
G02X1319757Y1727706I303J-1D01*
G37*
G36*
G01X1335505D02*
X1339205D01*
G02X1339508Y1727404I1J-302D01*
G01Y1717398D01*
G02X1339205Y1717096I-303J1D01*
G01X1335505D01*
G02X1335202Y1717398I-1J302D01*
G01Y1719810D01*
G02X1335189Y1720039I2003J229D01*
G02X1335202Y1720268I2016J0D01*
G01Y1724534D01*
G02X1335189Y1724763I2003J229D01*
G02X1335202Y1724992I2016J0D01*
G01Y1727404D01*
G02X1335505Y1727706I303J-1D01*
G37*
G36*
G01X1351253D02*
X1354953D01*
G02X1355256Y1727404I1J-302D01*
G01Y1717398D01*
G02X1354953Y1717096I-303J1D01*
G01X1351253D01*
G02X1350950Y1717398I-1J302D01*
G01Y1719810D01*
G02X1350937Y1720039I2003J229D01*
G02X1350950Y1720268I2016J0D01*
G01Y1724534D01*
G02X1350937Y1724763I2003J229D01*
G02X1350950Y1724992I2016J0D01*
G01Y1727404D01*
G02X1351253Y1727706I303J-1D01*
G37*
G36*
G01X1501253D02*
X1504953D01*
G02X1505256Y1727404I1J-302D01*
G01Y1717398D01*
G02X1504953Y1717096I-303J1D01*
G01X1501253D01*
G02X1500950Y1717398I-1J302D01*
G01Y1719432D01*
G02X1500860Y1720039I2002J607D01*
G02X1501582Y1721621I2094J0D01*
G01X1501901Y1722271D01*
G03Y1722533I-267J131D01*
G01X1501584Y1723180D01*
G02X1500860Y1724763I1369J1583D01*
G02X1500950Y1725370I2092J0D01*
G01Y1727404D01*
G02X1501253Y1727706I303J-1D01*
G37*
G36*
G01X1517001D02*
X1520701D01*
G02X1521004Y1727404I1J-302D01*
G01Y1717398D01*
G02X1520701Y1717096I-303J1D01*
G01X1517001D01*
G02X1516698Y1717398I-1J302D01*
G01Y1719432D01*
G02X1516608Y1720039I2002J607D01*
G02X1517330Y1721621I2094J0D01*
G01X1517649Y1722271D01*
G03Y1722533I-267J131D01*
G01X1517332Y1723180D01*
G02X1516608Y1724763I1369J1583D01*
G02X1516698Y1725370I2092J0D01*
G01Y1727404D01*
G02X1517001Y1727706I303J-1D01*
G37*
G36*
G01X1532749D02*
X1536449D01*
G02X1536752Y1727404I1J-302D01*
G01Y1717398D01*
G02X1536449Y1717096I-303J1D01*
G01X1532749D01*
G02X1532446Y1717398I-1J302D01*
G01Y1719432D01*
G02X1532356Y1720039I2002J607D01*
G02X1533078Y1721621I2094J0D01*
G01X1533397Y1722271D01*
G03Y1722533I-267J131D01*
G01X1533080Y1723180D01*
G02X1532356Y1724763I1369J1583D01*
G02X1532446Y1725370I2092J0D01*
G01Y1727404D01*
G02X1532749Y1727706I303J-1D01*
G37*
G36*
G01X1548497D02*
X1552197D01*
G02X1552500Y1727404I1J-302D01*
G01Y1717398D01*
G02X1552197Y1717096I-303J1D01*
G01X1548497D01*
G02X1548194Y1717398I-1J302D01*
G01Y1719432D01*
G02X1548104Y1720039I2002J607D01*
G02X1548826Y1721621I2094J0D01*
G01X1549145Y1722271D01*
G03Y1722533I-267J131D01*
G01X1548828Y1723180D01*
G02X1548104Y1724763I1369J1583D01*
G02X1548194Y1725370I2092J0D01*
G01Y1727404D01*
G02X1548497Y1727706I303J-1D01*
G37*
G36*
G01X237080Y1731644D02*
X240780D01*
G02X241082Y1731341I-1J-303D01*
G01Y1721335D01*
G02X240780Y1721032I-302J-1D01*
G01X237080D01*
G02X236778Y1721335I1J303D01*
G01Y1723739D01*
G02X236764Y1723976I2002J237D01*
G02X236778Y1724213I2016J0D01*
G01Y1728463D01*
G02X236764Y1728700I2002J237D01*
G02X236778Y1728937I2016J0D01*
G01Y1731341D01*
G02X237080Y1731644I302J1D01*
G37*
G36*
G01X252828D02*
X256528D01*
G02X256830Y1731341I-1J-303D01*
G01Y1721335D01*
G02X256528Y1721032I-302J-1D01*
G01X252828D01*
G02X252526Y1721335I1J303D01*
G01Y1723739D01*
G02X252512Y1723976I2002J237D01*
G02X252526Y1724213I2016J0D01*
G01Y1728463D01*
G02X252512Y1728700I2002J237D01*
G02X252526Y1728937I2016J0D01*
G01Y1731341D01*
G02X252828Y1731644I302J1D01*
G37*
G36*
G01X268576D02*
X272276D01*
G02X272578Y1731341I-1J-303D01*
G01Y1721335D01*
G02X272276Y1721032I-302J-1D01*
G01X268576D01*
G02X268274Y1721335I1J303D01*
G01Y1723739D01*
G02X268260Y1723976I2002J237D01*
G02X268274Y1724213I2016J0D01*
G01Y1728463D01*
G02X268260Y1728700I2002J237D01*
G02X268274Y1728937I2016J0D01*
G01Y1731341D01*
G02X268576Y1731644I302J1D01*
G37*
G36*
G01X284324D02*
X288024D01*
G02X288326Y1731341I-1J-303D01*
G01Y1721335D01*
G02X288024Y1721032I-302J-1D01*
G01X284324D01*
G02X284022Y1721335I1J303D01*
G01Y1723739D01*
G02X284008Y1723976I2002J237D01*
G02X284022Y1724213I2016J0D01*
G01Y1728463D01*
G02X284008Y1728700I2002J237D01*
G02X284022Y1728937I2016J0D01*
G01Y1731341D01*
G02X284324Y1731644I302J1D01*
G37*
G36*
G01X304009D02*
X307709D01*
G02X308012Y1731341I0J-303D01*
G01Y1721335D01*
G02X307709Y1721032I-303J0D01*
G01X304009D01*
G02X303706Y1721335I0J303D01*
G01Y1723747D01*
G02X303693Y1723976I2003J229D01*
G02X303706Y1724205I2016J0D01*
G01Y1728471D01*
G02X303693Y1728700I2003J229D01*
G02X303706Y1728929I2016J0D01*
G01Y1731341D01*
G02X304009Y1731644I303J0D01*
G37*
G36*
G01X319757D02*
X323457D01*
G02X323760Y1731341I0J-303D01*
G01Y1721335D01*
G02X323457Y1721032I-303J0D01*
G01X319757D01*
G02X319454Y1721335I0J303D01*
G01Y1723747D01*
G02X319441Y1723976I2003J229D01*
G02X319454Y1724205I2016J0D01*
G01Y1728471D01*
G02X319441Y1728700I2003J229D01*
G02X319454Y1728929I2016J0D01*
G01Y1731341D01*
G02X319757Y1731644I303J0D01*
G37*
G36*
G01X335505D02*
X339205D01*
G02X339508Y1731341I0J-303D01*
G01Y1721335D01*
G02X339205Y1721032I-303J0D01*
G01X335505D01*
G02X335202Y1721335I0J303D01*
G01Y1723747D01*
G02X335189Y1723976I2003J229D01*
G02X335202Y1724205I2016J0D01*
G01Y1728471D01*
G02X335189Y1728700I2003J229D01*
G02X335202Y1728929I2016J0D01*
G01Y1731341D01*
G02X335505Y1731644I303J0D01*
G37*
G36*
G01X351253D02*
X354953D01*
G02X355256Y1731341I0J-303D01*
G01Y1721335D01*
G02X354953Y1721032I-303J0D01*
G01X351253D01*
G02X350950Y1721335I0J303D01*
G01Y1723747D01*
G02X350937Y1723976I2003J229D01*
G02X350950Y1724205I2016J0D01*
G01Y1728471D01*
G02X350937Y1728700I2003J229D01*
G02X350950Y1728929I2016J0D01*
G01Y1731341D01*
G02X351253Y1731644I303J0D01*
G37*
G36*
G01X501253D02*
X504953D01*
G02X505256Y1731341I0J-303D01*
G01Y1721335D01*
G02X504953Y1721032I-303J0D01*
G01X501253D01*
G02X500950Y1721335I0J303D01*
G01Y1723369D01*
G02X500860Y1723976I2002J607D01*
G02X501582Y1725558I2094J0D01*
G01X501901Y1726208D01*
G03Y1726470I-267J131D01*
G01X501584Y1727117D01*
G02X500860Y1728700I1369J1583D01*
G02X500950Y1729307I2092J0D01*
G01Y1731341D01*
G02X501253Y1731644I303J0D01*
G37*
G36*
G01X517001D02*
X520701D01*
G02X521004Y1731341I0J-303D01*
G01Y1721335D01*
G02X520701Y1721032I-303J0D01*
G01X517001D01*
G02X516698Y1721335I0J303D01*
G01Y1723369D01*
G02X516608Y1723976I2002J607D01*
G02X517330Y1725558I2094J0D01*
G01X517649Y1726208D01*
G03Y1726470I-267J131D01*
G01X517332Y1727117D01*
G02X516608Y1728700I1369J1583D01*
G02X516698Y1729307I2092J0D01*
G01Y1731341D01*
G02X517001Y1731644I303J0D01*
G37*
G36*
G01X532749D02*
X536449D01*
G02X536752Y1731341I0J-303D01*
G01Y1721335D01*
G02X536449Y1721032I-303J0D01*
G01X532749D01*
G02X532446Y1721335I0J303D01*
G01Y1723369D01*
G02X532356Y1723976I2002J607D01*
G02X533078Y1725558I2094J0D01*
G01X533397Y1726208D01*
G03Y1726470I-267J131D01*
G01X533080Y1727117D01*
G02X532356Y1728700I1369J1583D01*
G02X532446Y1729307I2092J0D01*
G01Y1731341D01*
G02X532749Y1731644I303J0D01*
G37*
G36*
G01X548497D02*
X552197D01*
G02X552500Y1731341I0J-303D01*
G01Y1721335D01*
G02X552197Y1721032I-303J0D01*
G01X548497D01*
G02X548194Y1721335I0J303D01*
G01Y1723369D01*
G02X548104Y1723976I2002J607D01*
G02X548826Y1725558I2094J0D01*
G01X549145Y1726208D01*
G03Y1726470I-267J131D01*
G01X548828Y1727117D01*
G02X548104Y1728700I1369J1583D01*
G02X548194Y1729307I2092J0D01*
G01Y1731341D01*
G02X548497Y1731644I303J0D01*
G37*
G36*
G01X568182D02*
X571882D01*
G02X572184Y1731341I-1J-303D01*
G01Y1721335D01*
G02X571882Y1721032I-302J-1D01*
G01X568182D01*
G02X567880Y1721335I1J303D01*
G01Y1723366D01*
G02X567789Y1723976I2002J610D01*
G02X568511Y1725558I2094J0D01*
G01X568830Y1726208D01*
G03Y1726470I-267J131D01*
G01X568513Y1727117D01*
G02X567789Y1728700I1369J1583D01*
G02X567880Y1729310I2093J0D01*
G01Y1731341D01*
G02X568182Y1731644I302J1D01*
G37*
G36*
G01X583930D02*
X587630D01*
G02X587932Y1731341I-1J-303D01*
G01Y1721335D01*
G02X587630Y1721032I-302J-1D01*
G01X583930D01*
G02X583628Y1721335I1J303D01*
G01Y1723366D01*
G02X583537Y1723976I2002J610D01*
G02X584259Y1725558I2094J0D01*
G01X584578Y1726208D01*
G03Y1726470I-267J131D01*
G01X584261Y1727117D01*
G02X583537Y1728700I1369J1583D01*
G02X583628Y1729310I2093J0D01*
G01Y1731341D01*
G02X583930Y1731644I302J1D01*
G37*
G36*
G01X599678D02*
X603378D01*
G02X603680Y1731341I-1J-303D01*
G01Y1721335D01*
G02X603378Y1721032I-302J-1D01*
G01X599678D01*
G02X599376Y1721335I1J303D01*
G01Y1723366D01*
G02X599285Y1723976I2002J610D01*
G02X600007Y1725558I2094J0D01*
G01X600326Y1726208D01*
G03Y1726470I-267J131D01*
G01X600009Y1727117D01*
G02X599285Y1728700I1369J1583D01*
G02X599376Y1729310I2093J0D01*
G01Y1731341D01*
G02X599678Y1731644I302J1D01*
G37*
G36*
G01X615426D02*
X619126D01*
G02X619428Y1731341I-1J-303D01*
G01Y1721335D01*
G02X619126Y1721032I-302J-1D01*
G01X615426D01*
G02X615124Y1721335I1J303D01*
G01Y1723366D01*
G02X615033Y1723976I2002J610D01*
G02X615755Y1725558I2094J0D01*
G01X616074Y1726208D01*
G03Y1726470I-267J131D01*
G01X615757Y1727117D01*
G02X615033Y1728700I1369J1583D01*
G02X615124Y1729310I2093J0D01*
G01Y1731341D01*
G02X615426Y1731644I302J1D01*
G37*
G36*
G01X1244954D02*
X1248654D01*
G02X1248956Y1731341I-1J-303D01*
G01Y1721335D01*
G02X1248654Y1721032I-302J-1D01*
G01X1244954D01*
G02X1244652Y1721335I1J303D01*
G01Y1723739D01*
G02X1244638Y1723976I2002J237D01*
G02X1244652Y1724213I2016J0D01*
G01Y1728463D01*
G02X1244638Y1728700I2002J237D01*
G02X1244652Y1728937I2016J0D01*
G01Y1731341D01*
G02X1244954Y1731644I302J1D01*
G37*
G36*
G01X1260702D02*
X1264402D01*
G02X1264704Y1731341I-1J-303D01*
G01Y1721335D01*
G02X1264402Y1721032I-302J-1D01*
G01X1260702D01*
G02X1260400Y1721335I1J303D01*
G01Y1723739D01*
G02X1260386Y1723976I2002J237D01*
G02X1260400Y1724213I2016J0D01*
G01Y1728463D01*
G02X1260386Y1728700I2002J237D01*
G02X1260400Y1728937I2016J0D01*
G01Y1731341D01*
G02X1260702Y1731644I302J1D01*
G37*
G36*
G01X1276450D02*
X1280150D01*
G02X1280452Y1731341I-1J-303D01*
G01Y1721335D01*
G02X1280150Y1721032I-302J-1D01*
G01X1276450D01*
G02X1276148Y1721335I1J303D01*
G01Y1723739D01*
G02X1276134Y1723976I2002J237D01*
G02X1276148Y1724213I2016J0D01*
G01Y1728463D01*
G02X1276134Y1728700I2002J237D01*
G02X1276148Y1728937I2016J0D01*
G01Y1731341D01*
G02X1276450Y1731644I302J1D01*
G37*
G36*
G01X1292198D02*
X1295898D01*
G02X1296200Y1731341I-1J-303D01*
G01Y1721335D01*
G02X1295898Y1721032I-302J-1D01*
G01X1292198D01*
G02X1291896Y1721335I1J303D01*
G01Y1723739D01*
G02X1291882Y1723976I2002J237D01*
G02X1291896Y1724213I2016J0D01*
G01Y1728463D01*
G02X1291882Y1728700I2002J237D01*
G02X1291896Y1728937I2016J0D01*
G01Y1731341D01*
G02X1292198Y1731644I302J1D01*
G37*
G36*
G01X1311883D02*
X1315583D01*
G02X1315886Y1731341I0J-303D01*
G01Y1721335D01*
G02X1315583Y1721032I-303J0D01*
G01X1311883D01*
G02X1311580Y1721335I0J303D01*
G01Y1723747D01*
G02X1311567Y1723976I2003J229D01*
G02X1311580Y1724205I2016J0D01*
G01Y1728471D01*
G02X1311567Y1728700I2003J229D01*
G02X1311580Y1728929I2016J0D01*
G01Y1731341D01*
G02X1311883Y1731644I303J0D01*
G37*
G36*
G01X1327631D02*
X1331331D01*
G02X1331634Y1731341I0J-303D01*
G01Y1721335D01*
G02X1331331Y1721032I-303J0D01*
G01X1327631D01*
G02X1327328Y1721335I0J303D01*
G01Y1723747D01*
G02X1327315Y1723976I2003J229D01*
G02X1327328Y1724205I2016J0D01*
G01Y1728471D01*
G02X1327315Y1728700I2003J229D01*
G02X1327328Y1728929I2016J0D01*
G01Y1731341D01*
G02X1327631Y1731644I303J0D01*
G37*
G36*
G01X1343379D02*
X1347079D01*
G02X1347382Y1731341I0J-303D01*
G01Y1721335D01*
G02X1347079Y1721032I-303J0D01*
G01X1343379D01*
G02X1343076Y1721335I0J303D01*
G01Y1723747D01*
G02X1343063Y1723976I2003J229D01*
G02X1343076Y1724205I2016J0D01*
G01Y1728471D01*
G02X1343063Y1728700I2003J229D01*
G02X1343076Y1728929I2016J0D01*
G01Y1731341D01*
G02X1343379Y1731644I303J0D01*
G37*
G36*
G01X1359127D02*
X1362827D01*
G02X1363130Y1731341I0J-303D01*
G01Y1721335D01*
G02X1362827Y1721032I-303J0D01*
G01X1359127D01*
G02X1358824Y1721335I0J303D01*
G01Y1723747D01*
G02X1358811Y1723976I2003J229D01*
G02X1358824Y1724205I2016J0D01*
G01Y1728471D01*
G02X1358811Y1728700I2003J229D01*
G02X1358824Y1728929I2016J0D01*
G01Y1731341D01*
G02X1359127Y1731644I303J0D01*
G37*
G36*
G01X1509127D02*
X1512827D01*
G02X1513130Y1731341I0J-303D01*
G01Y1721335D01*
G02X1512827Y1721032I-303J0D01*
G01X1509127D01*
G02X1508824Y1721335I0J303D01*
G01Y1723369D01*
G02X1508734Y1723976I2002J607D01*
G02X1509456Y1725558I2094J0D01*
G01X1509775Y1726208D01*
G03Y1726470I-267J131D01*
G01X1509458Y1727117D01*
G02X1508734Y1728700I1369J1583D01*
G02X1508824Y1729307I2092J0D01*
G01Y1731341D01*
G02X1509127Y1731644I303J0D01*
G37*
G36*
G01X1524875D02*
X1528575D01*
G02X1528878Y1731341I0J-303D01*
G01Y1721335D01*
G02X1528575Y1721032I-303J0D01*
G01X1524875D01*
G02X1524572Y1721335I0J303D01*
G01Y1723369D01*
G02X1524482Y1723976I2002J607D01*
G02X1525204Y1725558I2094J0D01*
G01X1525523Y1726208D01*
G03Y1726470I-267J131D01*
G01X1525206Y1727117D01*
G02X1524482Y1728700I1369J1583D01*
G02X1524572Y1729307I2092J0D01*
G01Y1731341D01*
G02X1524875Y1731644I303J0D01*
G37*
G36*
G01X1540623D02*
X1544323D01*
G02X1544626Y1731341I0J-303D01*
G01Y1721335D01*
G02X1544323Y1721032I-303J0D01*
G01X1540623D01*
G02X1540320Y1721335I0J303D01*
G01Y1723369D01*
G02X1540230Y1723976I2002J607D01*
G02X1540952Y1725558I2094J0D01*
G01X1541271Y1726208D01*
G03Y1726470I-267J131D01*
G01X1540954Y1727117D01*
G02X1540230Y1728700I1369J1583D01*
G02X1540320Y1729307I2092J0D01*
G01Y1731341D01*
G02X1540623Y1731644I303J0D01*
G37*
G36*
G01X1556371D02*
X1560071D01*
G02X1560374Y1731341I0J-303D01*
G01Y1721335D01*
G02X1560071Y1721032I-303J0D01*
G01X1556371D01*
G02X1556068Y1721335I0J303D01*
G01Y1723369D01*
G02X1555978Y1723976I2002J607D01*
G02X1556700Y1725558I2094J0D01*
G01X1557019Y1726208D01*
G03Y1726470I-267J131D01*
G01X1556702Y1727117D01*
G02X1555978Y1728700I1369J1583D01*
G02X1556068Y1729307I2092J0D01*
G01Y1731341D01*
G02X1556371Y1731644I303J0D01*
G37*
G36*
G01X1576056D02*
X1579756D01*
G02X1580058Y1731341I-1J-303D01*
G01Y1721335D01*
G02X1579756Y1721032I-302J-1D01*
G01X1576056D01*
G02X1575754Y1721335I1J303D01*
G01Y1723366D01*
G02X1575663Y1723976I2002J610D01*
G02X1576385Y1725558I2094J0D01*
G01X1576704Y1726208D01*
G03Y1726470I-267J131D01*
G01X1576387Y1727117D01*
G02X1575663Y1728700I1369J1583D01*
G02X1575754Y1729310I2093J0D01*
G01Y1731341D01*
G02X1576056Y1731644I302J1D01*
G37*
G36*
G01X1591804D02*
X1595504D01*
G02X1595806Y1731341I-1J-303D01*
G01Y1721335D01*
G02X1595504Y1721032I-302J-1D01*
G01X1591804D01*
G02X1591502Y1721335I1J303D01*
G01Y1723366D01*
G02X1591411Y1723976I2002J610D01*
G02X1592133Y1725558I2094J0D01*
G01X1592452Y1726208D01*
G03Y1726470I-267J131D01*
G01X1592135Y1727117D01*
G02X1591411Y1728700I1369J1583D01*
G02X1591502Y1729310I2093J0D01*
G01Y1731341D01*
G02X1591804Y1731644I302J1D01*
G37*
G36*
G01X1607552D02*
X1611252D01*
G02X1611554Y1731341I-1J-303D01*
G01Y1721335D01*
G02X1611252Y1721032I-302J-1D01*
G01X1607552D01*
G02X1607250Y1721335I1J303D01*
G01Y1723366D01*
G02X1607159Y1723976I2002J610D01*
G02X1607881Y1725558I2094J0D01*
G01X1608200Y1726208D01*
G03Y1726470I-267J131D01*
G01X1607883Y1727117D01*
G02X1607159Y1728700I1369J1583D01*
G02X1607250Y1729310I2093J0D01*
G01Y1731341D01*
G02X1607552Y1731644I302J1D01*
G37*
G36*
G01X1623300D02*
X1627000D01*
G02X1627302Y1731341I-1J-303D01*
G01Y1721335D01*
G02X1627000Y1721032I-302J-1D01*
G01X1623300D01*
G02X1622998Y1721335I1J303D01*
G01Y1723366D01*
G02X1622907Y1723976I2002J610D01*
G02X1623629Y1725558I2094J0D01*
G01X1623948Y1726208D01*
G03Y1726470I-267J131D01*
G01X1623631Y1727117D01*
G02X1622907Y1728700I1369J1583D01*
G02X1622998Y1729310I2093J0D01*
G01Y1731341D01*
G02X1623300Y1731644I302J1D01*
G37*
G36*
G01X816942Y1721140D02*
X901218D01*
G02X902102Y1720774I0J-1251D01*
G01X909144Y1713732D01*
G02X909510Y1712848I-885J-884D01*
G01Y1667588D01*
X918588Y1658510D01*
X1064948D01*
G02X1065832Y1658144I0J-1251D01*
G01X1085876Y1638100D01*
X1102078D01*
G02X1102962Y1637734I0J-1251D01*
G01X1105274Y1635422D01*
G02X1105640Y1634538I-885J-884D01*
G01Y1606962D01*
G02X1105274Y1606078I-1251J0D01*
G01X1103642Y1604446D01*
G02X1102758Y1604080I-884J885D01*
G01X943752D01*
G02X942868Y1604446I0J1251D01*
G01X916564Y1630750D01*
X815802D01*
G02X814918Y1631116I0J1251D01*
G01X810826Y1635208D01*
G02X810460Y1636092I885J884D01*
G01Y1714658D01*
G02X810826Y1715542I1251J0D01*
G01X816058Y1720774D01*
G02X816942Y1721140I884J-885D01*
G37*
G36*
G01X944340Y1584840D02*
X1103630D01*
G02X1104337Y1584547I0J-999D01*
G01X1105077Y1583807D01*
G02X1105370Y1583100I-706J-707D01*
G01Y1564620D01*
G02X1105077Y1563913I-999J0D01*
G01X1104017Y1562853D01*
G02X1103310Y1562560I-707J706D01*
G01X945140D01*
G02X944433Y1562853I0J999D01*
G01X942903Y1564383D01*
G02X942610Y1565090I706J707D01*
G01Y1583110D01*
G02X942903Y1583817I999J0D01*
G01X943633Y1584547D01*
G02X944340Y1584840I707J-706D01*
G37*
G36*
G01X105651Y1575002D02*
X102251D01*
G02Y1578006I0J1502D01*
G01X105651D01*
G02Y1575002I0J-1502D01*
G37*
G36*
G01X74218Y1574006D02*
X77618D01*
G02Y1571002I0J-1502D01*
G01X74218D01*
G02Y1574006I0J1502D01*
G37*
G36*
G01X76369Y1508958D02*
X79769D01*
G02Y1505954I0J-1502D01*
G01X76369D01*
G02Y1508958I0J1502D01*
G37*
G36*
G01X391330Y1583652D02*
X387930D01*
G02Y1586658I0J1503D01*
G01X391330D01*
G02Y1583652I0J-1503D01*
G37*
G36*
G01X148938Y1515872D02*
X145538D01*
G02Y1518876I0J1502D01*
G01X148938D01*
G02Y1515872I0J-1502D01*
G37*
G36*
G01X164710Y1519516D02*
X168110D01*
G02Y1516512I0J-1502D01*
G01X164710D01*
G02Y1519516I0J1502D01*
G37*
G36*
G01X89264Y1509114D02*
X92664D01*
G02Y1506108I0J-1503D01*
G01X89264D01*
G02Y1509114I0J1503D01*
G37*
G36*
G01X167266Y1571470D02*
X170666D01*
G02Y1568466I0J-1502D01*
G01X167266D01*
G02Y1571470I0J1502D01*
G37*
G36*
G01X1346792Y1615794D02*
X1350192D01*
G02Y1612790I0J-1502D01*
G01X1346792D01*
G02Y1615794I0J1502D01*
G37*
G36*
G01X1358852D02*
X1362252D01*
G02Y1612790I0J-1502D01*
G01X1358852D01*
G02Y1615794I0J1502D01*
G37*
G36*
G01X1365612Y1591596D02*
X1369012D01*
G02Y1588592I0J-1502D01*
G01X1365612D01*
G02Y1591596I0J1502D01*
G37*
G36*
G01Y1579684D02*
X1369012D01*
G02Y1576680I0J-1502D01*
G01X1365612D01*
G02Y1579684I0J1502D01*
G37*
G36*
G01X1305312D02*
X1308712D01*
G02Y1576680I0J-1502D01*
G01X1305312D01*
G02Y1579684I0J1502D01*
G37*
G36*
G01X1293252Y1591596D02*
X1296652D01*
G02Y1588592I0J-1502D01*
G01X1293252D01*
G02Y1591596I0J1502D01*
G37*
G36*
G01X1310612Y1615794D02*
X1314012D01*
G02Y1612790I0J-1502D01*
G01X1310612D01*
G02Y1615794I0J1502D01*
G37*
G36*
G01X1262372Y1603882D02*
X1265772D01*
G02Y1600878I0J-1502D01*
G01X1262372D01*
G02Y1603882I0J1502D01*
G37*
G36*
G01X1286492Y1615794D02*
X1289892D01*
G02Y1612790I0J-1502D01*
G01X1286492D01*
G02Y1615794I0J1502D01*
G37*
G36*
G01X1262372D02*
X1265772D01*
G02Y1612790I0J-1502D01*
G01X1262372D01*
G02Y1615794I0J1502D01*
G37*
G36*
G01X1334732Y1603882D02*
X1338132D01*
G02Y1600878I0J-1502D01*
G01X1334732D01*
G02Y1603882I0J1502D01*
G37*
G36*
G01X1220892Y1579684D02*
X1224292D01*
G02Y1576680I0J-1502D01*
G01X1220892D01*
G02Y1579684I0J1502D01*
G37*
G36*
G01X1334732Y1615794D02*
X1338132D01*
G02Y1612790I0J-1502D01*
G01X1334732D01*
G02Y1615794I0J1502D01*
G37*
G36*
G01X1370912Y1603882D02*
X1374312D01*
G02Y1600878I0J-1502D01*
G01X1370912D01*
G02Y1603882I0J1502D01*
G37*
G36*
G01X1214132D02*
X1217532D01*
G02Y1600878I0J-1502D01*
G01X1214132D01*
G02Y1603882I0J1502D01*
G37*
G36*
G01X1286492D02*
X1289892D01*
G02Y1600878I0J-1502D01*
G01X1286492D01*
G02Y1603882I0J1502D01*
G37*
G36*
G01X1298552D02*
X1301952D01*
G02Y1600878I0J-1502D01*
G01X1298552D01*
G02Y1603882I0J1502D01*
G37*
G36*
G01X1353552Y1579684D02*
X1356952D01*
G02Y1576680I0J-1502D01*
G01X1353552D01*
G02Y1579684I0J1502D01*
G37*
G36*
G01X1341492Y1591596D02*
X1344892D01*
G02Y1588592I0J-1502D01*
G01X1341492D01*
G02Y1591596I0J1502D01*
G37*
G36*
G01X1370912Y1615794D02*
X1374312D01*
G02Y1612790I0J-1502D01*
G01X1370912D01*
G02Y1615794I0J1502D01*
G37*
G36*
G01X1269132Y1591596D02*
X1272532D01*
G02Y1588592I0J-1502D01*
G01X1269132D01*
G02Y1591596I0J1502D01*
G37*
G36*
G01X1238252Y1603882D02*
X1241652D01*
G02Y1600878I0J-1502D01*
G01X1238252D01*
G02Y1603882I0J1502D01*
G37*
G36*
G01X1353552Y1591596D02*
X1356952D01*
G02Y1588592I0J-1502D01*
G01X1353552D01*
G02Y1591596I0J1502D01*
G37*
G36*
G01X1214132Y1615794D02*
X1217532D01*
G02Y1612790I0J-1502D01*
G01X1214132D01*
G02Y1615794I0J1502D01*
G37*
G36*
G01X1226192Y1603882D02*
X1229592D01*
G02Y1600878I0J-1502D01*
G01X1226192D01*
G02Y1603882I0J1502D01*
G37*
G36*
G01X1208832Y1579684D02*
X1212232D01*
G02Y1576680I0J-1502D01*
G01X1208832D01*
G02Y1579684I0J1502D01*
G37*
G36*
G01Y1591596D02*
X1212232D01*
G02Y1588592I0J-1502D01*
G01X1208832D01*
G02Y1591596I0J1502D01*
G37*
G36*
G01X1341492Y1579684D02*
X1344892D01*
G02Y1576680I0J-1502D01*
G01X1341492D01*
G02Y1579684I0J1502D01*
G37*
G36*
G01X1250312Y1615794D02*
X1253712D01*
G02Y1612790I0J-1502D01*
G01X1250312D01*
G02Y1615794I0J1502D01*
G37*
G36*
G01X1232952Y1579684D02*
X1236352D01*
G02Y1576680I0J-1502D01*
G01X1232952D01*
G02Y1579684I0J1502D01*
G37*
G36*
G01Y1591596D02*
X1236352D01*
G02Y1588592I0J-1502D01*
G01X1232952D01*
G02Y1591596I0J1502D01*
G37*
G36*
G01X1196772Y1579684D02*
X1200172D01*
G02Y1576680I0J-1502D01*
G01X1196772D01*
G02Y1579684I0J1502D01*
G37*
G36*
G01X1257072D02*
X1260472D01*
G02Y1576680I0J-1502D01*
G01X1257072D01*
G02Y1579684I0J1502D01*
G37*
G36*
G01X1220892Y1591596D02*
X1224292D01*
G02Y1588592I0J-1502D01*
G01X1220892D01*
G02Y1591596I0J1502D01*
G37*
G36*
G01X1269132Y1579684D02*
X1272532D01*
G02Y1576680I0J-1502D01*
G01X1269132D01*
G02Y1579684I0J1502D01*
G37*
G36*
G01X1305312Y1591596D02*
X1308712D01*
G02Y1588592I0J-1502D01*
G01X1305312D01*
G02Y1591596I0J1502D01*
G37*
G36*
G01X1245012D02*
X1248412D01*
G02Y1588592I0J-1502D01*
G01X1245012D01*
G02Y1591596I0J1502D01*
G37*
G36*
G01X1250312Y1603882D02*
X1253712D01*
G02Y1600878I0J-1502D01*
G01X1250312D01*
G02Y1603882I0J1502D01*
G37*
G36*
G01X1317372Y1579684D02*
X1320772D01*
G02Y1576680I0J-1502D01*
G01X1317372D01*
G02Y1579684I0J1502D01*
G37*
G36*
G01X1358852Y1603882D02*
X1362252D01*
G02Y1600878I0J-1502D01*
G01X1358852D01*
G02Y1603882I0J1502D01*
G37*
G36*
G01X1202072D02*
X1205472D01*
G02Y1600878I0J-1502D01*
G01X1202072D01*
G02Y1603882I0J1502D01*
G37*
G36*
G01Y1615794D02*
X1205472D01*
G02Y1612790I0J-1502D01*
G01X1202072D01*
G02Y1615794I0J1502D01*
G37*
G36*
G01X1322672Y1603882D02*
X1326072D01*
G02Y1600878I0J-1502D01*
G01X1322672D01*
G02Y1603882I0J1502D01*
G37*
G36*
G01X1310612D02*
X1314012D01*
G02Y1600878I0J-1502D01*
G01X1310612D01*
G02Y1603882I0J1502D01*
G37*
G36*
G01X1274432Y1615794D02*
X1277832D01*
G02Y1612790I0J-1502D01*
G01X1274432D01*
G02Y1615794I0J1502D01*
G37*
G36*
G01X1329432Y1579684D02*
X1332832D01*
G02Y1576680I0J-1502D01*
G01X1329432D01*
G02Y1579684I0J1502D01*
G37*
G36*
G01X1346792Y1603882D02*
X1350192D01*
G02Y1600878I0J-1502D01*
G01X1346792D01*
G02Y1603882I0J1502D01*
G37*
G36*
G01X1317372Y1591596D02*
X1320772D01*
G02Y1588592I0J-1502D01*
G01X1317372D01*
G02Y1591596I0J1502D01*
G37*
G36*
G01X1329432D02*
X1332832D01*
G02Y1588592I0J-1502D01*
G01X1329432D01*
G02Y1591596I0J1502D01*
G37*
G36*
G01X1322672Y1615794D02*
X1326072D01*
G02Y1612790I0J-1502D01*
G01X1322672D01*
G02Y1615794I0J1502D01*
G37*
G36*
G01X1281192Y1591596D02*
X1284592D01*
G02Y1588592I0J-1502D01*
G01X1281192D01*
G02Y1591596I0J1502D01*
G37*
G36*
G01X1196772D02*
X1200172D01*
G02Y1588592I0J-1502D01*
G01X1196772D01*
G02Y1591596I0J1502D01*
G37*
G36*
G01X1226192Y1615794D02*
X1229592D01*
G02Y1612790I0J-1502D01*
G01X1226192D01*
G02Y1615794I0J1502D01*
G37*
G36*
G01X1293252Y1579684D02*
X1296652D01*
G02Y1576680I0J-1502D01*
G01X1293252D01*
G02Y1579684I0J1502D01*
G37*
G36*
G01X1298552Y1615794D02*
X1301952D01*
G02Y1612790I0J-1502D01*
G01X1298552D01*
G02Y1615794I0J1502D01*
G37*
G36*
G01X1281192Y1579684D02*
X1284592D01*
G02Y1576680I0J-1502D01*
G01X1281192D01*
G02Y1579684I0J1502D01*
G37*
G36*
G01X1245012D02*
X1248412D01*
G02Y1576680I0J-1502D01*
G01X1245012D01*
G02Y1579684I0J1502D01*
G37*
G36*
G01X1257072Y1591596D02*
X1260472D01*
G02Y1588592I0J-1502D01*
G01X1257072D01*
G02Y1591596I0J1502D01*
G37*
G36*
G01X1274432Y1603882D02*
X1277832D01*
G02Y1600878I0J-1502D01*
G01X1274432D01*
G02Y1603882I0J1502D01*
G37*
G36*
G01X1238252Y1615794D02*
X1241652D01*
G02Y1612790I0J-1502D01*
G01X1238252D01*
G02Y1615794I0J1502D01*
G37*
G36*
G01X1474516Y730492D02*
G02X1473515Y728758I-2002J0D01*
G01X1469877Y726657D01*
G02X1468878Y726390I-999J1736D01*
G01X1468876D01*
G02X1466874Y728392I0J2002D01*
G02X1467875Y730126I2002J0D01*
G01X1471513Y732227D01*
G02X1472512Y732494I999J-1736D01*
G01X1472514D01*
G02X1474516Y730492I0J-2002D01*
G37*
G36*
G01X1477716Y717492D02*
G02X1476715Y715758I-2002J0D01*
G01X1473077Y713657D01*
G02X1472078Y713390I-999J1736D01*
G01X1472076D01*
G02X1470074Y715392I0J2002D01*
G02X1471075Y717126I2002J0D01*
G01X1474713Y719227D01*
G02X1475712Y719494I999J-1736D01*
G01X1475714D01*
G02X1477716Y717492I0J-2002D01*
G37*
G36*
G01Y702992D02*
G02X1476715Y701258I-2002J0D01*
G01X1473077Y699157D01*
G02X1472078Y698890I-999J1736D01*
G01X1472076D01*
G02X1470074Y700892I0J2002D01*
G02X1471075Y702626I2002J0D01*
G01X1474713Y704727D01*
G02X1475712Y704994I999J-1736D01*
G01X1475714D01*
G02X1477716Y702992I0J-2002D01*
G37*
G36*
G01Y688492D02*
G02X1476715Y686758I-2002J0D01*
G01X1473077Y684657D01*
G02X1472078Y684390I-999J1736D01*
G01X1472076D01*
G02X1470074Y686392I0J2002D01*
G02X1471075Y688126I2002J0D01*
G01X1474713Y690227D01*
G02X1475712Y690494I999J-1736D01*
G01X1475714D01*
G02X1477716Y688492I0J-2002D01*
G37*
G36*
G01Y673992D02*
G02X1476715Y672258I-2002J0D01*
G01X1473077Y670157D01*
G02X1472078Y669890I-999J1736D01*
G01X1472076D01*
G02X1470074Y671892I0J2002D01*
G02X1471075Y673626I2002J0D01*
G01X1474713Y675727D01*
G02X1475712Y675994I999J-1736D01*
G01X1475714D01*
G02X1477716Y673992I0J-2002D01*
G37*
G36*
G01Y659492D02*
G02X1476715Y657758I-2002J0D01*
G01X1473077Y655657D01*
G02X1472078Y655390I-999J1736D01*
G01X1472076D01*
G02X1470074Y657392I0J2002D01*
G02X1471075Y659126I2002J0D01*
G01X1474713Y661227D01*
G02X1475712Y661494I999J-1736D01*
G01X1475714D01*
G02X1477716Y659492I0J-2002D01*
G37*
G36*
G01X1455174Y716992D02*
G02X1457176Y718994I2002J0D01*
G01X1457178D01*
G02X1458177Y718727I0J-2003D01*
G01X1461815Y716626D01*
G02X1462816Y714892I-1001J-1734D01*
G02X1460814Y712890I-2002J0D01*
G01X1460812D01*
G02X1459813Y713157I0J2003D01*
G01X1456175Y715258D01*
G02X1455174Y716992I1001J1734D01*
G37*
G36*
G01Y704992D02*
G02X1457176Y706994I2002J0D01*
G01X1457178D01*
G02X1458177Y706727I0J-2003D01*
G01X1461815Y704626D01*
G02X1462816Y702892I-1001J-1734D01*
G02X1460814Y700890I-2002J0D01*
G01X1460812D01*
G02X1459813Y701157I0J2003D01*
G01X1456175Y703258D01*
G02X1455174Y704992I1001J1734D01*
G37*
G36*
G01Y692992D02*
G02X1457176Y694994I2002J0D01*
G01X1457178D01*
G02X1458177Y694727I0J-2003D01*
G01X1461815Y692626D01*
G02X1462816Y690892I-1001J-1734D01*
G02X1460814Y688890I-2002J0D01*
G01X1460812D01*
G02X1459813Y689157I0J2003D01*
G01X1456175Y691258D01*
G02X1455174Y692992I1001J1734D01*
G37*
G36*
G01Y680992D02*
G02X1457176Y682994I2002J0D01*
G01X1457178D01*
G02X1458177Y682727I0J-2003D01*
G01X1461815Y680626D01*
G02X1462816Y678892I-1001J-1734D01*
G02X1460814Y676890I-2002J0D01*
G01X1460812D01*
G02X1459813Y677157I0J2003D01*
G01X1456175Y679258D01*
G02X1455174Y680992I1001J1734D01*
G37*
G36*
G01Y668992D02*
G02X1457176Y670994I2002J0D01*
G01X1457178D01*
G02X1458177Y670727I0J-2003D01*
G01X1461815Y668626D01*
G02X1462816Y666892I-1001J-1734D01*
G02X1460814Y664890I-2002J0D01*
G01X1460812D01*
G02X1459813Y665157I0J2003D01*
G01X1456175Y667258D01*
G02X1455174Y668992I1001J1734D01*
G37*
G36*
G01Y656992D02*
G02X1457176Y658994I2002J0D01*
G01X1457178D01*
G02X1458177Y658727I0J-2003D01*
G01X1461815Y656626D01*
G02X1462816Y654892I-1001J-1734D01*
G02X1460814Y652890I-2002J0D01*
G01X1460812D01*
G02X1459813Y653157I0J2003D01*
G01X1456175Y655258D01*
G02X1455174Y656992I1001J1734D01*
G37*
G36*
G01X1390978Y737198D02*
G02X1389977Y735464I-2002J0D01*
G01X1386339Y733363D01*
G02X1385340Y733096I-999J1736D01*
G01X1385338D01*
G02X1383336Y735098I0J2002D01*
G02X1384337Y736832I2002J0D01*
G01X1387975Y738933D01*
G02X1388974Y739200I999J-1736D01*
G01X1388976D01*
G02X1390978Y737198I0J-2002D01*
G37*
G36*
G01X1395208Y722735D02*
G02X1394207Y721001I-2002J0D01*
G01X1390569Y718900D01*
G02X1389570Y718632I-1001J1735D01*
G01X1389568D01*
G02X1387566Y720635I1J2003D01*
G02X1388567Y722369I2002J0D01*
G01X1392205Y724470D01*
G02X1393204Y724738I1001J-1735D01*
G01X1393206D01*
G02X1395208Y722735I-1J-2003D01*
G37*
G36*
G01Y693708D02*
G02X1394207Y691974I-2002J0D01*
G01X1390569Y689873D01*
G02X1389570Y689606I-999J1736D01*
G01X1389568D01*
G02X1387566Y691608I0J2002D01*
G02X1388567Y693342I2002J0D01*
G01X1392205Y695443D01*
G02X1393204Y695710I999J-1736D01*
G01X1393206D01*
G02X1395208Y693708I0J-2002D01*
G37*
G36*
G01Y708208D02*
G02X1394207Y706474I-2002J0D01*
G01X1390569Y704373D01*
G02X1389570Y704106I-999J1736D01*
G01X1389568D01*
G02X1387566Y706108I0J2002D01*
G02X1388567Y707842I2002J0D01*
G01X1392205Y709943D01*
G02X1393204Y710210I999J-1736D01*
G01X1393206D01*
G02X1395208Y708208I0J-2002D01*
G37*
G36*
G01Y679208D02*
G02X1394207Y677474I-2002J0D01*
G01X1390569Y675373D01*
G02X1389570Y675106I-999J1736D01*
G01X1389568D01*
G02X1387566Y677108I0J2002D01*
G02X1388567Y678842I2002J0D01*
G01X1392205Y680943D01*
G02X1393204Y681210I999J-1736D01*
G01X1393206D01*
G02X1395208Y679208I0J-2002D01*
G37*
G36*
G01Y664708D02*
G02X1394207Y662974I-2002J0D01*
G01X1390569Y660873D01*
G02X1389570Y660606I-999J1736D01*
G01X1389568D01*
G02X1387566Y662608I0J2002D01*
G02X1388567Y664342I2002J0D01*
G01X1392205Y666443D01*
G02X1393204Y666710I999J-1736D01*
G01X1393206D01*
G02X1395208Y664708I0J-2002D01*
G37*
G36*
G01X1372666Y719708D02*
G02X1374668Y721710I2002J0D01*
G01X1374670D01*
G02X1375669Y721443I0J-2003D01*
G01X1379307Y719342D01*
G02X1380308Y717608I-1001J-1734D01*
G02X1378306Y715606I-2002J0D01*
G01X1378304D01*
G02X1377305Y715873I0J2003D01*
G01X1373667Y717974D01*
G02X1372666Y719708I1001J1734D01*
G37*
G36*
G01Y695708D02*
G02X1374668Y697710I2002J0D01*
G01X1374670D01*
G02X1375669Y697443I0J-2003D01*
G01X1379307Y695342D01*
G02X1380308Y693608I-1001J-1734D01*
G02X1378306Y691606I-2002J0D01*
G01X1378304D01*
G02X1377305Y691873I0J2003D01*
G01X1373667Y693974D01*
G02X1372666Y695708I1001J1734D01*
G37*
G36*
G01Y707708D02*
G02X1374668Y709710I2002J0D01*
G01X1374670D01*
G02X1375669Y709443I0J-2003D01*
G01X1379307Y707342D01*
G02X1380308Y705608I-1001J-1734D01*
G02X1378306Y703606I-2002J0D01*
G01X1378304D01*
G02X1377305Y703873I0J2003D01*
G01X1373667Y705974D01*
G02X1372666Y707708I1001J1734D01*
G37*
G36*
G01Y683708D02*
G02X1374668Y685710I2002J0D01*
G01X1374670D01*
G02X1375669Y685443I0J-2003D01*
G01X1379307Y683342D01*
G02X1380308Y681608I-1001J-1734D01*
G02X1378306Y679606I-2002J0D01*
G01X1378304D01*
G02X1377305Y679873I0J2003D01*
G01X1373667Y681974D01*
G02X1372666Y683708I1001J1734D01*
G37*
G36*
G01Y671708D02*
G02X1374668Y673710I2002J0D01*
G01X1374670D01*
G02X1375669Y673443I0J-2003D01*
G01X1379307Y671342D01*
G02X1380308Y669608I-1001J-1734D01*
G02X1378306Y667606I-2002J0D01*
G01X1378304D01*
G02X1377305Y667873I0J2003D01*
G01X1373667Y669974D01*
G02X1372666Y671708I1001J1734D01*
G37*
G36*
G01Y659708D02*
G02X1374668Y661710I2002J0D01*
G01X1374670D01*
G02X1375669Y661443I0J-2003D01*
G01X1379307Y659342D01*
G02X1380308Y657608I-1001J-1734D01*
G02X1378306Y655606I-2002J0D01*
G01X1378304D01*
G02X1377305Y655873I0J2003D01*
G01X1373667Y657974D01*
G02X1372666Y659708I1001J1734D01*
G37*
G36*
G01X146312Y1571028D02*
X149712D01*
G02Y1568022I0J-1503D01*
G01X146312D01*
G02Y1571028I0J1503D01*
G37*
G36*
G01X1701934Y76800D02*
X1705334D01*
G02Y73794I0J-1503D01*
G01X1701934D01*
G02Y76800I0J1503D01*
G37*
G36*
G01X1690934Y70800D02*
X1694334D01*
G02Y67794I0J-1503D01*
G01X1690934D01*
G02Y70800I0J1503D01*
G37*
G36*
G01X1679934Y76800D02*
X1683334D01*
G02Y73794I0J-1503D01*
G01X1679934D01*
G02Y76800I0J1503D01*
G37*
G36*
G01X1657800D02*
X1661200D01*
G02Y73794I0J-1503D01*
G01X1657800D01*
G02Y76800I0J1503D01*
G37*
G36*
G01X1668800Y70800D02*
X1672200D01*
G02Y67794I0J-1503D01*
G01X1668800D01*
G02Y70800I0J1503D01*
G37*
G36*
G01X1646800D02*
X1650200D01*
G02Y67794I0J-1503D01*
G01X1646800D01*
G02Y70800I0J1503D01*
G37*
G36*
G01X1635800Y76800D02*
X1639200D01*
G02Y73794I0J-1503D01*
G01X1635800D01*
G02Y76800I0J1503D01*
G37*
G36*
G01X1612596D02*
X1615996D01*
G02Y73794I0J-1503D01*
G01X1612596D01*
G02Y76800I0J1503D01*
G37*
G36*
G01X1623596Y70800D02*
X1626996D01*
G02Y67794I0J-1503D01*
G01X1623596D01*
G02Y70800I0J1503D01*
G37*
G36*
G01X1601596D02*
X1604996D01*
G02Y67794I0J-1503D01*
G01X1601596D01*
G02Y70800I0J1503D01*
G37*
G36*
G01X1590596Y76800D02*
X1593996D01*
G02Y73794I0J-1503D01*
G01X1590596D01*
G02Y76800I0J1503D01*
G37*
G36*
G01X1579596Y70800D02*
X1582996D01*
G02Y67794I0J-1503D01*
G01X1579596D01*
G02Y70800I0J1503D01*
G37*
G36*
G01X1568596Y76800D02*
X1571996D01*
G02Y73794I0J-1503D01*
G01X1568596D01*
G02Y76800I0J1503D01*
G37*
G36*
G01X1546596D02*
X1549996D01*
G02Y73794I0J-1503D01*
G01X1546596D01*
G02Y76800I0J1503D01*
G37*
G36*
G01X1557596Y70800D02*
X1560996D01*
G02Y67794I0J-1503D01*
G01X1557596D01*
G02Y70800I0J1503D01*
G37*
G36*
G01X1535596D02*
X1538996D01*
G02Y67794I0J-1503D01*
G01X1535596D01*
G02Y70800I0J1503D01*
G37*
G36*
G01X230895Y73838D02*
X227495D01*
G02Y76842I0J1502D01*
G01X230895D01*
G02Y73838I0J-1502D01*
G37*
G36*
G01X219895Y67838D02*
X216495D01*
G02Y70842I0J1502D01*
G01X219895D01*
G02Y67838I0J-1502D01*
G37*
G36*
G01X208895Y73838D02*
X205495D01*
G02Y76842I0J1502D01*
G01X208895D01*
G02Y73838I0J-1502D01*
G37*
G36*
G01X194361Y70842D02*
X197761D01*
G02Y67838I0J-1502D01*
G01X194361D01*
G02Y70842I0J1502D01*
G37*
G36*
G01X183361Y76842D02*
X186761D01*
G02Y73838I0J-1502D01*
G01X183361D01*
G02Y76842I0J1502D01*
G37*
G36*
G01X161361D02*
X164761D01*
G02Y73838I0J-1502D01*
G01X161361D01*
G02Y76842I0J1502D01*
G37*
G36*
G01X172361Y70842D02*
X175761D01*
G02Y67838I0J-1502D01*
G01X172361D01*
G02Y70842I0J1502D01*
G37*
G36*
G01X149157D02*
X152557D01*
G02Y67838I0J-1502D01*
G01X149157D01*
G02Y70842I0J1502D01*
G37*
G36*
G01X138157Y76842D02*
X141557D01*
G02Y73838I0J-1502D01*
G01X138157D01*
G02Y76842I0J1502D01*
G37*
G36*
G01X116157D02*
X119557D01*
G02Y73838I0J-1502D01*
G01X116157D01*
G02Y76842I0J1502D01*
G37*
G36*
G01X127157Y70842D02*
X130557D01*
G02Y67838I0J-1502D01*
G01X127157D01*
G02Y70842I0J1502D01*
G37*
G36*
G01X105157D02*
X108557D01*
G02Y67838I0J-1502D01*
G01X105157D01*
G02Y70842I0J1502D01*
G37*
G36*
G01X94157Y76842D02*
X97557D01*
G02Y73838I0J-1502D01*
G01X94157D01*
G02Y76842I0J1502D01*
G37*
G36*
G01X83157Y70842D02*
X86557D01*
G02Y67838I0J-1502D01*
G01X83157D01*
G02Y70842I0J1502D01*
G37*
G36*
G01X72157Y76842D02*
X75557D01*
G02Y73838I0J-1502D01*
G01X72157D01*
G02Y76842I0J1502D01*
G37*
G36*
G01X61157Y70842D02*
X64557D01*
G02Y67838I0J-1502D01*
G01X61157D01*
G02Y70842I0J1502D01*
G37*
G36*
G01X1619075Y1579684D02*
X1622475D01*
G02Y1576680I0J-1502D01*
G01X1619075D01*
G02Y1579684I0J1502D01*
G37*
G36*
G01X326857Y1603882D02*
X330257D01*
G02Y1600878I0J-1502D01*
G01X326857D01*
G02Y1603882I0J1502D01*
G37*
G36*
G01X363037Y1615794D02*
X366437D01*
G02Y1612790I0J-1502D01*
G01X363037D01*
G02Y1615794I0J1502D01*
G37*
G36*
G01X545411Y1579684D02*
X548811D01*
G02Y1576680I0J-1502D01*
G01X545411D01*
G02Y1579684I0J1502D01*
G37*
G36*
G01Y1591596D02*
X548811D01*
G02Y1588592I0J-1502D01*
G01X545411D01*
G02Y1591596I0J1502D01*
G37*
G36*
G01X1377672D02*
X1381072D01*
G02Y1588592I0J-1502D01*
G01X1377672D01*
G02Y1591596I0J1502D01*
G37*
G36*
G01X533351D02*
X536751D01*
G02Y1588592I0J-1502D01*
G01X533351D01*
G02Y1591596I0J1502D01*
G37*
G36*
G01Y1579684D02*
X536751D01*
G02Y1576680I0J-1502D01*
G01X533351D01*
G02Y1579684I0J1502D01*
G37*
G36*
G01X1594955Y1591596D02*
X1598355D01*
G02Y1588592I0J-1502D01*
G01X1594955D01*
G02Y1591596I0J1502D01*
G37*
G36*
G01X581591D02*
X584991D01*
G02Y1588592I0J-1502D01*
G01X581591D01*
G02Y1591596I0J1502D01*
G37*
G36*
G01Y1579684D02*
X584991D01*
G02Y1576680I0J-1502D01*
G01X581591D01*
G02Y1579684I0J1502D01*
G37*
G36*
G01X1594955D02*
X1598355D01*
G02Y1576680I0J-1502D01*
G01X1594955D01*
G02Y1579684I0J1502D01*
G37*
G36*
G01X605711Y1591596D02*
X609111D01*
G02Y1588592I0J-1502D01*
G01X605711D01*
G02Y1591596I0J1502D01*
G37*
G36*
G01X333617Y1579684D02*
X337017D01*
G02Y1576680I0J-1502D01*
G01X333617D01*
G02Y1579684I0J1502D01*
G37*
G36*
G01X345677D02*
X349077D01*
G02Y1576680I0J-1502D01*
G01X345677D01*
G02Y1579684I0J1502D01*
G37*
G36*
G01X617771D02*
X621171D01*
G02Y1576680I0J-1502D01*
G01X617771D01*
G02Y1579684I0J1502D01*
G37*
G36*
G01Y1591596D02*
X621171D01*
G02Y1588592I0J-1502D01*
G01X617771D01*
G02Y1591596I0J1502D01*
G37*
G36*
G01X629831Y1579684D02*
X633231D01*
G02Y1576680I0J-1502D01*
G01X629831D01*
G02Y1579684I0J1502D01*
G37*
G36*
G01X1582895D02*
X1586295D01*
G02Y1576680I0J-1502D01*
G01X1582895D01*
G02Y1579684I0J1502D01*
G37*
G36*
G01X1570835D02*
X1574235D01*
G02Y1576680I0J-1502D01*
G01X1570835D01*
G02Y1579684I0J1502D01*
G37*
G36*
G01X1558775D02*
X1562175D01*
G02Y1576680I0J-1502D01*
G01X1558775D01*
G02Y1579684I0J1502D01*
G37*
G36*
G01X321557D02*
X324957D01*
G02Y1576680I0J-1502D01*
G01X321557D01*
G02Y1579684I0J1502D01*
G37*
G36*
G01X278617Y1603882D02*
X282017D01*
G02Y1600878I0J-1502D01*
G01X278617D01*
G02Y1603882I0J1502D01*
G37*
G36*
G01X1534655Y1591596D02*
X1538055D01*
G02Y1588592I0J-1502D01*
G01X1534655D01*
G02Y1591596I0J1502D01*
G37*
G36*
G01Y1579684D02*
X1538055D01*
G02Y1576680I0J-1502D01*
G01X1534655D01*
G02Y1579684I0J1502D01*
G37*
G36*
G01X1510535Y1591596D02*
X1513935D01*
G02Y1588592I0J-1502D01*
G01X1510535D01*
G02Y1591596I0J1502D01*
G37*
G36*
G01X1522595D02*
X1525995D01*
G02Y1588592I0J-1502D01*
G01X1522595D01*
G02Y1591596I0J1502D01*
G37*
G36*
G01X309497Y1579684D02*
X312897D01*
G02Y1576680I0J-1502D01*
G01X309497D01*
G02Y1579684I0J1502D01*
G37*
G36*
G01X302737Y1603882D02*
X306137D01*
G02Y1600878I0J-1502D01*
G01X302737D01*
G02Y1603882I0J1502D01*
G37*
G36*
G01X1498475Y1579684D02*
X1501875D01*
G02Y1576680I0J-1502D01*
G01X1498475D01*
G02Y1579684I0J1502D01*
G37*
G36*
G01X314797Y1615794D02*
X318197D01*
G02Y1612790I0J-1502D01*
G01X314797D01*
G02Y1615794I0J1502D01*
G37*
G36*
G01X278617D02*
X282017D01*
G02Y1612790I0J-1502D01*
G01X278617D01*
G02Y1615794I0J1502D01*
G37*
G36*
G01X497171Y1591596D02*
X500571D01*
G02Y1588592I0J-1502D01*
G01X497171D01*
G02Y1591596I0J1502D01*
G37*
G36*
G01X509231D02*
X512631D01*
G02Y1588592I0J-1502D01*
G01X509231D01*
G02Y1591596I0J1502D01*
G37*
G36*
G01Y1579684D02*
X512631D01*
G02Y1576680I0J-1502D01*
G01X509231D01*
G02Y1579684I0J1502D01*
G37*
G36*
G01X1486415Y1591596D02*
X1489815D01*
G02Y1588592I0J-1502D01*
G01X1486415D01*
G02Y1591596I0J1502D01*
G37*
G36*
G01Y1579684D02*
X1489815D01*
G02Y1576680I0J-1502D01*
G01X1486415D01*
G02Y1579684I0J1502D01*
G37*
G36*
G01X321557Y1591596D02*
X324957D01*
G02Y1588592I0J-1502D01*
G01X321557D01*
G02Y1591596I0J1502D01*
G37*
G36*
G01X1462295D02*
X1465695D01*
G02Y1588592I0J-1502D01*
G01X1462295D01*
G02Y1591596I0J1502D01*
G37*
G36*
G01X1474355D02*
X1477755D01*
G02Y1588592I0J-1502D01*
G01X1474355D01*
G02Y1591596I0J1502D01*
G37*
G36*
G01X641891Y1579684D02*
X645291D01*
G02Y1576680I0J-1502D01*
G01X641891D01*
G02Y1579684I0J1502D01*
G37*
G36*
G01Y1591596D02*
X645291D01*
G02Y1588592I0J-1502D01*
G01X641891D01*
G02Y1591596I0J1502D01*
G37*
G36*
G01X285377Y1579684D02*
X288777D01*
G02Y1576680I0J-1502D01*
G01X285377D01*
G02Y1579684I0J1502D01*
G37*
G36*
G01X1462295D02*
X1465695D01*
G02Y1576680I0J-1502D01*
G01X1462295D01*
G02Y1579684I0J1502D01*
G37*
G36*
G01X206257Y1615794D02*
X209657D01*
G02Y1612790I0J-1502D01*
G01X206257D01*
G02Y1615794I0J1502D01*
G37*
G36*
G01X338917D02*
X342317D01*
G02Y1612790I0J-1502D01*
G01X338917D01*
G02Y1615794I0J1502D01*
G37*
G36*
G01X1474355Y1579684D02*
X1477755D01*
G02Y1576680I0J-1502D01*
G01X1474355D01*
G02Y1579684I0J1502D01*
G37*
G36*
G01X261257D02*
X264657D01*
G02Y1576680I0J-1502D01*
G01X261257D01*
G02Y1579684I0J1502D01*
G37*
G36*
G01X485111D02*
X488511D01*
G02Y1576680I0J-1502D01*
G01X485111D01*
G02Y1579684I0J1502D01*
G37*
G36*
G01Y1591596D02*
X488511D01*
G02Y1588592I0J-1502D01*
G01X485111D01*
G02Y1591596I0J1502D01*
G37*
G36*
G01X338917Y1603882D02*
X342317D01*
G02Y1600878I0J-1502D01*
G01X338917D01*
G02Y1603882I0J1502D01*
G37*
G36*
G01X1648495Y1615794D02*
X1651895D01*
G02Y1612790I0J-1502D01*
G01X1648495D01*
G02Y1615794I0J1502D01*
G37*
G36*
G01Y1603882D02*
X1651895D01*
G02Y1600878I0J-1502D01*
G01X1648495D01*
G02Y1603882I0J1502D01*
G37*
G36*
G01X1624375Y1615794D02*
X1627775D01*
G02Y1612790I0J-1502D01*
G01X1624375D01*
G02Y1615794I0J1502D01*
G37*
G36*
G01X266557D02*
X269957D01*
G02Y1612790I0J-1502D01*
G01X266557D01*
G02Y1615794I0J1502D01*
G37*
G36*
G01X254497Y1603882D02*
X257897D01*
G02Y1600878I0J-1502D01*
G01X254497D01*
G02Y1603882I0J1502D01*
G37*
G36*
G01X653951Y1591596D02*
X657351D01*
G02Y1588592I0J-1502D01*
G01X653951D01*
G02Y1591596I0J1502D01*
G37*
G36*
G01Y1579684D02*
X657351D01*
G02Y1576680I0J-1502D01*
G01X653951D01*
G02Y1579684I0J1502D01*
G37*
G36*
G01X369797Y1591596D02*
X373197D01*
G02Y1588592I0J-1502D01*
G01X369797D01*
G02Y1591596I0J1502D01*
G37*
G36*
G01X1636435Y1603882D02*
X1639835D01*
G02Y1600878I0J-1502D01*
G01X1636435D01*
G02Y1603882I0J1502D01*
G37*
G36*
G01X266557D02*
X269957D01*
G02Y1600878I0J-1502D01*
G01X266557D01*
G02Y1603882I0J1502D01*
G37*
G36*
G01X1624375D02*
X1627775D01*
G02Y1600878I0J-1502D01*
G01X1624375D01*
G02Y1603882I0J1502D01*
G37*
G36*
G01X254497Y1615794D02*
X257897D01*
G02Y1612790I0J-1502D01*
G01X254497D01*
G02Y1615794I0J1502D01*
G37*
G36*
G01X194197Y1603882D02*
X197597D01*
G02Y1600878I0J-1502D01*
G01X194197D01*
G02Y1603882I0J1502D01*
G37*
G36*
G01X242437D02*
X245837D01*
G02Y1600878I0J-1502D01*
G01X242437D01*
G02Y1603882I0J1502D01*
G37*
G36*
G01X1612315D02*
X1615715D01*
G02Y1600878I0J-1502D01*
G01X1612315D01*
G02Y1603882I0J1502D01*
G37*
G36*
G01Y1615794D02*
X1615715D01*
G02Y1612790I0J-1502D01*
G01X1612315D01*
G02Y1615794I0J1502D01*
G37*
G36*
G01X230377D02*
X233777D01*
G02Y1612790I0J-1502D01*
G01X230377D01*
G02Y1615794I0J1502D01*
G37*
G36*
G01X521291Y1579684D02*
X524691D01*
G02Y1576680I0J-1502D01*
G01X521291D01*
G02Y1579684I0J1502D01*
G37*
G36*
G01Y1591596D02*
X524691D01*
G02Y1588592I0J-1502D01*
G01X521291D01*
G02Y1591596I0J1502D01*
G37*
G36*
G01X497171Y1579684D02*
X500571D01*
G02Y1576680I0J-1502D01*
G01X497171D01*
G02Y1579684I0J1502D01*
G37*
G36*
G01X593651D02*
X597051D01*
G02Y1576680I0J-1502D01*
G01X593651D01*
G02Y1579684I0J1502D01*
G37*
G36*
G01Y1591596D02*
X597051D01*
G02Y1588592I0J-1502D01*
G01X593651D01*
G02Y1591596I0J1502D01*
G37*
G36*
G01X1600255Y1603882D02*
X1603655D01*
G02Y1600878I0J-1502D01*
G01X1600255D01*
G02Y1603882I0J1502D01*
G37*
G36*
G01Y1615794D02*
X1603655D01*
G02Y1612790I0J-1502D01*
G01X1600255D01*
G02Y1615794I0J1502D01*
G37*
G36*
G01X557471Y1579684D02*
X560871D01*
G02Y1576680I0J-1502D01*
G01X557471D01*
G02Y1579684I0J1502D01*
G37*
G36*
G01X569531D02*
X572931D01*
G02Y1576680I0J-1502D01*
G01X569531D01*
G02Y1579684I0J1502D01*
G37*
G36*
G01Y1591596D02*
X572931D01*
G02Y1588592I0J-1502D01*
G01X569531D01*
G02Y1591596I0J1502D01*
G37*
G36*
G01X557471D02*
X560871D01*
G02Y1588592I0J-1502D01*
G01X557471D01*
G02Y1591596I0J1502D01*
G37*
G36*
G01X333617D02*
X337017D01*
G02Y1588592I0J-1502D01*
G01X333617D01*
G02Y1591596I0J1502D01*
G37*
G36*
G01X345677D02*
X349077D01*
G02Y1588592I0J-1502D01*
G01X345677D01*
G02Y1591596I0J1502D01*
G37*
G36*
G01X1607015Y1579684D02*
X1610415D01*
G02Y1576680I0J-1502D01*
G01X1607015D01*
G02Y1579684I0J1502D01*
G37*
G36*
G01X1576135Y1615794D02*
X1579535D01*
G02Y1612790I0J-1502D01*
G01X1576135D01*
G02Y1615794I0J1502D01*
G37*
G36*
G01X314797Y1603882D02*
X318197D01*
G02Y1600878I0J-1502D01*
G01X314797D01*
G02Y1603882I0J1502D01*
G37*
G36*
G01X1576135D02*
X1579535D01*
G02Y1600878I0J-1502D01*
G01X1576135D01*
G02Y1603882I0J1502D01*
G37*
G36*
G01X261257Y1591596D02*
X264657D01*
G02Y1588592I0J-1502D01*
G01X261257D01*
G02Y1591596I0J1502D01*
G37*
G36*
G01X357737Y1579684D02*
X361137D01*
G02Y1576680I0J-1502D01*
G01X357737D01*
G02Y1579684I0J1502D01*
G37*
G36*
G01X1546715Y1591596D02*
X1550115D01*
G02Y1588592I0J-1502D01*
G01X1546715D01*
G02Y1591596I0J1502D01*
G37*
G36*
G01Y1579684D02*
X1550115D01*
G02Y1576680I0J-1502D01*
G01X1546715D01*
G02Y1579684I0J1502D01*
G37*
G36*
G01X326857Y1615794D02*
X330257D01*
G02Y1612790I0J-1502D01*
G01X326857D01*
G02Y1615794I0J1502D01*
G37*
G36*
G01X249197Y1591596D02*
X252597D01*
G02Y1588592I0J-1502D01*
G01X249197D01*
G02Y1591596I0J1502D01*
G37*
G36*
G01X309497D02*
X312897D01*
G02Y1588592I0J-1502D01*
G01X309497D01*
G02Y1591596I0J1502D01*
G37*
G36*
G01X1564075Y1603882D02*
X1567475D01*
G02Y1600878I0J-1502D01*
G01X1564075D01*
G02Y1603882I0J1502D01*
G37*
G36*
G01Y1615794D02*
X1567475D01*
G02Y1612790I0J-1502D01*
G01X1564075D01*
G02Y1615794I0J1502D01*
G37*
G36*
G01X1552015D02*
X1555415D01*
G02Y1612790I0J-1502D01*
G01X1552015D01*
G02Y1615794I0J1502D01*
G37*
G36*
G01X1503775D02*
X1507175D01*
G02Y1612790I0J-1502D01*
G01X1503775D01*
G02Y1615794I0J1502D01*
G37*
G36*
G01X1552015Y1603882D02*
X1555415D01*
G02Y1600878I0J-1502D01*
G01X1552015D01*
G02Y1603882I0J1502D01*
G37*
G36*
G01X629831Y1591596D02*
X633231D01*
G02Y1588592I0J-1502D01*
G01X629831D01*
G02Y1591596I0J1502D01*
G37*
G36*
G01X1377672Y1579684D02*
X1381072D01*
G02Y1576680I0J-1502D01*
G01X1377672D01*
G02Y1579684I0J1502D01*
G37*
G36*
G01X218317Y1603882D02*
X221717D01*
G02Y1600878I0J-1502D01*
G01X218317D01*
G02Y1603882I0J1502D01*
G37*
G36*
G01X206257D02*
X209657D01*
G02Y1600878I0J-1502D01*
G01X206257D01*
G02Y1603882I0J1502D01*
G37*
G36*
G01X1527895Y1615794D02*
X1531295D01*
G02Y1612790I0J-1502D01*
G01X1527895D01*
G02Y1615794I0J1502D01*
G37*
G36*
G01X200957Y1591596D02*
X204357D01*
G02Y1588592I0J-1502D01*
G01X200957D01*
G02Y1591596I0J1502D01*
G37*
G36*
G01X1631135D02*
X1634535D01*
G02Y1588592I0J-1502D01*
G01X1631135D01*
G02Y1591596I0J1502D01*
G37*
G36*
G01X1539955Y1615794D02*
X1543355D01*
G02Y1612790I0J-1502D01*
G01X1539955D01*
G02Y1615794I0J1502D01*
G37*
G36*
G01Y1603882D02*
X1543355D01*
G02Y1600878I0J-1502D01*
G01X1539955D01*
G02Y1603882I0J1502D01*
G37*
G36*
G01X1527895D02*
X1531295D01*
G02Y1600878I0J-1502D01*
G01X1527895D01*
G02Y1603882I0J1502D01*
G37*
G36*
G01X302737Y1615794D02*
X306137D01*
G02Y1612790I0J-1502D01*
G01X302737D01*
G02Y1615794I0J1502D01*
G37*
G36*
G01X1522595Y1579684D02*
X1525995D01*
G02Y1576680I0J-1502D01*
G01X1522595D01*
G02Y1579684I0J1502D01*
G37*
G36*
G01X1515835Y1615794D02*
X1519235D01*
G02Y1612790I0J-1502D01*
G01X1515835D01*
G02Y1615794I0J1502D01*
G37*
G36*
G01X1636435D02*
X1639835D01*
G02Y1612790I0J-1502D01*
G01X1636435D01*
G02Y1615794I0J1502D01*
G37*
G36*
G01X1498475Y1591596D02*
X1501875D01*
G02Y1588592I0J-1502D01*
G01X1498475D01*
G02Y1591596I0J1502D01*
G37*
G36*
G01X1643195D02*
X1646595D01*
G02Y1588592I0J-1502D01*
G01X1643195D01*
G02Y1591596I0J1502D01*
G37*
G36*
G01X1515835Y1603882D02*
X1519235D01*
G02Y1600878I0J-1502D01*
G01X1515835D01*
G02Y1603882I0J1502D01*
G37*
G36*
G01X357737Y1591596D02*
X361137D01*
G02Y1588592I0J-1502D01*
G01X357737D01*
G02Y1591596I0J1502D01*
G37*
G36*
G01X194197Y1615794D02*
X197597D01*
G02Y1612790I0J-1502D01*
G01X194197D01*
G02Y1615794I0J1502D01*
G37*
G36*
G01X1510535Y1579684D02*
X1513935D01*
G02Y1576680I0J-1502D01*
G01X1510535D01*
G02Y1579684I0J1502D01*
G37*
G36*
G01X1570835Y1591596D02*
X1574235D01*
G02Y1588592I0J-1502D01*
G01X1570835D01*
G02Y1591596I0J1502D01*
G37*
G36*
G01X273317D02*
X276717D01*
G02Y1588592I0J-1502D01*
G01X273317D01*
G02Y1591596I0J1502D01*
G37*
G36*
G01Y1579684D02*
X276717D01*
G02Y1576680I0J-1502D01*
G01X273317D01*
G02Y1579684I0J1502D01*
G37*
G36*
G01X1491715Y1603882D02*
X1495115D01*
G02Y1600878I0J-1502D01*
G01X1491715D01*
G02Y1603882I0J1502D01*
G37*
G36*
G01Y1615794D02*
X1495115D01*
G02Y1612790I0J-1502D01*
G01X1491715D01*
G02Y1615794I0J1502D01*
G37*
G36*
G01X1631135Y1579684D02*
X1634535D01*
G02Y1576680I0J-1502D01*
G01X1631135D01*
G02Y1579684I0J1502D01*
G37*
G36*
G01X213017Y1591596D02*
X216417D01*
G02Y1588592I0J-1502D01*
G01X213017D01*
G02Y1591596I0J1502D01*
G37*
G36*
G01X188897Y1579684D02*
X192297D01*
G02Y1576680I0J-1502D01*
G01X188897D01*
G02Y1579684I0J1502D01*
G37*
G36*
G01X1503775Y1603882D02*
X1507175D01*
G02Y1600878I0J-1502D01*
G01X1503775D01*
G02Y1603882I0J1502D01*
G37*
G36*
G01X200957Y1579684D02*
X204357D01*
G02Y1576680I0J-1502D01*
G01X200957D01*
G02Y1579684I0J1502D01*
G37*
G36*
G01X605711D02*
X609111D01*
G02Y1576680I0J-1502D01*
G01X605711D01*
G02Y1579684I0J1502D01*
G37*
G36*
G01X1479655Y1603882D02*
X1483055D01*
G02Y1600878I0J-1502D01*
G01X1479655D01*
G02Y1603882I0J1502D01*
G37*
G36*
G01Y1615794D02*
X1483055D01*
G02Y1612790I0J-1502D01*
G01X1479655D01*
G02Y1615794I0J1502D01*
G37*
G36*
G01X249197Y1579684D02*
X252597D01*
G02Y1576680I0J-1502D01*
G01X249197D01*
G02Y1579684I0J1502D01*
G37*
G36*
G01X1467595Y1615794D02*
X1470995D01*
G02Y1612790I0J-1502D01*
G01X1467595D01*
G02Y1615794I0J1502D01*
G37*
G36*
G01Y1603882D02*
X1470995D01*
G02Y1600878I0J-1502D01*
G01X1467595D01*
G02Y1603882I0J1502D01*
G37*
G36*
G01X1558775Y1591596D02*
X1562175D01*
G02Y1588592I0J-1502D01*
G01X1558775D01*
G02Y1591596I0J1502D01*
G37*
G36*
G01X1643195Y1579684D02*
X1646595D01*
G02Y1576680I0J-1502D01*
G01X1643195D01*
G02Y1579684I0J1502D01*
G37*
G36*
G01X188897Y1591596D02*
X192297D01*
G02Y1588592I0J-1502D01*
G01X188897D01*
G02Y1591596I0J1502D01*
G37*
G36*
G01X1607015D02*
X1610415D01*
G02Y1588592I0J-1502D01*
G01X1607015D01*
G02Y1591596I0J1502D01*
G37*
G36*
G01X1582895D02*
X1586295D01*
G02Y1588592I0J-1502D01*
G01X1582895D01*
G02Y1591596I0J1502D01*
G37*
G36*
G01X225077Y1579684D02*
X228477D01*
G02Y1576680I0J-1502D01*
G01X225077D01*
G02Y1579684I0J1502D01*
G37*
G36*
G01Y1591596D02*
X228477D01*
G02Y1588592I0J-1502D01*
G01X225077D01*
G02Y1591596I0J1502D01*
G37*
G36*
G01X218317Y1615794D02*
X221717D01*
G02Y1612790I0J-1502D01*
G01X218317D01*
G02Y1615794I0J1502D01*
G37*
G36*
G01X290677Y1603882D02*
X294077D01*
G02Y1600878I0J-1502D01*
G01X290677D01*
G02Y1603882I0J1502D01*
G37*
G36*
G01Y1615794D02*
X294077D01*
G02Y1612790I0J-1502D01*
G01X290677D01*
G02Y1615794I0J1502D01*
G37*
G36*
G01X237137Y1579684D02*
X240537D01*
G02Y1576680I0J-1502D01*
G01X237137D01*
G02Y1579684I0J1502D01*
G37*
G36*
G01X213017D02*
X216417D01*
G02Y1576680I0J-1502D01*
G01X213017D01*
G02Y1579684I0J1502D01*
G37*
G36*
G01X230377Y1603882D02*
X233777D01*
G02Y1600878I0J-1502D01*
G01X230377D01*
G02Y1603882I0J1502D01*
G37*
G36*
G01X1619075Y1591596D02*
X1622475D01*
G02Y1588592I0J-1502D01*
G01X1619075D01*
G02Y1591596I0J1502D01*
G37*
G36*
G01X242437Y1615794D02*
X245837D01*
G02Y1612790I0J-1502D01*
G01X242437D01*
G02Y1615794I0J1502D01*
G37*
G36*
G01X369797Y1579684D02*
X373197D01*
G02Y1576680I0J-1502D01*
G01X369797D01*
G02Y1579684I0J1502D01*
G37*
G36*
G01X473051Y1591596D02*
X476451D01*
G02Y1588592I0J-1502D01*
G01X473051D01*
G02Y1591596I0J1502D01*
G37*
G36*
G01Y1579684D02*
X476451D01*
G02Y1576680I0J-1502D01*
G01X473051D01*
G02Y1579684I0J1502D01*
G37*
G36*
G01X1588195Y1603882D02*
X1591595D01*
G02Y1600878I0J-1502D01*
G01X1588195D01*
G02Y1603882I0J1502D01*
G37*
G36*
G01Y1615794D02*
X1591595D01*
G02Y1612790I0J-1502D01*
G01X1588195D01*
G02Y1615794I0J1502D01*
G37*
G36*
G01X61470Y86124D02*
X64870D01*
G02Y83120I0J-1502D01*
G01X61470D01*
G02Y86124I0J1502D01*
G37*
G36*
G01X297437Y1579684D02*
X300837D01*
G02Y1576680I0J-1502D01*
G01X297437D01*
G02Y1579684I0J1502D01*
G37*
G36*
G01X350977Y1615794D02*
X354377D01*
G02Y1612790I0J-1502D01*
G01X350977D01*
G02Y1615794I0J1502D01*
G37*
G36*
G01X375097Y1603882D02*
X378497D01*
G02Y1600878I0J-1502D01*
G01X375097D01*
G02Y1603882I0J1502D01*
G37*
G36*
G01Y1615794D02*
X378497D01*
G02Y1612790I0J-1502D01*
G01X375097D01*
G02Y1615794I0J1502D01*
G37*
G36*
G01X363037Y1603882D02*
X366437D01*
G02Y1600878I0J-1502D01*
G01X363037D01*
G02Y1603882I0J1502D01*
G37*
G36*
G01X1330101Y541552D02*
X1333143D01*
G02Y538546I0J-1503D01*
G01X1330101D01*
G02Y541552I0J1503D01*
G37*
G36*
G01X1358624Y283142D02*
X1355224D01*
G02Y286146I0J1502D01*
G01X1358624D01*
G02Y283142I0J-1502D01*
G37*
G36*
G01X1348084Y278756D02*
X1344684D01*
G02Y281762I0J1503D01*
G01X1348084D01*
G02Y278756I0J-1503D01*
G37*
G36*
G01X1368524Y281242D02*
X1365124D01*
G02Y284246I0J1502D01*
G01X1368524D01*
G02Y281242I0J-1502D01*
G37*
G36*
G01X1328480Y322400D02*
X1325080D01*
G02Y325404I0J1502D01*
G01X1328480D01*
G02Y322400I0J-1502D01*
G37*
G36*
G01X613970Y190254D02*
X617370D01*
G02Y187250I0J-1502D01*
G01X613970D01*
G02Y190254I0J1502D01*
G37*
G36*
G01X64571Y427304D02*
X61171D01*
G02Y430308I0J1502D01*
G01X64571D01*
G02Y427304I0J-1502D01*
G37*
G36*
G01X626640Y190254D02*
X630040D01*
G02Y187250I0J-1502D01*
G01X626640D01*
G02Y190254I0J1502D01*
G37*
G36*
G01X423180Y1601300D02*
X419780D01*
G02Y1604304I0J1502D01*
G01X423180D01*
G02Y1601300I0J-1502D01*
G37*
G36*
G01X49360Y427304D02*
X45960D01*
G02Y430308I0J1502D01*
G01X49360D01*
G02Y427304I0J-1502D01*
G37*
G36*
G01X1400985Y242432D02*
X1404385D01*
G02Y239426I0J-1503D01*
G01X1400985D01*
G02Y242432I0J1503D01*
G37*
G36*
G01X930731Y531982D02*
X933773D01*
G02Y528976I0J-1503D01*
G01X930731D01*
G02Y531982I0J1503D01*
G37*
G36*
G01X285377Y1591596D02*
X288777D01*
G02Y1588592I0J-1502D01*
G01X285377D01*
G02Y1591596I0J1502D01*
G37*
G36*
G01X229131Y49144D02*
X225731D01*
G02Y52148I0J1502D01*
G01X229131D01*
G02Y49144I0J-1502D01*
G37*
G36*
G01X284230D02*
X280830D01*
G02Y52148I0J1502D01*
G01X284230D01*
G02Y49144I0J-1502D01*
G37*
G36*
G01X1755272Y27934D02*
X1758672D01*
G02Y24928I0J-1503D01*
G01X1755272D01*
G02Y27934I0J1503D01*
G37*
G36*
G01X1530660Y101664D02*
X1534060D01*
G02Y98660I0J-1502D01*
G01X1530660D01*
G02Y101664I0J1502D01*
G37*
G36*
G01X1549308Y27934D02*
X1552708D01*
G02Y24928I0J-1503D01*
G01X1549308D01*
G02Y27934I0J1503D01*
G37*
G36*
G01X1556413Y20998D02*
X1559813D01*
G02Y17992I0J-1503D01*
G01X1556413D01*
G02Y20998I0J1503D01*
G37*
G36*
G01X1563481Y27934D02*
X1566881D01*
G02Y24928I0J-1503D01*
G01X1563481D01*
G02Y27934I0J1503D01*
G37*
G36*
G01X1570586Y20998D02*
X1573986D01*
G02Y17992I0J-1503D01*
G01X1570586D01*
G02Y20998I0J1503D01*
G37*
G36*
G01X1577654Y27934D02*
X1581054D01*
G02Y24928I0J-1503D01*
G01X1577654D01*
G02Y27934I0J1503D01*
G37*
G36*
G01X1584759Y20998D02*
X1588159D01*
G02Y17992I0J-1503D01*
G01X1584759D01*
G02Y20998I0J1503D01*
G37*
G36*
G01X1591828Y27934D02*
X1595228D01*
G02Y24928I0J-1503D01*
G01X1591828D01*
G02Y27934I0J1503D01*
G37*
G36*
G01X1598933Y20998D02*
X1602333D01*
G02Y17992I0J-1503D01*
G01X1598933D01*
G02Y20998I0J1503D01*
G37*
G36*
G01X1627694Y27934D02*
X1631094D01*
G02Y24928I0J-1503D01*
G01X1627694D01*
G02Y27934I0J1503D01*
G37*
G36*
G01X1634799Y20998D02*
X1638199D01*
G02Y17992I0J-1503D01*
G01X1634799D01*
G02Y20998I0J1503D01*
G37*
G36*
G01X218667Y21040D02*
X222067D01*
G02Y18036I0J-1502D01*
G01X218667D01*
G02Y21040I0J1502D01*
G37*
G36*
G01X211562Y27976D02*
X214962D01*
G02Y24972I0J-1502D01*
G01X211562D01*
G02Y27976I0J1502D01*
G37*
G36*
G01X204494Y21040D02*
X207894D01*
G02Y18036I0J-1502D01*
G01X204494D01*
G02Y21040I0J1502D01*
G37*
G36*
G01X197389Y27976D02*
X200789D01*
G02Y24972I0J-1502D01*
G01X197389D01*
G02Y27976I0J1502D01*
G37*
G36*
G01X167428D02*
X170828D01*
G02Y24972I0J-1502D01*
G01X167428D01*
G02Y27976I0J1502D01*
G37*
G36*
G01X174533Y21040D02*
X177933D01*
G02Y18036I0J-1502D01*
G01X174533D01*
G02Y21040I0J1502D01*
G37*
G36*
G01X153255Y27976D02*
X156655D01*
G02Y24972I0J-1502D01*
G01X153255D01*
G02Y27976I0J1502D01*
G37*
G36*
G01X160360Y21040D02*
X163760D01*
G02Y18036I0J-1502D01*
G01X160360D01*
G02Y21040I0J1502D01*
G37*
G36*
G01X124494D02*
X127894D01*
G02Y18036I0J-1502D01*
G01X124494D01*
G02Y21040I0J1502D01*
G37*
G36*
G01X117389Y27976D02*
X120789D01*
G02Y24972I0J-1502D01*
G01X117389D01*
G02Y27976I0J1502D01*
G37*
G36*
G01X103215D02*
X106615D01*
G02Y24972I0J-1502D01*
G01X103215D01*
G02Y27976I0J1502D01*
G37*
G36*
G01X110320Y21040D02*
X113720D01*
G02Y18036I0J-1502D01*
G01X110320D01*
G02Y21040I0J1502D01*
G37*
G36*
G01X89042Y27976D02*
X92442D01*
G02Y24972I0J-1502D01*
G01X89042D01*
G02Y27976I0J1502D01*
G37*
G36*
G01X96147Y21040D02*
X99547D01*
G02Y18036I0J-1502D01*
G01X96147D01*
G02Y21040I0J1502D01*
G37*
G36*
G01X74869Y27976D02*
X78269D01*
G02Y24972I0J-1502D01*
G01X74869D01*
G02Y27976I0J1502D01*
G37*
G36*
G01X81974Y21040D02*
X85374D01*
G02Y18036I0J-1502D01*
G01X81974D01*
G02Y21040I0J1502D01*
G37*
G36*
G01X1641867Y27934D02*
X1645267D01*
G02Y24928I0J-1503D01*
G01X1641867D01*
G02Y27934I0J1503D01*
G37*
G36*
G01X1648972Y20998D02*
X1652372D01*
G02Y17992I0J-1503D01*
G01X1648972D01*
G02Y20998I0J1503D01*
G37*
G36*
G01X1671828Y27934D02*
X1675228D01*
G02Y24928I0J-1503D01*
G01X1671828D01*
G02Y27934I0J1503D01*
G37*
G36*
G01X1678933Y20998D02*
X1682333D01*
G02Y17992I0J-1503D01*
G01X1678933D01*
G02Y20998I0J1503D01*
G37*
G36*
G01X1686001Y27934D02*
X1689401D01*
G02Y24928I0J-1503D01*
G01X1686001D01*
G02Y27934I0J1503D01*
G37*
G36*
G01X1693106Y20998D02*
X1696506D01*
G02Y17992I0J-1503D01*
G01X1693106D01*
G02Y20998I0J1503D01*
G37*
G36*
G01X1700217Y27962D02*
X1703617D01*
G02Y24956I0J-1503D01*
G01X1700217D01*
G02Y27962I0J1503D01*
G37*
G36*
G01X1700170Y52152D02*
X1703570D01*
G02Y49146I0J-1503D01*
G01X1700170D01*
G02Y52152I0J1503D01*
G37*
G36*
G01X670612Y48766D02*
X674012D01*
G02Y45762I0J-1502D01*
G01X670612D01*
G02Y48766I0J1502D01*
G37*
G36*
G01X284233Y24972D02*
X280833D01*
G02Y27976I0J1502D01*
G01X284233D01*
G02Y24972I0J-1502D01*
G37*
G36*
G01X1307442Y305496D02*
X1304042D01*
G02Y308500I0J1502D01*
G01X1307442D01*
G02Y305496I0J-1502D01*
G37*
G36*
G01X1382972Y1603882D02*
X1386372D01*
G02Y1600878I0J-1502D01*
G01X1382972D01*
G02Y1603882I0J1502D01*
G37*
G36*
G01Y1615794D02*
X1386372D01*
G02Y1612790I0J-1502D01*
G01X1382972D01*
G02Y1615794I0J1502D01*
G37*
G36*
G01X229135Y24972D02*
X225735D01*
G02Y27976I0J1502D01*
G01X229135D01*
G02Y24972I0J-1502D01*
G37*
G36*
G01X350977Y1603882D02*
X354377D01*
G02Y1600878I0J-1502D01*
G01X350977D01*
G02Y1603882I0J1502D01*
G37*
G36*
G01X1307042Y291134D02*
X1303642D01*
G02Y294138I0J1502D01*
G01X1307042D01*
G02Y291134I0J-1502D01*
G37*
G36*
G01X405990Y1617450D02*
X402590D01*
G02Y1620454I0J1502D01*
G01X405990D01*
G02Y1617450I0J-1502D01*
G37*
G36*
G01X441740Y1650764D02*
X438340D01*
G02Y1653768I0J1502D01*
G01X441740D01*
G02Y1650764I0J-1502D01*
G37*
G36*
G01X49212Y450100D02*
X45812D01*
G02Y453104I0J1502D01*
G01X49212D01*
G02Y450100I0J-1502D01*
G37*
G36*
G01X1418630Y221520D02*
X1422030D01*
G02Y218516I0J-1502D01*
G01X1418630D01*
G02Y221520I0J1502D01*
G37*
G36*
G01X1407420D02*
X1410820D01*
G02Y218516I0J-1502D01*
G01X1407420D01*
G02Y221520I0J1502D01*
G37*
G36*
G01X1432660D02*
X1436060D01*
G02Y218516I0J-1502D01*
G01X1432660D01*
G02Y221520I0J1502D01*
G37*
G36*
G01X862930Y71574D02*
X866330D01*
G02Y68570I0J-1502D01*
G01X862930D01*
G02Y71574I0J1502D01*
G37*
G36*
G01X1348824Y327478D02*
X1345424D01*
G02Y330484I0J1503D01*
G01X1348824D01*
G02Y327478I0J-1503D01*
G37*
G36*
G01X1341431Y321190D02*
X1338031D01*
G02Y324196I0J1503D01*
G01X1341431D01*
G02Y321190I0J-1503D01*
G37*
G36*
G01X1335145Y331114D02*
X1331745D01*
G02Y334118I0J1502D01*
G01X1335145D01*
G02Y331114I0J-1502D01*
G37*
G36*
G01X1319618Y316570D02*
X1316218D01*
G02Y319576I0J1503D01*
G01X1319618D01*
G02Y316570I0J-1503D01*
G37*
G36*
G01X1311077Y321494D02*
X1307677D01*
G02Y324498I0J1502D01*
G01X1311077D01*
G02Y321494I0J-1502D01*
G37*
G36*
G01X1380602Y199170D02*
X1384002D01*
G02Y196166I0J-1502D01*
G01X1380602D01*
G02Y199170I0J1502D01*
G37*
G36*
G01X1398006D02*
X1401406D01*
G02Y196166I0J-1502D01*
G01X1398006D01*
G02Y199170I0J1502D01*
G37*
G36*
G01X1373591Y177932D02*
X1376991D01*
G02Y174928I0J-1502D01*
G01X1373591D01*
G02Y177932I0J1502D01*
G37*
G36*
G01X1169820Y637554D02*
X1173220D01*
G02Y634550I0J-1502D01*
G01X1169820D01*
G02Y637554I0J1502D01*
G37*
G36*
G01X519764Y41830D02*
X523164D01*
G02Y38826I0J-1502D01*
G01X519764D01*
G02Y41830I0J1502D01*
G37*
G36*
G01X732793Y72938D02*
X736193D01*
G02Y69934I0J-1502D01*
G01X732793D01*
G02Y72938I0J1502D01*
G37*
G36*
G01X1161860Y643614D02*
X1165260D01*
G02Y640610I0J-1502D01*
G01X1161860D01*
G02Y643614I0J1502D01*
G37*
G36*
G01X663543Y44830D02*
X666943D01*
G02Y41826I0J-1502D01*
G01X663543D01*
G02Y44830I0J1502D01*
G37*
G36*
G01X656439Y48766D02*
X659839D01*
G02Y45762I0J-1502D01*
G01X656439D01*
G02Y48766I0J1502D01*
G37*
G36*
G01X562771Y1603882D02*
X566171D01*
G02Y1600878I0J-1502D01*
G01X562771D01*
G02Y1603882I0J1502D01*
G37*
G36*
G01X538651D02*
X542051D01*
G02Y1600878I0J-1502D01*
G01X538651D01*
G02Y1603882I0J1502D01*
G37*
G36*
G01X1406970Y140244D02*
X1410370D01*
G02Y137240I0J-1502D01*
G01X1406970D01*
G02Y140244I0J1502D01*
G37*
G36*
G01X1323303Y297674D02*
X1319903D01*
G02Y300678I0J1502D01*
G01X1323303D01*
G02Y297674I0J-1502D01*
G37*
G36*
G01X1361771Y330772D02*
X1358371D01*
G02Y333778I0J1503D01*
G01X1361771D01*
G02Y330772I0J-1503D01*
G37*
G36*
G01X555175Y72938D02*
X558575D01*
G02Y69934I0J-1502D01*
G01X555175D01*
G02Y72938I0J1502D01*
G37*
G36*
G01X541002D02*
X544402D01*
G02Y69934I0J-1502D01*
G01X541002D01*
G02Y72938I0J1502D01*
G37*
G36*
G01X519742D02*
X523142D01*
G02Y69934I0J-1502D01*
G01X519742D01*
G02Y72938I0J1502D01*
G37*
G36*
G01X533915Y61324D02*
X537315D01*
G02Y58320I0J-1502D01*
G01X533915D01*
G02Y61324I0J1502D01*
G37*
G36*
G01X1294500Y298190D02*
X1291100D01*
G02Y301194I0J1502D01*
G01X1294500D01*
G02Y298190I0J-1502D01*
G37*
G36*
G01X1404829Y185766D02*
X1408229D01*
G02Y182760I0J-1503D01*
G01X1404829D01*
G02Y185766I0J1503D01*
G37*
G36*
G01X538651Y1615794D02*
X542051D01*
G02Y1612790I0J-1502D01*
G01X538651D01*
G02Y1615794I0J1502D01*
G37*
G36*
G01X526591Y1603882D02*
X529991D01*
G02Y1600878I0J-1502D01*
G01X526591D01*
G02Y1603882I0J1502D01*
G37*
G36*
G01X514531D02*
X517931D01*
G02Y1600878I0J-1502D01*
G01X514531D01*
G02Y1603882I0J1502D01*
G37*
G36*
G01X526591Y1615794D02*
X529991D01*
G02Y1612790I0J-1502D01*
G01X526591D01*
G02Y1615794I0J1502D01*
G37*
G36*
G01X514531D02*
X517931D01*
G02Y1612790I0J-1502D01*
G01X514531D01*
G02Y1615794I0J1502D01*
G37*
G36*
G01X490411Y1603882D02*
X493811D01*
G02Y1600878I0J-1502D01*
G01X490411D01*
G02Y1603882I0J1502D01*
G37*
G36*
G01X478351Y1615794D02*
X481751D01*
G02Y1612790I0J-1502D01*
G01X478351D01*
G02Y1615794I0J1502D01*
G37*
G36*
G01X502471D02*
X505871D01*
G02Y1612790I0J-1502D01*
G01X502471D01*
G02Y1615794I0J1502D01*
G37*
G36*
G01X478351Y1603882D02*
X481751D01*
G02Y1600878I0J-1502D01*
G01X478351D01*
G02Y1603882I0J1502D01*
G37*
G36*
G01X1412284Y173198D02*
X1415684D01*
G02Y170194I0J-1502D01*
G01X1412284D01*
G02Y173198I0J1502D01*
G37*
G36*
G01X598951Y1603882D02*
X602351D01*
G02Y1600878I0J-1502D01*
G01X598951D01*
G02Y1603882I0J1502D01*
G37*
G36*
G01Y1615794D02*
X602351D01*
G02Y1612790I0J-1502D01*
G01X598951D01*
G02Y1615794I0J1502D01*
G37*
G36*
G01X586891Y1603882D02*
X590291D01*
G02Y1600878I0J-1502D01*
G01X586891D01*
G02Y1603882I0J1502D01*
G37*
G36*
G01X647191D02*
X650591D01*
G02Y1600878I0J-1502D01*
G01X647191D01*
G02Y1603882I0J1502D01*
G37*
G36*
G01X635131Y1615794D02*
X638531D01*
G02Y1612790I0J-1502D01*
G01X635131D01*
G02Y1615794I0J1502D01*
G37*
G36*
G01X647191D02*
X650591D01*
G02Y1612790I0J-1502D01*
G01X647191D01*
G02Y1615794I0J1502D01*
G37*
G36*
G01X623071D02*
X626471D01*
G02Y1612790I0J-1502D01*
G01X623071D01*
G02Y1615794I0J1502D01*
G37*
G36*
G01X1355200Y336340D02*
X1351800D01*
G02Y339346I0J1503D01*
G01X1355200D01*
G02Y336340I0J-1503D01*
G37*
G36*
G01X1328814Y292054D02*
X1325414D01*
G02Y295058I0J1502D01*
G01X1328814D01*
G02Y292054I0J-1502D01*
G37*
G36*
G01X1340161Y291902D02*
X1336761D01*
G02Y294906I0J1502D01*
G01X1340161D01*
G02Y291902I0J-1502D01*
G37*
G36*
G01X1413950Y185766D02*
X1417350D01*
G02Y182760I0J-1503D01*
G01X1413950D01*
G02Y185766I0J1503D01*
G37*
G36*
G01X1423110D02*
X1426510D01*
G02Y182760I0J-1503D01*
G01X1423110D01*
G02Y185766I0J1503D01*
G37*
G36*
G01X1401341Y178662D02*
X1404741D01*
G02Y175656I0J-1503D01*
G01X1401341D01*
G02Y178662I0J1503D01*
G37*
G36*
G01X1403778Y173186D02*
X1407178D01*
G02Y170182I0J-1502D01*
G01X1403778D01*
G02Y173186I0J1502D01*
G37*
G36*
G01X1389256Y199170D02*
X1392656D01*
G02Y196166I0J-1502D01*
G01X1389256D01*
G02Y199170I0J1502D01*
G37*
G36*
G01X550711Y1603882D02*
X554111D01*
G02Y1600878I0J-1502D01*
G01X550711D01*
G02Y1603882I0J1502D01*
G37*
G36*
G01X502471D02*
X505871D01*
G02Y1600878I0J-1502D01*
G01X502471D01*
G02Y1603882I0J1502D01*
G37*
G36*
G01X490411Y1615794D02*
X493811D01*
G02Y1612790I0J-1502D01*
G01X490411D01*
G02Y1615794I0J1502D01*
G37*
G36*
G01X987440Y432696D02*
X990840D01*
G02Y429690I0J-1503D01*
G01X987440D01*
G02Y432696I0J1503D01*
G37*
G36*
G01X1471460Y631900D02*
X1468060D01*
G02Y634904I0J1502D01*
G01X1471460D01*
G02Y631900I0J-1502D01*
G37*
G36*
G01X934047Y459364D02*
X937447D01*
G02Y456360I0J-1502D01*
G01X934047D01*
G02Y459364I0J1502D01*
G37*
G36*
G01X942047Y464514D02*
X945447D01*
G02Y461510I0J-1502D01*
G01X942047D01*
G02Y464514I0J1502D01*
G37*
G36*
G01X550711Y1615794D02*
X554111D01*
G02Y1612790I0J-1502D01*
G01X550711D01*
G02Y1615794I0J1502D01*
G37*
G36*
G01X635131Y1603882D02*
X638531D01*
G02Y1600878I0J-1502D01*
G01X635131D01*
G02Y1603882I0J1502D01*
G37*
G36*
G01X909584Y459638D02*
X912984D01*
G02Y456632I0J-1503D01*
G01X909584D01*
G02Y459638I0J1503D01*
G37*
G36*
G01X913394Y523164D02*
X916794D01*
G02Y520160I0J-1502D01*
G01X913394D01*
G02Y523164I0J1502D01*
G37*
G36*
G01X574831Y1603882D02*
X578231D01*
G02Y1600878I0J-1502D01*
G01X574831D01*
G02Y1603882I0J1502D01*
G37*
G36*
G01X659251D02*
X662651D01*
G02Y1600878I0J-1502D01*
G01X659251D01*
G02Y1603882I0J1502D01*
G37*
G36*
G01X1153370Y639694D02*
X1156770D01*
G02Y636690I0J-1502D01*
G01X1153370D01*
G02Y639694I0J1502D01*
G37*
G36*
G01X1406786Y199170D02*
X1410186D01*
G02Y196166I0J-1502D01*
G01X1406786D01*
G02Y199170I0J1502D01*
G37*
G36*
G01X611011Y1615794D02*
X614411D01*
G02Y1612790I0J-1502D01*
G01X611011D01*
G02Y1615794I0J1502D01*
G37*
G36*
G01X1312136Y283446D02*
X1308736D01*
G02Y286450I0J1502D01*
G01X1312136D01*
G02Y283446I0J-1502D01*
G37*
G36*
G01X611011Y1603882D02*
X614411D01*
G02Y1600878I0J-1502D01*
G01X611011D01*
G02Y1603882I0J1502D01*
G37*
G36*
G01X586891Y1615794D02*
X590291D01*
G02Y1612790I0J-1502D01*
G01X586891D01*
G02Y1615794I0J1502D01*
G37*
G36*
G01X659251D02*
X662651D01*
G02Y1612790I0J-1502D01*
G01X659251D01*
G02Y1615794I0J1502D01*
G37*
G36*
G01X574831D02*
X578231D01*
G02Y1612790I0J-1502D01*
G01X574831D01*
G02Y1615794I0J1502D01*
G37*
G36*
G01X1183360Y643564D02*
X1186760D01*
G02Y640560I0J-1502D01*
G01X1183360D01*
G02Y643564I0J1502D01*
G37*
G36*
G01X562771Y1615794D02*
X566171D01*
G02Y1612790I0J-1502D01*
G01X562771D01*
G02Y1615794I0J1502D01*
G37*
G36*
G01X901230Y533114D02*
X904630D01*
G02Y530110I0J-1502D01*
G01X901230D01*
G02Y533114I0J1502D01*
G37*
G36*
G01X954390Y529098D02*
X957790D01*
G02Y526094I0J-1502D01*
G01X954390D01*
G02Y529098I0J1502D01*
G37*
G36*
G01X963930Y534864D02*
X967330D01*
G02Y531860I0J-1502D01*
G01X963930D01*
G02Y534864I0J1502D01*
G37*
G36*
G01X548070Y80874D02*
X551470D01*
G02Y77870I0J-1502D01*
G01X548070D01*
G02Y80874I0J1502D01*
G37*
G36*
G01X623071Y1603882D02*
X626471D01*
G02Y1600878I0J-1502D01*
G01X623071D01*
G02Y1603882I0J1502D01*
G37*
G36*
G01X888130Y534114D02*
X891530D01*
G02Y531110I0J-1502D01*
G01X888130D01*
G02Y534114I0J1502D01*
G37*
G36*
G01X297437Y1591596D02*
X300837D01*
G02Y1588592I0J-1502D01*
G01X297437D01*
G02Y1591596I0J1502D01*
G37*
G36*
G01X237137D02*
X240537D01*
G02Y1588592I0J-1502D01*
G01X237137D01*
G02Y1591596I0J1502D01*
G37*
G36*
G01X937340Y309612D02*
X920138D01*
G02X937340I8601J12041D01*
G37*
G36*
G01X921047Y464514D02*
X924447D01*
G02Y461510I0J-1502D01*
G01X921047D01*
G02Y464514I0J1502D01*
G37*
G36*
G01X371587Y173422D02*
X365287D01*
G02Y197050I0J11814D01*
G01X371587D01*
G02Y173422I0J-11814D01*
G37*
G36*
G01X253477D02*
X247176D01*
G02X247175Y197050I0J11814D01*
G01X253476D01*
G02X253477Y173422I0J-11814D01*
G37*
G36*
G01X1012861Y434390D02*
X1016261D01*
G02Y431386I0J-1502D01*
G01X1012861D01*
G02Y434390I0J1502D01*
G37*
G36*
G01X50772Y120610D02*
X55372Y124913D01*
G02X66448Y113076I5538J-5919D01*
G01X61848Y108773D01*
G02X50772Y120610I-5538J5918D01*
G37*
G36*
G01X62587Y23395D02*
G02X58024Y17311I-2280J-3043D01*
G02X62587Y23395I2279J3044D01*
G37*
G36*
G01X443227Y845968D02*
G02X444266Y845448I0J-1298D01*
G01X445888D01*
G02X446927Y845968I1039J-778D01*
G02Y843374I0J-1297D01*
G02X445888Y843894I0J1298D01*
G01X444266D01*
G02X443227Y843374I-1039J778D01*
G02Y845968I0J1297D01*
G37*
G36*
G01X356830Y844971D02*
G02X359424I1297J0D01*
G02X358362Y843695I-1298J0D01*
G01X358267Y843677D01*
X357426Y842082D01*
X357465Y841994D01*
G02X357576Y841467I-1186J-525D01*
G02X354982I-1297J0D01*
G02X356044Y842743I1298J0D01*
G01X356139Y842761D01*
X356980Y844356D01*
X356941Y844444D01*
G02X356830Y844971I1186J525D01*
G37*
G36*
G01X364230D02*
G02X366824I1297J0D01*
G02X365762Y843695I-1298J0D01*
G01X365667Y843677D01*
X364826Y842082D01*
X364865Y841994D01*
G02X364976Y841467I-1186J-525D01*
G02X362382I-1297J0D01*
G02X363444Y842743I1298J0D01*
G01X363539Y842761D01*
X364380Y844356D01*
X364341Y844444D01*
G02X364230Y844971I1186J525D01*
G37*
G36*
G01X371630D02*
G02X374224I1297J0D01*
G02X373162Y843695I-1298J0D01*
G01X373067Y843677D01*
X372226Y842082D01*
X372265Y841994D01*
G02X372376Y841467I-1186J-525D01*
G02X369782I-1297J0D01*
G02X370844Y842743I1298J0D01*
G01X370939Y842761D01*
X371780Y844356D01*
X371741Y844444D01*
G02X371630Y844971I1186J525D01*
G37*
G36*
G01X379030D02*
G02X381624I1297J0D01*
G02X380562Y843695I-1298J0D01*
G01X380467Y843677D01*
X379626Y842082D01*
X379665Y841994D01*
G02X379776Y841467I-1186J-525D01*
G02X377182I-1297J0D01*
G02X378244Y842743I1298J0D01*
G01X378339Y842761D01*
X379180Y844356D01*
X379141Y844444D01*
G02X379030Y844971I1186J525D01*
G37*
G36*
G01X386430D02*
G02X389024I1297J0D01*
G02X387962Y843695I-1298J0D01*
G01X387867Y843677D01*
X387026Y842082D01*
X387065Y841994D01*
G02X387176Y841467I-1186J-525D01*
G02X384582I-1297J0D01*
G02X385644Y842743I1298J0D01*
G01X385739Y842761D01*
X386580Y844356D01*
X386541Y844444D01*
G02X386430Y844971I1186J525D01*
G37*
G36*
G01X393830D02*
G02X396424I1297J0D01*
G02X395362Y843695I-1298J0D01*
G01X395267Y843677D01*
X394426Y842082D01*
X394465Y841994D01*
G02X394576Y841467I-1186J-525D01*
G02X391982I-1297J0D01*
G02X393044Y842743I1298J0D01*
G01X393139Y842761D01*
X393980Y844356D01*
X393941Y844444D01*
G02X393830Y844971I1186J525D01*
G37*
G36*
G01X401230D02*
G02X403824I1297J0D01*
G02X402762Y843695I-1298J0D01*
G01X402667Y843677D01*
X401826Y842082D01*
X401865Y841994D01*
G02X401976Y841467I-1186J-525D01*
G02X399382I-1297J0D01*
G02X400444Y842743I1298J0D01*
G01X400539Y842761D01*
X401380Y844356D01*
X401341Y844444D01*
G02X401230Y844971I1186J525D01*
G37*
G36*
G01X408630D02*
G02X411224I1297J0D01*
G02X410162Y843695I-1298J0D01*
G01X410067Y843677D01*
X409226Y842082D01*
X409265Y841994D01*
G02X409376Y841467I-1186J-525D01*
G02X406782I-1297J0D01*
G02X407844Y842743I1298J0D01*
G01X407939Y842761D01*
X408780Y844356D01*
X408741Y844444D01*
G02X408630Y844971I1186J525D01*
G37*
G36*
G01X416030D02*
G02X418624I1297J0D01*
G02X417562Y843695I-1298J0D01*
G01X417467Y843677D01*
X416626Y842082D01*
X416665Y841994D01*
G02X416776Y841467I-1186J-525D01*
G02X414182I-1297J0D01*
G02X415244Y842743I1298J0D01*
G01X415339Y842761D01*
X416180Y844356D01*
X416141Y844444D01*
G02X416030Y844971I1186J525D01*
G37*
G36*
G01X423430D02*
G02X426024I1297J0D01*
G02X424962Y843695I-1298J0D01*
G01X424867Y843677D01*
X424026Y842082D01*
X424065Y841994D01*
G02X424176Y841467I-1186J-525D01*
G02X421582I-1297J0D01*
G02X422644Y842743I1298J0D01*
G01X422739Y842761D01*
X423580Y844356D01*
X423541Y844444D01*
G02X423430Y844971I1186J525D01*
G37*
G36*
G01X453030D02*
G02X455624I1297J0D01*
G02X454562Y843695I-1298J0D01*
G01X454467Y843677D01*
X453626Y842082D01*
X453665Y841994D01*
G02X453776Y841467I-1186J-525D01*
G02X451182I-1297J0D01*
G02X452244Y842743I1298J0D01*
G01X452339Y842761D01*
X453180Y844356D01*
X453141Y844444D01*
G02X453030Y844971I1186J525D01*
G37*
G36*
G01X460430D02*
G02X463024I1297J0D01*
G02X461962Y843695I-1298J0D01*
G01X461867Y843677D01*
X461026Y842082D01*
X461065Y841994D01*
G02X461176Y841467I-1186J-525D01*
G02X458582I-1297J0D01*
G02X459644Y842743I1298J0D01*
G01X459739Y842761D01*
X460580Y844356D01*
X460541Y844444D01*
G02X460430Y844971I1186J525D01*
G37*
G36*
G01X467830D02*
G02X470424I1297J0D01*
G02X469362Y843695I-1298J0D01*
G01X469267Y843677D01*
X468426Y842082D01*
X468465Y841994D01*
G02X468576Y841467I-1186J-525D01*
G02X465982I-1297J0D01*
G02X467044Y842743I1298J0D01*
G01X467139Y842761D01*
X467980Y844356D01*
X467941Y844444D01*
G02X467830Y844971I1186J525D01*
G37*
G36*
G01X475230D02*
G02X477824I1297J0D01*
G02X476762Y843695I-1298J0D01*
G01X476667Y843677D01*
X475826Y842082D01*
X475865Y841994D01*
G02X475976Y841467I-1186J-525D01*
G02X473382I-1297J0D01*
G02X474444Y842743I1298J0D01*
G01X474539Y842761D01*
X475380Y844356D01*
X475341Y844444D01*
G02X475230Y844971I1186J525D01*
G37*
G36*
G01X482630D02*
G02X485224I1297J0D01*
G02X484162Y843695I-1298J0D01*
G01X484067Y843677D01*
X483226Y842082D01*
X483265Y841994D01*
G02X483376Y841467I-1186J-525D01*
G02X480782I-1297J0D01*
G02X481844Y842743I1298J0D01*
G01X481939Y842761D01*
X482780Y844356D01*
X482741Y844444D01*
G02X482630Y844971I1186J525D01*
G37*
G36*
G01X490030D02*
G02X492624I1297J0D01*
G02X491519Y843688I-1297J0D01*
G01X491418Y843673D01*
X490608Y842112D01*
X490651Y842023D01*
G02X490776Y841467I-1174J-556D01*
G02X488180I-1298J0D01*
G02X489315Y842754I1297J0D01*
G01X489420Y842767D01*
X490213Y844297D01*
X490168Y844389D01*
G02X490030Y844971I1158J582D01*
G37*
G36*
G01X497430D02*
G02X500024I1297J0D01*
G02X498962Y843695I-1298J0D01*
G01X498867Y843677D01*
X498025Y842081D01*
X498064Y841993D01*
G02X498176Y841467I-1186J-527D01*
G02X495580I-1298J0D01*
G02X496644Y842743I1297J0D01*
G01X496739Y842761D01*
X497580Y844356D01*
X497541Y844444D01*
G02X497430Y844971I1186J525D01*
G37*
G36*
G01X504830D02*
G02X507424I1297J0D01*
G02X506362Y843695I-1298J0D01*
G01X506267Y843677D01*
X505426Y842082D01*
X505465Y841994D01*
G02X505576Y841467I-1186J-525D01*
G02X502982I-1297J0D01*
G02X504044Y842743I1298J0D01*
G01X504139Y842761D01*
X504980Y844356D01*
X504941Y844444D01*
G02X504830Y844971I1186J525D01*
G37*
G36*
G01X512230D02*
G02X514824I1297J0D01*
G02X513762Y843695I-1298J0D01*
G01X513667Y843677D01*
X512826Y842082D01*
X512865Y841994D01*
G02X512976Y841467I-1186J-525D01*
G02X510382I-1297J0D01*
G02X511444Y842743I1298J0D01*
G01X511539Y842761D01*
X512380Y844356D01*
X512341Y844444D01*
G02X512230Y844971I1186J525D01*
G37*
G36*
G01X519630D02*
G02X522224I1297J0D01*
G02X521162Y843695I-1298J0D01*
G01X521067Y843677D01*
X520226Y842082D01*
X520265Y841994D01*
G02X520376Y841467I-1186J-525D01*
G02X517782I-1297J0D01*
G02X518844Y842743I1298J0D01*
G01X518939Y842761D01*
X519780Y844356D01*
X519741Y844444D01*
G02X519630Y844971I1186J525D01*
G37*
G36*
G01X1332972D02*
G02X1335566I1297J0D01*
G02X1334504Y843695I-1298J0D01*
G01X1334409Y843677D01*
X1333568Y842082D01*
X1333607Y841994D01*
G02X1333718Y841467I-1186J-525D01*
G02X1331124I-1297J0D01*
G02X1332186Y842743I1298J0D01*
G01X1332281Y842761D01*
X1333122Y844356D01*
X1333083Y844444D01*
G02X1332972Y844971I1186J525D01*
G37*
G36*
G01X1340372D02*
G02X1342966I1297J0D01*
G02X1341904Y843695I-1298J0D01*
G01X1341809Y843677D01*
X1340968Y842082D01*
X1341007Y841994D01*
G02X1341118Y841467I-1186J-525D01*
G02X1338524I-1297J0D01*
G02X1339586Y842743I1298J0D01*
G01X1339681Y842761D01*
X1340522Y844356D01*
X1340483Y844444D01*
G02X1340372Y844971I1186J525D01*
G37*
G36*
G01X1347772D02*
G02X1350366I1297J0D01*
G02X1349304Y843695I-1298J0D01*
G01X1349209Y843677D01*
X1348368Y842082D01*
X1348407Y841994D01*
G02X1348518Y841467I-1186J-525D01*
G02X1345924I-1297J0D01*
G02X1346986Y842743I1298J0D01*
G01X1347081Y842761D01*
X1347922Y844356D01*
X1347883Y844444D01*
G02X1347772Y844971I1186J525D01*
G37*
G36*
G01X1355172D02*
G02X1357766I1297J0D01*
G02X1356704Y843695I-1298J0D01*
G01X1356609Y843677D01*
X1355768Y842082D01*
X1355807Y841994D01*
G02X1355918Y841467I-1186J-525D01*
G02X1353324I-1297J0D01*
G02X1354386Y842743I1298J0D01*
G01X1354481Y842761D01*
X1355322Y844356D01*
X1355283Y844444D01*
G02X1355172Y844971I1186J525D01*
G37*
G36*
G01X1362572D02*
G02X1365166I1297J0D01*
G02X1364104Y843695I-1298J0D01*
G01X1364009Y843677D01*
X1363168Y842082D01*
X1363207Y841994D01*
G02X1363318Y841467I-1186J-525D01*
G02X1360724I-1297J0D01*
G02X1361786Y842743I1298J0D01*
G01X1361881Y842761D01*
X1362722Y844356D01*
X1362683Y844444D01*
G02X1362572Y844971I1186J525D01*
G37*
G36*
G01X1369972D02*
G02X1372566I1297J0D01*
G02X1371504Y843695I-1298J0D01*
G01X1371409Y843677D01*
X1370568Y842082D01*
X1370607Y841994D01*
G02X1370718Y841467I-1186J-525D01*
G02X1368124I-1297J0D01*
G02X1369186Y842743I1298J0D01*
G01X1369281Y842761D01*
X1370122Y844356D01*
X1370083Y844444D01*
G02X1369972Y844971I1186J525D01*
G37*
G36*
G01X1377372D02*
G02X1379966I1297J0D01*
G02X1378904Y843695I-1298J0D01*
G01X1378809Y843677D01*
X1377968Y842082D01*
X1378007Y841994D01*
G02X1378118Y841467I-1186J-525D01*
G02X1375524I-1297J0D01*
G02X1376586Y842743I1298J0D01*
G01X1376681Y842761D01*
X1377522Y844356D01*
X1377483Y844444D01*
G02X1377372Y844971I1186J525D01*
G37*
G36*
G01X1384772D02*
G02X1387366I1297J0D01*
G02X1386304Y843695I-1298J0D01*
G01X1386209Y843677D01*
X1385368Y842082D01*
X1385407Y841994D01*
G02X1385518Y841467I-1186J-525D01*
G02X1382924I-1297J0D01*
G02X1383986Y842743I1298J0D01*
G01X1384081Y842761D01*
X1384922Y844356D01*
X1384883Y844444D01*
G02X1384772Y844971I1186J525D01*
G37*
G36*
G01X1392172D02*
G02X1394766I1297J0D01*
G02X1393704Y843695I-1298J0D01*
G01X1393609Y843677D01*
X1392768Y842082D01*
X1392807Y841994D01*
G02X1392918Y841467I-1186J-525D01*
G02X1390324I-1297J0D01*
G02X1391386Y842743I1298J0D01*
G01X1391481Y842761D01*
X1392322Y844356D01*
X1392283Y844444D01*
G02X1392172Y844971I1186J525D01*
G37*
G36*
G01X1399572D02*
G02X1402166I1297J0D01*
G02X1401104Y843695I-1298J0D01*
G01X1401009Y843677D01*
X1400168Y842082D01*
X1400207Y841994D01*
G02X1400318Y841467I-1186J-525D01*
G02X1397724I-1297J0D01*
G02X1398786Y842743I1298J0D01*
G01X1398881Y842761D01*
X1399722Y844356D01*
X1399683Y844444D01*
G02X1399572Y844971I1186J525D01*
G37*
G36*
G01X351280Y848176D02*
G02X353876I1298J0D01*
G02X353803Y847747I-1297J0D01*
G01X353772Y847661D01*
X354579Y846263D01*
X354669Y846246D01*
G02X355724Y844971I-243J-1275D01*
G02X353130I-1297J0D01*
G02X353202Y845400I1297J3D01*
G01X353233Y845486D01*
X352426Y846884D01*
X352336Y846901D01*
G02X351280Y848176I242J1275D01*
G37*
G36*
G01X358680D02*
G02X361276I1298J0D01*
G02X361203Y847747I-1297J0D01*
G01X361172Y847661D01*
X361979Y846263D01*
X362069Y846246D01*
G02X363124Y844971I-243J-1275D01*
G02X360530I-1297J0D01*
G02X360602Y845400I1297J3D01*
G01X360633Y845486D01*
X359826Y846884D01*
X359736Y846901D01*
G02X358680Y848176I242J1275D01*
G37*
G36*
G01X366080D02*
G02X368676I1298J0D01*
G02X368603Y847747I-1297J0D01*
G01X368572Y847661D01*
X369379Y846263D01*
X369469Y846246D01*
G02X370524Y844971I-243J-1275D01*
G02X367930I-1297J0D01*
G02X368002Y845400I1297J3D01*
G01X368033Y845486D01*
X367226Y846884D01*
X367136Y846901D01*
G02X366080Y848176I242J1275D01*
G37*
G36*
G01X373480D02*
G02X376076I1298J0D01*
G02X376003Y847747I-1297J0D01*
G01X375972Y847661D01*
X376779Y846263D01*
X376869Y846246D01*
G02X377924Y844971I-243J-1275D01*
G02X375330I-1297J0D01*
G02X375402Y845400I1297J3D01*
G01X375433Y845486D01*
X374626Y846884D01*
X374536Y846901D01*
G02X373480Y848176I242J1275D01*
G37*
G36*
G01X380880D02*
G02X383476I1298J0D01*
G02X383403Y847747I-1297J0D01*
G01X383372Y847661D01*
X384179Y846263D01*
X384269Y846246D01*
G02X385324Y844971I-243J-1275D01*
G02X382730I-1297J0D01*
G02X382802Y845400I1297J3D01*
G01X382833Y845486D01*
X382026Y846884D01*
X381936Y846901D01*
G02X380880Y848176I242J1275D01*
G37*
G36*
G01X388280D02*
G02X390876I1298J0D01*
G02X390803Y847747I-1297J0D01*
G01X390772Y847661D01*
X391579Y846263D01*
X391669Y846246D01*
G02X392724Y844971I-243J-1275D01*
G02X390130I-1297J0D01*
G02X390202Y845400I1297J3D01*
G01X390233Y845486D01*
X389426Y846884D01*
X389336Y846901D01*
G02X388280Y848176I242J1275D01*
G37*
G36*
G01X395680D02*
G02X398276I1298J0D01*
G02X398203Y847747I-1297J0D01*
G01X398172Y847661D01*
X398979Y846263D01*
X399069Y846246D01*
G02X400124Y844971I-243J-1275D01*
G02X397530I-1297J0D01*
G02X397602Y845400I1297J3D01*
G01X397633Y845486D01*
X396826Y846884D01*
X396736Y846901D01*
G02X395680Y848176I242J1275D01*
G37*
G36*
G01X403080D02*
G02X405676I1298J0D01*
G02X405603Y847747I-1297J0D01*
G01X405572Y847661D01*
X406379Y846263D01*
X406469Y846246D01*
G02X407524Y844971I-243J-1275D01*
G02X404930I-1297J0D01*
G02X405002Y845400I1297J3D01*
G01X405033Y845486D01*
X404226Y846884D01*
X404136Y846901D01*
G02X403080Y848176I242J1275D01*
G37*
G36*
G01X410480D02*
G02X413076I1298J0D01*
G02X413003Y847747I-1297J0D01*
G01X412972Y847661D01*
X413779Y846263D01*
X413869Y846246D01*
G02X414924Y844971I-243J-1275D01*
G02X412330I-1297J0D01*
G02X412402Y845400I1297J3D01*
G01X412433Y845486D01*
X411626Y846884D01*
X411536Y846901D01*
G02X410480Y848176I242J1275D01*
G37*
G36*
G01X417880D02*
G02X420476I1298J0D01*
G02X420403Y847747I-1297J0D01*
G01X420372Y847661D01*
X421179Y846263D01*
X421269Y846246D01*
G02X422324Y844971I-243J-1275D01*
G02X419730I-1297J0D01*
G02X419802Y845400I1297J3D01*
G01X419833Y845486D01*
X419026Y846884D01*
X418936Y846901D01*
G02X417880Y848176I242J1275D01*
G37*
G36*
G01X425280D02*
G02X427876I1298J0D01*
G02X427803Y847747I-1297J0D01*
G01X427772Y847661D01*
X428579Y846263D01*
X428669Y846246D01*
G02X429724Y844971I-243J-1275D01*
G02X427130I-1297J0D01*
G02X427202Y845400I1297J3D01*
G01X427233Y845486D01*
X426426Y846884D01*
X426336Y846901D01*
G02X425280Y848176I242J1275D01*
G37*
G36*
G01X430278Y849474D02*
G02X431317Y848954I0J-1298D01*
G01X432939D01*
G02X433978Y849474I1039J-778D01*
G02Y846878I0J-1298D01*
G02X432939Y847398I0J1298D01*
G01X431317D01*
G02X430278Y846878I-1039J778D01*
G02Y849474I0J1298D01*
G37*
G36*
G01X436380Y848176D02*
G02X438976I1298J0D01*
G02X437913Y846900I-1297J0D01*
G01X437818Y846882D01*
X436976Y845286D01*
X437015Y845197D01*
G02X437126Y844673I-1186J-525D01*
G01Y844671D01*
G02X434532I-1297J0D01*
G02X435594Y845947I1298J0D01*
G01X435689Y845965D01*
X436531Y847561D01*
X436492Y847650D01*
G02X436380Y848176I1186J527D01*
G37*
G36*
G01X447480D02*
G02X450076I1298J0D01*
G02X450003Y847748I-1298J1D01*
G01X449972Y847661D01*
X450780Y846263D01*
X450870Y846246D01*
G02X451926Y844971I-242J-1275D01*
G02X449330I-1298J0D01*
G02X449403Y845399I1298J-1D01*
G01X449434Y845486D01*
X448626Y846884D01*
X448536Y846901D01*
G02X447480Y848176I242J1275D01*
G37*
G36*
G01X454880D02*
G02X457476I1298J0D01*
G02X457403Y847747I-1297J0D01*
G01X457372Y847661D01*
X458179Y846263D01*
X458269Y846246D01*
G02X459324Y844971I-243J-1275D01*
G02X456730I-1297J0D01*
G02X456802Y845400I1297J3D01*
G01X456833Y845486D01*
X456026Y846884D01*
X455936Y846901D01*
G02X454880Y848176I242J1275D01*
G37*
G36*
G01X462280D02*
G02X464876I1298J0D01*
G02X464803Y847747I-1297J0D01*
G01X464772Y847661D01*
X465579Y846263D01*
X465669Y846246D01*
G02X466724Y844971I-243J-1275D01*
G02X464130I-1297J0D01*
G02X464202Y845400I1297J3D01*
G01X464233Y845486D01*
X463426Y846884D01*
X463336Y846901D01*
G02X462280Y848176I242J1275D01*
G37*
G36*
G01X469680D02*
G02X472276I1298J0D01*
G02X472203Y847747I-1297J0D01*
G01X472172Y847661D01*
X472979Y846263D01*
X473069Y846246D01*
G02X474124Y844971I-243J-1275D01*
G02X471530I-1297J0D01*
G02X471602Y845400I1297J3D01*
G01X471633Y845486D01*
X470826Y846884D01*
X470736Y846901D01*
G02X469680Y848176I242J1275D01*
G37*
G36*
G01X477080D02*
G02X479676I1298J0D01*
G02X479603Y847747I-1297J0D01*
G01X479572Y847661D01*
X480379Y846263D01*
X480469Y846246D01*
G02X481524Y844971I-243J-1275D01*
G02X478930I-1297J0D01*
G02X479002Y845400I1297J3D01*
G01X479033Y845486D01*
X478226Y846884D01*
X478136Y846901D01*
G02X477080Y848176I242J1275D01*
G37*
G36*
G01X484480D02*
G02X487076I1298J0D01*
G02X487003Y847747I-1297J0D01*
G01X486972Y847661D01*
X487779Y846263D01*
X487869Y846246D01*
G02X488924Y844971I-243J-1275D01*
G02X486330I-1297J0D01*
G02X486402Y845400I1297J3D01*
G01X486433Y845486D01*
X485626Y846884D01*
X485536Y846901D01*
G02X484480Y848176I242J1275D01*
G37*
G36*
G01X491880D02*
G02X494476I1298J0D01*
G02X494403Y847747I-1297J0D01*
G01X494372Y847661D01*
X495179Y846263D01*
X495269Y846246D01*
G02X496324Y844971I-243J-1275D01*
G02X493730I-1297J0D01*
G02X493802Y845400I1297J3D01*
G01X493833Y845486D01*
X493026Y846884D01*
X492936Y846901D01*
G02X491880Y848176I242J1275D01*
G37*
G36*
G01X499280D02*
G02X501876I1298J0D01*
G02X501803Y847747I-1297J0D01*
G01X501772Y847661D01*
X502579Y846263D01*
X502669Y846246D01*
G02X503724Y844971I-243J-1275D01*
G02X501130I-1297J0D01*
G02X501202Y845400I1297J3D01*
G01X501233Y845486D01*
X500426Y846884D01*
X500336Y846901D01*
G02X499280Y848176I242J1275D01*
G37*
G36*
G01X506680D02*
G02X509276I1298J0D01*
G02X509203Y847747I-1297J0D01*
G01X509172Y847661D01*
X509979Y846263D01*
X510069Y846246D01*
G02X511124Y844971I-243J-1275D01*
G02X508530I-1297J0D01*
G02X508602Y845400I1297J3D01*
G01X508633Y845486D01*
X507826Y846884D01*
X507736Y846901D01*
G02X506680Y848176I242J1275D01*
G37*
G36*
G01X514080D02*
G02X516676I1298J0D01*
G02X516603Y847747I-1297J0D01*
G01X516572Y847661D01*
X517379Y846263D01*
X517469Y846246D01*
G02X518524Y844971I-243J-1275D01*
G02X515930I-1297J0D01*
G02X516002Y845400I1297J3D01*
G01X516033Y845486D01*
X515226Y846884D01*
X515136Y846901D01*
G02X514080Y848176I242J1275D01*
G37*
G36*
G01X521480D02*
G02X524076I1298J0D01*
G02X524003Y847747I-1297J0D01*
G01X523972Y847661D01*
X524779Y846263D01*
X524869Y846246D01*
G02X525924Y844971I-243J-1275D01*
G02X523330I-1297J0D01*
G02X523402Y845400I1297J3D01*
G01X523433Y845486D01*
X522626Y846884D01*
X522536Y846901D01*
G02X521480Y848176I242J1275D01*
G37*
G36*
G01X526478Y849474D02*
G02X527517Y848954I0J-1298D01*
G01X529139D01*
G02X530178Y849474I1039J-778D01*
G02Y846878I0J-1298D01*
G02X529139Y847398I0J1298D01*
G01X527517D01*
G02X526478Y846878I-1039J778D01*
G02Y849474I0J1298D01*
G37*
G36*
G01X532580Y848176D02*
G02X535176I1298J0D01*
G02X534168Y846911I-1298J0D01*
G01X534079Y846891D01*
X533202Y845231D01*
X533236Y845145D01*
G02X533326Y844671I-1208J-475D01*
G02X530730I-1298J0D01*
G02X531738Y845936I1298J0D01*
G01X531827Y845956D01*
X532704Y847616D01*
X532670Y847702D01*
G02X532580Y848176I1208J475D01*
G37*
G36*
G01X1327422D02*
G02X1330018I1298J0D01*
G02X1329945Y847747I-1297J0D01*
G01X1329914Y847661D01*
X1330721Y846263D01*
X1330811Y846246D01*
G02X1331866Y844971I-243J-1275D01*
G02X1329272I-1297J0D01*
G02X1329344Y845400I1297J3D01*
G01X1329375Y845486D01*
X1328568Y846884D01*
X1328478Y846901D01*
G02X1327422Y848176I242J1275D01*
G37*
G36*
G01X1334822D02*
G02X1337418I1298J0D01*
G02X1337345Y847747I-1297J0D01*
G01X1337314Y847661D01*
X1338121Y846263D01*
X1338211Y846246D01*
G02X1339266Y844971I-243J-1275D01*
G02X1336672I-1297J0D01*
G02X1336744Y845400I1297J3D01*
G01X1336775Y845486D01*
X1335968Y846884D01*
X1335878Y846901D01*
G02X1334822Y848176I242J1275D01*
G37*
G36*
G01X1342222D02*
G02X1344818I1298J0D01*
G02X1344745Y847747I-1297J0D01*
G01X1344714Y847661D01*
X1345521Y846263D01*
X1345611Y846246D01*
G02X1346666Y844971I-243J-1275D01*
G02X1344072I-1297J0D01*
G02X1344144Y845400I1297J3D01*
G01X1344175Y845486D01*
X1343368Y846884D01*
X1343278Y846901D01*
G02X1342222Y848176I242J1275D01*
G37*
G36*
G01X1349622D02*
G02X1352218I1298J0D01*
G02X1352145Y847747I-1297J0D01*
G01X1352114Y847661D01*
X1352921Y846263D01*
X1353011Y846246D01*
G02X1354066Y844971I-243J-1275D01*
G02X1351472I-1297J0D01*
G02X1351544Y845400I1297J3D01*
G01X1351575Y845486D01*
X1350768Y846884D01*
X1350678Y846901D01*
G02X1349622Y848176I242J1275D01*
G37*
G36*
G01X1357022D02*
G02X1359618I1298J0D01*
G02X1359545Y847747I-1297J0D01*
G01X1359514Y847661D01*
X1360321Y846263D01*
X1360411Y846246D01*
G02X1361466Y844971I-243J-1275D01*
G02X1358872I-1297J0D01*
G02X1358944Y845400I1297J3D01*
G01X1358975Y845486D01*
X1358168Y846884D01*
X1358078Y846901D01*
G02X1357022Y848176I242J1275D01*
G37*
G36*
G01X1364422D02*
G02X1367018I1298J0D01*
G02X1366945Y847747I-1297J0D01*
G01X1366914Y847661D01*
X1367721Y846263D01*
X1367811Y846246D01*
G02X1368866Y844971I-243J-1275D01*
G02X1366272I-1297J0D01*
G02X1366344Y845400I1297J3D01*
G01X1366375Y845486D01*
X1365568Y846884D01*
X1365478Y846901D01*
G02X1364422Y848176I242J1275D01*
G37*
G36*
G01X1371822D02*
G02X1374418I1298J0D01*
G02X1374345Y847747I-1297J0D01*
G01X1374314Y847661D01*
X1375121Y846263D01*
X1375211Y846246D01*
G02X1376266Y844971I-243J-1275D01*
G02X1373672I-1297J0D01*
G02X1373744Y845400I1297J3D01*
G01X1373775Y845486D01*
X1372968Y846884D01*
X1372878Y846901D01*
G02X1371822Y848176I242J1275D01*
G37*
G36*
G01X1379222D02*
G02X1381818I1298J0D01*
G02X1381745Y847747I-1297J0D01*
G01X1381714Y847661D01*
X1382521Y846263D01*
X1382611Y846246D01*
G02X1383666Y844971I-243J-1275D01*
G02X1381072I-1297J0D01*
G02X1381144Y845400I1297J3D01*
G01X1381175Y845486D01*
X1380368Y846884D01*
X1380278Y846901D01*
G02X1379222Y848176I242J1275D01*
G37*
G36*
G01X1386622D02*
G02X1389218I1298J0D01*
G02X1389145Y847747I-1297J0D01*
G01X1389114Y847661D01*
X1389921Y846263D01*
X1390011Y846246D01*
G02X1391066Y844971I-243J-1275D01*
G02X1388472I-1297J0D01*
G02X1388544Y845400I1297J3D01*
G01X1388575Y845486D01*
X1387768Y846884D01*
X1387678Y846901D01*
G02X1386622Y848176I242J1275D01*
G37*
G36*
G01X1394022D02*
G02X1396618I1298J0D01*
G02X1396545Y847747I-1297J0D01*
G01X1396514Y847661D01*
X1397321Y846263D01*
X1397411Y846246D01*
G02X1398466Y844971I-243J-1275D01*
G02X1395872I-1297J0D01*
G02X1395944Y845400I1297J3D01*
G01X1395975Y845486D01*
X1395168Y846884D01*
X1395078Y846901D01*
G02X1394022Y848176I242J1275D01*
G37*
G36*
G01X1401422D02*
G02X1404018I1298J0D01*
G02X1403945Y847747I-1297J0D01*
G01X1403914Y847661D01*
X1404721Y846263D01*
X1404811Y846246D01*
G02X1405866Y844971I-243J-1275D01*
G02X1403272I-1297J0D01*
G02X1403344Y845400I1297J3D01*
G01X1403375Y845486D01*
X1402568Y846884D01*
X1402478Y846901D01*
G02X1401422Y848176I242J1275D01*
G37*
G36*
G01X1406420Y849474D02*
G02X1407459Y848954I0J-1298D01*
G01X1409081D01*
G02X1410120Y849474I1039J-778D01*
G02Y846878I0J-1298D01*
G02X1409081Y847398I0J1298D01*
G01X1407459D01*
G02X1406420Y846878I-1039J778D01*
G02Y849474I0J1298D01*
G37*
G36*
G01X1412522Y848176D02*
G02X1415118I1298J0D01*
G02X1414062Y846901I-1298J0D01*
G01X1413972Y846884D01*
X1413164Y845485D01*
X1413194Y845398D01*
G02X1413266Y844973I-1225J-426D01*
G01Y844971D01*
G02X1410672I-1297J0D01*
G02X1411728Y846246I1298J0D01*
G01X1411818Y846263D01*
X1412625Y847662D01*
X1412595Y847748D01*
G02X1412522Y848176I1225J429D01*
G37*
G36*
G01X349430Y851380D02*
G02X352024I1297J0D01*
G02X350969Y850105I-1298J0D01*
G01X350879Y850088D01*
X350072Y848691D01*
X350103Y848604D01*
G02X350176Y848176I-1225J-429D01*
G02X347580I-1298J0D01*
G02X348636Y849451I1298J0D01*
G01X348726Y849468D01*
X349533Y850865D01*
X349502Y850952D01*
G02X349430Y851380I1225J426D01*
G37*
G36*
G01X1325572D02*
G02X1328166I1297J0D01*
G02X1327111Y850105I-1298J0D01*
G01X1327021Y850088D01*
X1326214Y848691D01*
X1326245Y848604D01*
G02X1326318Y848176I-1225J-429D01*
G02X1323722I-1298J0D01*
G02X1324778Y849451I1298J0D01*
G01X1324868Y849468D01*
X1325675Y850865D01*
X1325644Y850952D01*
G02X1325572Y851380I1225J426D01*
G37*
G36*
G01X353132Y857789D02*
G02X355726I1297J0D01*
G02X355654Y857360I-1297J-3D01*
G01X355623Y857274D01*
X356430Y855876D01*
X356520Y855859D01*
G02X357576Y854584I-242J-1275D01*
G02X354980I-1298J0D01*
G02X355053Y855013I1297J0D01*
G01X355084Y855099D01*
X354277Y856497D01*
X354187Y856514D01*
G02X353132Y857789I243J1275D01*
G37*
G36*
G01X360532D02*
G02X363126I1297J0D01*
G02X363054Y857360I-1297J-3D01*
G01X363023Y857274D01*
X363830Y855876D01*
X363920Y855859D01*
G02X364976Y854584I-242J-1275D01*
G02X362380I-1298J0D01*
G02X362453Y855013I1297J0D01*
G01X362484Y855099D01*
X361677Y856497D01*
X361587Y856514D01*
G02X360532Y857789I243J1275D01*
G37*
G36*
G01X367932D02*
G02X370526I1297J0D01*
G02X370454Y857360I-1297J-3D01*
G01X370423Y857274D01*
X371230Y855876D01*
X371320Y855859D01*
G02X372376Y854584I-242J-1275D01*
G02X369780I-1298J0D01*
G02X369853Y855013I1297J0D01*
G01X369884Y855099D01*
X369077Y856497D01*
X368987Y856514D01*
G02X367932Y857789I243J1275D01*
G37*
G36*
G01X375332D02*
G02X377926I1297J0D01*
G02X377854Y857360I-1297J-3D01*
G01X377823Y857274D01*
X378630Y855876D01*
X378720Y855859D01*
G02X379776Y854584I-242J-1275D01*
G02X377180I-1298J0D01*
G02X377253Y855013I1297J0D01*
G01X377284Y855099D01*
X376477Y856497D01*
X376387Y856514D01*
G02X375332Y857789I243J1275D01*
G37*
G36*
G01X382732D02*
G02X385326I1297J0D01*
G02X385254Y857360I-1297J-3D01*
G01X385223Y857274D01*
X386030Y855876D01*
X386120Y855859D01*
G02X387176Y854584I-242J-1275D01*
G02X384580I-1298J0D01*
G02X384653Y855013I1297J0D01*
G01X384684Y855099D01*
X383877Y856497D01*
X383787Y856514D01*
G02X382732Y857789I243J1275D01*
G37*
G36*
G01X390132D02*
G02X392726I1297J0D01*
G02X392654Y857360I-1297J-3D01*
G01X392623Y857274D01*
X393430Y855876D01*
X393520Y855859D01*
G02X394576Y854584I-242J-1275D01*
G02X391980I-1298J0D01*
G02X392053Y855013I1297J0D01*
G01X392084Y855099D01*
X391277Y856497D01*
X391187Y856514D01*
G02X390132Y857789I243J1275D01*
G37*
G36*
G01X397532D02*
G02X400126I1297J0D01*
G02X400054Y857360I-1297J-3D01*
G01X400023Y857274D01*
X400830Y855876D01*
X400920Y855859D01*
G02X401976Y854584I-242J-1275D01*
G02X399380I-1298J0D01*
G02X399453Y855013I1297J0D01*
G01X399484Y855099D01*
X398677Y856497D01*
X398587Y856514D01*
G02X397532Y857789I243J1275D01*
G37*
G36*
G01X404932D02*
G02X407526I1297J0D01*
G02X407454Y857360I-1297J-3D01*
G01X407423Y857274D01*
X408230Y855876D01*
X408320Y855859D01*
G02X409376Y854584I-242J-1275D01*
G02X406780I-1298J0D01*
G02X406853Y855013I1297J0D01*
G01X406884Y855099D01*
X406077Y856497D01*
X405987Y856514D01*
G02X404932Y857789I243J1275D01*
G37*
G36*
G01X412332D02*
G02X414926I1297J0D01*
G02X414854Y857360I-1297J-3D01*
G01X414823Y857274D01*
X415630Y855876D01*
X415720Y855859D01*
G02X416776Y854584I-242J-1275D01*
G02X414180I-1298J0D01*
G02X414253Y855013I1297J0D01*
G01X414284Y855099D01*
X413477Y856497D01*
X413387Y856514D01*
G02X412332Y857789I243J1275D01*
G37*
G36*
G01X419732D02*
G02X422326I1297J0D01*
G02X422254Y857360I-1297J-3D01*
G01X422223Y857274D01*
X423030Y855876D01*
X423120Y855859D01*
G02X424176Y854584I-242J-1275D01*
G02X421580I-1298J0D01*
G02X421653Y855013I1297J0D01*
G01X421684Y855099D01*
X420877Y856497D01*
X420787Y856514D01*
G02X419732Y857789I243J1275D01*
G37*
G36*
G01X427132D02*
G02X429726I1297J0D01*
G02X429654Y857360I-1297J-3D01*
G01X429623Y857274D01*
X430430Y855876D01*
X430520Y855859D01*
G02X431576Y854584I-242J-1275D01*
G02X428980I-1298J0D01*
G02X429053Y855013I1297J0D01*
G01X429084Y855099D01*
X428277Y856497D01*
X428187Y856514D01*
G02X427132Y857789I243J1275D01*
G37*
G36*
G01X434532D02*
G02X437126I1297J0D01*
G02X437054Y857360I-1297J-3D01*
G01X437023Y857274D01*
X437830Y855876D01*
X437920Y855859D01*
G02X438976Y854584I-242J-1275D01*
G02X436382I-1297J0D01*
G02X436454Y855012I1297J2D01*
G01X436484Y855098D01*
X435677Y856497D01*
X435587Y856514D01*
G02X434532Y857789I243J1275D01*
G37*
G36*
G01X445632D02*
G02X448226I1297J0D01*
G02X447171Y856514I-1298J0D01*
G01X447081Y856497D01*
X446273Y855098D01*
X446303Y855011D01*
G02X446376Y854584I-1225J-429D01*
G02X443780I-1298J0D01*
G02X444838Y855859I1297J0D01*
G01X444928Y855876D01*
X445735Y857274D01*
X445704Y857361D01*
G02X445632Y857789I1225J426D01*
G37*
G36*
G01X453032D02*
G02X455626I1297J0D01*
G02X454571Y856514I-1298J0D01*
G01X454481Y856497D01*
X453673Y855098D01*
X453703Y855011D01*
G02X453776Y854584I-1225J-429D01*
G02X451180I-1298J0D01*
G02X452238Y855859I1297J0D01*
G01X452328Y855876D01*
X453135Y857274D01*
X453104Y857361D01*
G02X453032Y857789I1225J426D01*
G37*
G36*
G01X460432D02*
G02X463026I1297J0D01*
G02X461971Y856514I-1298J0D01*
G01X461881Y856497D01*
X461073Y855098D01*
X461103Y855011D01*
G02X461176Y854584I-1225J-429D01*
G02X458580I-1298J0D01*
G02X459638Y855859I1297J0D01*
G01X459728Y855876D01*
X460535Y857274D01*
X460504Y857361D01*
G02X460432Y857789I1225J426D01*
G37*
G36*
G01X467832D02*
G02X470426I1297J0D01*
G02X469371Y856514I-1298J0D01*
G01X469281Y856497D01*
X468473Y855098D01*
X468503Y855011D01*
G02X468576Y854584I-1225J-429D01*
G02X465980I-1298J0D01*
G02X467038Y855859I1297J0D01*
G01X467128Y855876D01*
X467935Y857274D01*
X467904Y857361D01*
G02X467832Y857789I1225J426D01*
G37*
G36*
G01X475232D02*
G02X477826I1297J0D01*
G02X476771Y856514I-1298J0D01*
G01X476681Y856497D01*
X475873Y855098D01*
X475903Y855011D01*
G02X475976Y854584I-1225J-429D01*
G02X473380I-1298J0D01*
G02X474438Y855859I1297J0D01*
G01X474528Y855876D01*
X475335Y857274D01*
X475304Y857361D01*
G02X475232Y857789I1225J426D01*
G37*
G36*
G01X482632D02*
G02X485226I1297J0D01*
G02X484171Y856514I-1298J0D01*
G01X484081Y856497D01*
X483273Y855098D01*
X483303Y855011D01*
G02X483376Y854584I-1225J-429D01*
G02X480780I-1298J0D01*
G02X481838Y855859I1297J0D01*
G01X481928Y855876D01*
X482735Y857274D01*
X482704Y857361D01*
G02X482632Y857789I1225J426D01*
G37*
G36*
G01X490032D02*
G02X492626I1297J0D01*
G02X491571Y856514I-1298J0D01*
G01X491481Y856497D01*
X490673Y855098D01*
X490703Y855011D01*
G02X490776Y854584I-1225J-429D01*
G02X488180I-1298J0D01*
G02X489238Y855859I1297J0D01*
G01X489328Y855876D01*
X490135Y857274D01*
X490104Y857361D01*
G02X490032Y857789I1225J426D01*
G37*
G36*
G01X497432D02*
G02X500026I1297J0D01*
G02X498971Y856514I-1298J0D01*
G01X498881Y856497D01*
X498073Y855098D01*
X498103Y855011D01*
G02X498176Y854584I-1225J-429D01*
G02X495580I-1298J0D01*
G02X496638Y855859I1297J0D01*
G01X496728Y855876D01*
X497535Y857274D01*
X497504Y857361D01*
G02X497432Y857789I1225J426D01*
G37*
G36*
G01X504832D02*
G02X507426I1297J0D01*
G02X506371Y856514I-1298J0D01*
G01X506281Y856497D01*
X505473Y855098D01*
X505503Y855011D01*
G02X505576Y854584I-1225J-429D01*
G02X502980I-1298J0D01*
G02X504038Y855859I1297J0D01*
G01X504128Y855876D01*
X504935Y857274D01*
X504904Y857361D01*
G02X504832Y857789I1225J426D01*
G37*
G36*
G01X512232D02*
G02X514826I1297J0D01*
G02X513771Y856514I-1298J0D01*
G01X513681Y856497D01*
X512873Y855098D01*
X512903Y855011D01*
G02X512976Y854584I-1225J-429D01*
G02X510380I-1298J0D01*
G02X511438Y855859I1297J0D01*
G01X511528Y855876D01*
X512335Y857274D01*
X512304Y857361D01*
G02X512232Y857789I1225J426D01*
G37*
G36*
G01X519632D02*
G02X522226I1297J0D01*
G02X521171Y856514I-1298J0D01*
G01X521081Y856497D01*
X520273Y855098D01*
X520303Y855011D01*
G02X520376Y854584I-1225J-429D01*
G02X517780I-1298J0D01*
G02X518838Y855859I1297J0D01*
G01X518928Y855876D01*
X519735Y857274D01*
X519704Y857361D01*
G02X519632Y857789I1225J426D01*
G37*
G36*
G01X527032D02*
G02X529626I1297J0D01*
G02X528571Y856514I-1298J0D01*
G01X528481Y856497D01*
X527673Y855098D01*
X527703Y855011D01*
G02X527776Y854584I-1225J-429D01*
G02X525180I-1298J0D01*
G02X526238Y855859I1297J0D01*
G01X526328Y855876D01*
X527135Y857274D01*
X527104Y857361D01*
G02X527032Y857789I1225J426D01*
G37*
G36*
G01X1329274D02*
G02X1331868I1297J0D01*
G02X1331796Y857360I-1297J-3D01*
G01X1331765Y857274D01*
X1332572Y855876D01*
X1332662Y855859D01*
G02X1333718Y854584I-242J-1275D01*
G02X1331122I-1298J0D01*
G02X1331195Y855013I1297J0D01*
G01X1331226Y855099D01*
X1330419Y856497D01*
X1330329Y856514D01*
G02X1329274Y857789I243J1275D01*
G37*
G36*
G01X1336674D02*
G02X1339268I1297J0D01*
G02X1339196Y857360I-1297J-3D01*
G01X1339165Y857274D01*
X1339972Y855876D01*
X1340062Y855859D01*
G02X1341118Y854584I-242J-1275D01*
G02X1338522I-1298J0D01*
G02X1338595Y855013I1297J0D01*
G01X1338626Y855099D01*
X1337819Y856497D01*
X1337729Y856514D01*
G02X1336674Y857789I243J1275D01*
G37*
G36*
G01X1344074D02*
G02X1346668I1297J0D01*
G02X1346596Y857360I-1297J-3D01*
G01X1346565Y857274D01*
X1347372Y855876D01*
X1347462Y855859D01*
G02X1348518Y854584I-242J-1275D01*
G02X1345922I-1298J0D01*
G02X1345995Y855013I1297J0D01*
G01X1346026Y855099D01*
X1345219Y856497D01*
X1345129Y856514D01*
G02X1344074Y857789I243J1275D01*
G37*
G36*
G01X1351474D02*
G02X1354068I1297J0D01*
G02X1353996Y857360I-1297J-3D01*
G01X1353965Y857274D01*
X1354772Y855876D01*
X1354862Y855859D01*
G02X1355918Y854584I-242J-1275D01*
G02X1353322I-1298J0D01*
G02X1353395Y855013I1297J0D01*
G01X1353426Y855099D01*
X1352619Y856497D01*
X1352529Y856514D01*
G02X1351474Y857789I243J1275D01*
G37*
G36*
G01X1358874D02*
G02X1361468I1297J0D01*
G02X1361396Y857360I-1297J-3D01*
G01X1361365Y857274D01*
X1362172Y855876D01*
X1362262Y855859D01*
G02X1363318Y854584I-242J-1275D01*
G02X1360722I-1298J0D01*
G02X1360795Y855013I1297J0D01*
G01X1360826Y855099D01*
X1360019Y856497D01*
X1359929Y856514D01*
G02X1358874Y857789I243J1275D01*
G37*
G36*
G01X1366274D02*
G02X1368868I1297J0D01*
G02X1368796Y857360I-1297J-3D01*
G01X1368765Y857274D01*
X1369572Y855876D01*
X1369662Y855859D01*
G02X1370718Y854584I-242J-1275D01*
G02X1368122I-1298J0D01*
G02X1368195Y855013I1297J0D01*
G01X1368226Y855099D01*
X1367419Y856497D01*
X1367329Y856514D01*
G02X1366274Y857789I243J1275D01*
G37*
G36*
G01X1373674D02*
G02X1376268I1297J0D01*
G02X1376196Y857360I-1297J-3D01*
G01X1376165Y857274D01*
X1376972Y855876D01*
X1377062Y855859D01*
G02X1378118Y854584I-242J-1275D01*
G02X1375522I-1298J0D01*
G02X1375595Y855013I1297J0D01*
G01X1375626Y855099D01*
X1374819Y856497D01*
X1374729Y856514D01*
G02X1373674Y857789I243J1275D01*
G37*
G36*
G01X1381074D02*
G02X1383668I1297J0D01*
G02X1383596Y857360I-1297J-3D01*
G01X1383565Y857274D01*
X1384372Y855876D01*
X1384462Y855859D01*
G02X1385518Y854584I-242J-1275D01*
G02X1382922I-1298J0D01*
G02X1382995Y855013I1297J0D01*
G01X1383026Y855099D01*
X1382219Y856497D01*
X1382129Y856514D01*
G02X1381074Y857789I243J1275D01*
G37*
G36*
G01X1388474D02*
G02X1391068I1297J0D01*
G02X1390996Y857360I-1297J-3D01*
G01X1390965Y857274D01*
X1391772Y855876D01*
X1391862Y855859D01*
G02X1392918Y854584I-242J-1275D01*
G02X1390322I-1298J0D01*
G02X1390395Y855013I1297J0D01*
G01X1390426Y855099D01*
X1389619Y856497D01*
X1389529Y856514D01*
G02X1388474Y857789I243J1275D01*
G37*
G36*
G01X1395874D02*
G02X1398468I1297J0D01*
G02X1398396Y857360I-1297J-3D01*
G01X1398365Y857274D01*
X1399172Y855876D01*
X1399262Y855859D01*
G02X1400318Y854584I-242J-1275D01*
G02X1397722I-1298J0D01*
G02X1397795Y855013I1297J0D01*
G01X1397826Y855099D01*
X1397019Y856497D01*
X1396929Y856514D01*
G02X1395874Y857789I243J1275D01*
G37*
G36*
G01X1403274D02*
G02X1405868I1297J0D01*
G02X1405796Y857360I-1297J-3D01*
G01X1405765Y857274D01*
X1406572Y855876D01*
X1406662Y855859D01*
G02X1407718Y854584I-242J-1275D01*
G02X1405122I-1298J0D01*
G02X1405195Y855013I1297J0D01*
G01X1405226Y855099D01*
X1404419Y856497D01*
X1404329Y856514D01*
G02X1403274Y857789I243J1275D01*
G37*
G36*
G01X1410674D02*
G02X1413268I1297J0D01*
G02X1413196Y857360I-1297J-3D01*
G01X1413165Y857274D01*
X1413972Y855876D01*
X1414062Y855859D01*
G02X1415118Y854584I-242J-1275D01*
G02X1412524I-1297J0D01*
G02X1412596Y855012I1297J2D01*
G01X1412626Y855098D01*
X1411819Y856497D01*
X1411729Y856514D01*
G02X1410674Y857789I243J1275D01*
G37*
G36*
G01X1421774D02*
G02X1424368I1297J0D01*
G02X1423313Y856514I-1298J0D01*
G01X1423223Y856497D01*
X1422415Y855098D01*
X1422445Y855011D01*
G02X1422518Y854584I-1225J-429D01*
G02X1419922I-1298J0D01*
G02X1420980Y855859I1297J0D01*
G01X1421070Y855876D01*
X1421877Y857274D01*
X1421846Y857361D01*
G02X1421774Y857789I1225J426D01*
G37*
G36*
G01X1429174D02*
G02X1431768I1297J0D01*
G02X1430713Y856514I-1298J0D01*
G01X1430623Y856497D01*
X1429815Y855098D01*
X1429845Y855011D01*
G02X1429918Y854584I-1225J-429D01*
G02X1427322I-1298J0D01*
G02X1428380Y855859I1297J0D01*
G01X1428470Y855876D01*
X1429277Y857274D01*
X1429246Y857361D01*
G02X1429174Y857789I1225J426D01*
G37*
G36*
G01X1436574D02*
G02X1439168I1297J0D01*
G02X1438113Y856514I-1298J0D01*
G01X1438023Y856497D01*
X1437215Y855098D01*
X1437245Y855011D01*
G02X1437318Y854584I-1225J-429D01*
G02X1434722I-1298J0D01*
G02X1435780Y855859I1297J0D01*
G01X1435870Y855876D01*
X1436677Y857274D01*
X1436646Y857361D01*
G02X1436574Y857789I1225J426D01*
G37*
G36*
G01X1443974D02*
G02X1446568I1297J0D01*
G02X1445513Y856514I-1298J0D01*
G01X1445423Y856497D01*
X1444615Y855098D01*
X1444645Y855011D01*
G02X1444718Y854584I-1225J-429D01*
G02X1442122I-1298J0D01*
G02X1443180Y855859I1297J0D01*
G01X1443270Y855876D01*
X1444077Y857274D01*
X1444046Y857361D01*
G02X1443974Y857789I1225J426D01*
G37*
G36*
G01X1451374D02*
G02X1453968I1297J0D01*
G02X1452913Y856514I-1298J0D01*
G01X1452823Y856497D01*
X1452015Y855098D01*
X1452045Y855011D01*
G02X1452118Y854584I-1225J-429D01*
G02X1449522I-1298J0D01*
G02X1450580Y855859I1297J0D01*
G01X1450670Y855876D01*
X1451477Y857274D01*
X1451446Y857361D01*
G02X1451374Y857789I1225J426D01*
G37*
G36*
G01X1458774D02*
G02X1461368I1297J0D01*
G02X1460313Y856514I-1298J0D01*
G01X1460223Y856497D01*
X1459415Y855098D01*
X1459445Y855011D01*
G02X1459518Y854584I-1225J-429D01*
G02X1456922I-1298J0D01*
G02X1457980Y855859I1297J0D01*
G01X1458070Y855876D01*
X1458877Y857274D01*
X1458846Y857361D01*
G02X1458774Y857789I1225J426D01*
G37*
G36*
G01X1466174D02*
G02X1468768I1297J0D01*
G02X1467713Y856514I-1298J0D01*
G01X1467623Y856497D01*
X1466815Y855098D01*
X1466845Y855011D01*
G02X1466918Y854584I-1225J-429D01*
G02X1464322I-1298J0D01*
G02X1465380Y855859I1297J0D01*
G01X1465470Y855876D01*
X1466277Y857274D01*
X1466246Y857361D01*
G02X1466174Y857789I1225J426D01*
G37*
G36*
G01X1473574D02*
G02X1476168I1297J0D01*
G02X1475113Y856514I-1298J0D01*
G01X1475023Y856497D01*
X1474215Y855098D01*
X1474245Y855011D01*
G02X1474318Y854584I-1225J-429D01*
G02X1471722I-1298J0D01*
G02X1472780Y855859I1297J0D01*
G01X1472870Y855876D01*
X1473677Y857274D01*
X1473646Y857361D01*
G02X1473574Y857789I1225J426D01*
G37*
G36*
G01X1480974D02*
G02X1483568I1297J0D01*
G02X1482513Y856514I-1298J0D01*
G01X1482423Y856497D01*
X1481615Y855098D01*
X1481645Y855011D01*
G02X1481718Y854584I-1225J-429D01*
G02X1479122I-1298J0D01*
G02X1480180Y855859I1297J0D01*
G01X1480270Y855876D01*
X1481077Y857274D01*
X1481046Y857361D01*
G02X1480974Y857789I1225J426D01*
G37*
G36*
G01X1488374D02*
G02X1490968I1297J0D01*
G02X1489913Y856514I-1298J0D01*
G01X1489823Y856497D01*
X1489015Y855098D01*
X1489045Y855011D01*
G02X1489118Y854584I-1225J-429D01*
G02X1486522I-1298J0D01*
G02X1487580Y855859I1297J0D01*
G01X1487670Y855876D01*
X1488477Y857274D01*
X1488446Y857361D01*
G02X1488374Y857789I1225J426D01*
G37*
G36*
G01X1495774D02*
G02X1498368I1297J0D01*
G02X1497313Y856514I-1298J0D01*
G01X1497223Y856497D01*
X1496415Y855098D01*
X1496445Y855011D01*
G02X1496518Y854584I-1225J-429D01*
G02X1493922I-1298J0D01*
G02X1494980Y855859I1297J0D01*
G01X1495070Y855876D01*
X1495877Y857274D01*
X1495846Y857361D01*
G02X1495774Y857789I1225J426D01*
G37*
G36*
G01X1503174D02*
G02X1505768I1297J0D01*
G02X1504713Y856514I-1298J0D01*
G01X1504623Y856497D01*
X1503815Y855098D01*
X1503845Y855011D01*
G02X1503918Y854584I-1225J-429D01*
G02X1501322I-1298J0D01*
G02X1502380Y855859I1297J0D01*
G01X1502470Y855876D01*
X1503277Y857274D01*
X1503246Y857361D01*
G02X1503174Y857789I1225J426D01*
G37*
G36*
G01X351280Y860993D02*
G02X353876I1298J0D01*
G02X352820Y859718I-1298J0D01*
G01X352730Y859701D01*
X351923Y858304D01*
X351954Y858217D01*
G02X352026Y857789I-1225J-426D01*
G02X349432I-1297J0D01*
G02X350487Y859064I1298J0D01*
G01X350577Y859081D01*
X351384Y860478D01*
X351353Y860565D01*
G02X351280Y860993I1225J429D01*
G37*
G36*
G01X358680D02*
G02X361276I1298J0D01*
G02X360220Y859718I-1298J0D01*
G01X360130Y859701D01*
X359323Y858304D01*
X359354Y858217D01*
G02X359426Y857789I-1225J-426D01*
G02X356832I-1297J0D01*
G02X357887Y859064I1298J0D01*
G01X357977Y859081D01*
X358784Y860478D01*
X358753Y860565D01*
G02X358680Y860993I1225J429D01*
G37*
G36*
G01X366080D02*
G02X368676I1298J0D01*
G02X367620Y859718I-1298J0D01*
G01X367530Y859701D01*
X366723Y858304D01*
X366754Y858217D01*
G02X366826Y857789I-1225J-426D01*
G02X364232I-1297J0D01*
G02X365287Y859064I1298J0D01*
G01X365377Y859081D01*
X366184Y860478D01*
X366153Y860565D01*
G02X366080Y860993I1225J429D01*
G37*
G36*
G01X373480D02*
G02X376076I1298J0D01*
G02X375020Y859718I-1298J0D01*
G01X374930Y859701D01*
X374123Y858304D01*
X374154Y858217D01*
G02X374226Y857789I-1225J-426D01*
G02X371632I-1297J0D01*
G02X372687Y859064I1298J0D01*
G01X372777Y859081D01*
X373584Y860478D01*
X373553Y860565D01*
G02X373480Y860993I1225J429D01*
G37*
G36*
G01X380880D02*
G02X383476I1298J0D01*
G02X382420Y859718I-1298J0D01*
G01X382330Y859701D01*
X381523Y858304D01*
X381554Y858217D01*
G02X381626Y857789I-1225J-426D01*
G02X379032I-1297J0D01*
G02X380087Y859064I1298J0D01*
G01X380177Y859081D01*
X380984Y860478D01*
X380953Y860565D01*
G02X380880Y860993I1225J429D01*
G37*
G36*
G01X388280D02*
G02X390876I1298J0D01*
G02X389820Y859718I-1298J0D01*
G01X389730Y859701D01*
X388923Y858304D01*
X388954Y858217D01*
G02X389026Y857789I-1225J-426D01*
G02X386432I-1297J0D01*
G02X387487Y859064I1298J0D01*
G01X387577Y859081D01*
X388384Y860478D01*
X388353Y860565D01*
G02X388280Y860993I1225J429D01*
G37*
G36*
G01X395680D02*
G02X398276I1298J0D01*
G02X397220Y859718I-1298J0D01*
G01X397130Y859701D01*
X396323Y858304D01*
X396354Y858217D01*
G02X396426Y857789I-1225J-426D01*
G02X393832I-1297J0D01*
G02X394887Y859064I1298J0D01*
G01X394977Y859081D01*
X395784Y860478D01*
X395753Y860565D01*
G02X395680Y860993I1225J429D01*
G37*
G36*
G01X403080D02*
G02X405676I1298J0D01*
G02X404620Y859718I-1298J0D01*
G01X404530Y859701D01*
X403723Y858304D01*
X403754Y858217D01*
G02X403826Y857789I-1225J-426D01*
G02X401232I-1297J0D01*
G02X402287Y859064I1298J0D01*
G01X402377Y859081D01*
X403184Y860478D01*
X403153Y860565D01*
G02X403080Y860993I1225J429D01*
G37*
G36*
G01X410480D02*
G02X413076I1298J0D01*
G02X412020Y859718I-1298J0D01*
G01X411930Y859701D01*
X411123Y858304D01*
X411154Y858217D01*
G02X411226Y857789I-1225J-426D01*
G02X408632I-1297J0D01*
G02X409687Y859064I1298J0D01*
G01X409777Y859081D01*
X410584Y860478D01*
X410553Y860565D01*
G02X410480Y860993I1225J429D01*
G37*
G36*
G01X417880D02*
G02X420476I1298J0D01*
G02X419420Y859718I-1298J0D01*
G01X419330Y859701D01*
X418523Y858304D01*
X418554Y858217D01*
G02X418626Y857789I-1225J-426D01*
G02X416032I-1297J0D01*
G02X417087Y859064I1298J0D01*
G01X417177Y859081D01*
X417984Y860478D01*
X417953Y860565D01*
G02X417880Y860993I1225J429D01*
G37*
G36*
G01X425280D02*
G02X427876I1298J0D01*
G02X426820Y859718I-1298J0D01*
G01X426730Y859701D01*
X425923Y858304D01*
X425954Y858217D01*
G02X426026Y857789I-1225J-426D01*
G02X423432I-1297J0D01*
G02X424487Y859064I1298J0D01*
G01X424577Y859081D01*
X425384Y860478D01*
X425353Y860565D01*
G02X425280Y860993I1225J429D01*
G37*
G36*
G01X432682D02*
G02X435276I1297J0D01*
G02X434221Y859718I-1298J0D01*
G01X434131Y859701D01*
X433324Y858303D01*
X433354Y858217D01*
G02X433426Y857789I-1225J-426D01*
G02X430832I-1297J0D01*
G02X431888Y859064I1298J0D01*
G01X431978Y859081D01*
X432785Y860478D01*
X432754Y860565D01*
G02X432682Y860993I1225J426D01*
G37*
G36*
G01X440080D02*
G02X442676I1298J0D01*
G02X442603Y860564I-1297J0D01*
G01X442572Y860478D01*
X443378Y859081D01*
X443468Y859064D01*
G02X444526Y857789I-239J-1275D01*
G02X441932I-1297J0D01*
G02X442003Y858215I1297J3D01*
G01X442034Y858302D01*
X441226Y859701D01*
X441136Y859718D01*
G02X440080Y860993I242J1275D01*
G37*
G36*
G01X447482D02*
G02X450076I1297J0D01*
G02X450004Y860564I-1297J-3D01*
G01X449973Y860478D01*
X450779Y859081D01*
X450869Y859064D01*
G02X451926Y857789I-240J-1275D01*
G02X449332I-1297J0D01*
G01Y857791D01*
G02X449404Y858216I1297J-1D01*
G01X449434Y858303D01*
X448627Y859701D01*
X448537Y859718D01*
G02X447482Y860993I243J1275D01*
G37*
G36*
G01X454880D02*
G02X457476I1298J0D01*
G02X457403Y860564I-1297J0D01*
G01X457372Y860478D01*
X458178Y859081D01*
X458268Y859064D01*
G02X459326Y857789I-239J-1275D01*
G02X456732I-1297J0D01*
G02X456803Y858215I1297J3D01*
G01X456834Y858302D01*
X456026Y859701D01*
X455936Y859718D01*
G02X454880Y860993I242J1275D01*
G37*
G36*
G01X462280D02*
G02X464876I1298J0D01*
G02X464803Y860564I-1297J0D01*
G01X464772Y860478D01*
X465578Y859081D01*
X465668Y859064D01*
G02X466726Y857789I-239J-1275D01*
G02X464132I-1297J0D01*
G02X464203Y858215I1297J3D01*
G01X464234Y858302D01*
X463426Y859701D01*
X463336Y859718D01*
G02X462280Y860993I242J1275D01*
G37*
G36*
G01X469680D02*
G02X472276I1298J0D01*
G02X472203Y860564I-1297J0D01*
G01X472172Y860478D01*
X472978Y859081D01*
X473068Y859064D01*
G02X474126Y857789I-239J-1275D01*
G02X471532I-1297J0D01*
G02X471603Y858215I1297J3D01*
G01X471634Y858302D01*
X470826Y859701D01*
X470736Y859718D01*
G02X469680Y860993I242J1275D01*
G37*
G36*
G01X477080D02*
G02X479676I1298J0D01*
G02X479603Y860564I-1297J0D01*
G01X479572Y860478D01*
X480378Y859081D01*
X480468Y859064D01*
G02X481526Y857789I-239J-1275D01*
G02X478932I-1297J0D01*
G02X479003Y858215I1297J3D01*
G01X479034Y858302D01*
X478226Y859701D01*
X478136Y859718D01*
G02X477080Y860993I242J1275D01*
G37*
G36*
G01X484480D02*
G02X487076I1298J0D01*
G02X487003Y860564I-1297J0D01*
G01X486972Y860478D01*
X487778Y859081D01*
X487868Y859064D01*
G02X488926Y857789I-239J-1275D01*
G02X486332I-1297J0D01*
G02X486403Y858215I1297J3D01*
G01X486434Y858302D01*
X485626Y859701D01*
X485536Y859718D01*
G02X484480Y860993I242J1275D01*
G37*
G36*
G01X491880D02*
G02X494476I1298J0D01*
G02X494403Y860564I-1297J0D01*
G01X494372Y860478D01*
X495178Y859081D01*
X495268Y859064D01*
G02X496326Y857789I-239J-1275D01*
G02X493732I-1297J0D01*
G02X493803Y858215I1297J3D01*
G01X493834Y858302D01*
X493026Y859701D01*
X492936Y859718D01*
G02X491880Y860993I242J1275D01*
G37*
G36*
G01X499280D02*
G02X501876I1298J0D01*
G02X501803Y860564I-1297J0D01*
G01X501772Y860478D01*
X502578Y859081D01*
X502668Y859064D01*
G02X503726Y857789I-239J-1275D01*
G02X501132I-1297J0D01*
G02X501203Y858215I1297J3D01*
G01X501234Y858302D01*
X500426Y859701D01*
X500336Y859718D01*
G02X499280Y860993I242J1275D01*
G37*
G36*
G01X506680D02*
G02X509276I1298J0D01*
G02X509203Y860564I-1297J0D01*
G01X509172Y860478D01*
X509978Y859081D01*
X510068Y859064D01*
G02X511126Y857789I-239J-1275D01*
G02X508532I-1297J0D01*
G02X508603Y858215I1297J3D01*
G01X508634Y858302D01*
X507826Y859701D01*
X507736Y859718D01*
G02X506680Y860993I242J1275D01*
G37*
G36*
G01X514080D02*
G02X516676I1298J0D01*
G02X516603Y860564I-1297J0D01*
G01X516572Y860478D01*
X517378Y859081D01*
X517468Y859064D01*
G02X518526Y857789I-239J-1275D01*
G02X515932I-1297J0D01*
G02X516003Y858215I1297J3D01*
G01X516034Y858302D01*
X515226Y859701D01*
X515136Y859718D01*
G02X514080Y860993I242J1275D01*
G37*
G36*
G01X521480D02*
G02X524076I1298J0D01*
G02X524003Y860564I-1297J0D01*
G01X523972Y860478D01*
X524778Y859081D01*
X524868Y859064D01*
G02X525926Y857789I-239J-1275D01*
G02X523332I-1297J0D01*
G02X523403Y858215I1297J3D01*
G01X523434Y858302D01*
X522626Y859701D01*
X522536Y859718D01*
G02X521480Y860993I242J1275D01*
G37*
G36*
G01X1327422D02*
G02X1330018I1298J0D01*
G02X1328962Y859718I-1298J0D01*
G01X1328872Y859701D01*
X1328065Y858304D01*
X1328096Y858217D01*
G02X1328168Y857789I-1225J-426D01*
G02X1325574I-1297J0D01*
G02X1326629Y859064I1298J0D01*
G01X1326719Y859081D01*
X1327526Y860478D01*
X1327495Y860565D01*
G02X1327422Y860993I1225J429D01*
G37*
G36*
G01X1334822D02*
G02X1337418I1298J0D01*
G02X1336362Y859718I-1298J0D01*
G01X1336272Y859701D01*
X1335465Y858304D01*
X1335496Y858217D01*
G02X1335568Y857789I-1225J-426D01*
G02X1332974I-1297J0D01*
G02X1334029Y859064I1298J0D01*
G01X1334119Y859081D01*
X1334926Y860478D01*
X1334895Y860565D01*
G02X1334822Y860993I1225J429D01*
G37*
G36*
G01X1342222D02*
G02X1344818I1298J0D01*
G02X1343762Y859718I-1298J0D01*
G01X1343672Y859701D01*
X1342865Y858304D01*
X1342896Y858217D01*
G02X1342968Y857789I-1225J-426D01*
G02X1340374I-1297J0D01*
G02X1341429Y859064I1298J0D01*
G01X1341519Y859081D01*
X1342326Y860478D01*
X1342295Y860565D01*
G02X1342222Y860993I1225J429D01*
G37*
G36*
G01X1349622D02*
G02X1352218I1298J0D01*
G02X1351162Y859718I-1298J0D01*
G01X1351072Y859701D01*
X1350265Y858304D01*
X1350296Y858217D01*
G02X1350368Y857789I-1225J-426D01*
G02X1347774I-1297J0D01*
G02X1348829Y859064I1298J0D01*
G01X1348919Y859081D01*
X1349726Y860478D01*
X1349695Y860565D01*
G02X1349622Y860993I1225J429D01*
G37*
G36*
G01X1357022D02*
G02X1359618I1298J0D01*
G02X1358562Y859718I-1298J0D01*
G01X1358472Y859701D01*
X1357665Y858304D01*
X1357696Y858217D01*
G02X1357768Y857789I-1225J-426D01*
G02X1355174I-1297J0D01*
G02X1356229Y859064I1298J0D01*
G01X1356319Y859081D01*
X1357126Y860478D01*
X1357095Y860565D01*
G02X1357022Y860993I1225J429D01*
G37*
G36*
G01X1364422D02*
G02X1367018I1298J0D01*
G02X1365962Y859718I-1298J0D01*
G01X1365872Y859701D01*
X1365065Y858304D01*
X1365096Y858217D01*
G02X1365168Y857789I-1225J-426D01*
G02X1362574I-1297J0D01*
G02X1363629Y859064I1298J0D01*
G01X1363719Y859081D01*
X1364526Y860478D01*
X1364495Y860565D01*
G02X1364422Y860993I1225J429D01*
G37*
G36*
G01X1371822D02*
G02X1374418I1298J0D01*
G02X1373362Y859718I-1298J0D01*
G01X1373272Y859701D01*
X1372465Y858304D01*
X1372496Y858217D01*
G02X1372568Y857789I-1225J-426D01*
G02X1369974I-1297J0D01*
G02X1371029Y859064I1298J0D01*
G01X1371119Y859081D01*
X1371926Y860478D01*
X1371895Y860565D01*
G02X1371822Y860993I1225J429D01*
G37*
G36*
G01X1379222D02*
G02X1381818I1298J0D01*
G02X1380762Y859718I-1298J0D01*
G01X1380672Y859701D01*
X1379865Y858304D01*
X1379896Y858217D01*
G02X1379968Y857789I-1225J-426D01*
G02X1377374I-1297J0D01*
G02X1378429Y859064I1298J0D01*
G01X1378519Y859081D01*
X1379326Y860478D01*
X1379295Y860565D01*
G02X1379222Y860993I1225J429D01*
G37*
G36*
G01X1386622D02*
G02X1389218I1298J0D01*
G02X1388162Y859718I-1298J0D01*
G01X1388072Y859701D01*
X1387265Y858304D01*
X1387296Y858217D01*
G02X1387368Y857789I-1225J-426D01*
G02X1384774I-1297J0D01*
G02X1385829Y859064I1298J0D01*
G01X1385919Y859081D01*
X1386726Y860478D01*
X1386695Y860565D01*
G02X1386622Y860993I1225J429D01*
G37*
G36*
G01X1394022D02*
G02X1396618I1298J0D01*
G02X1395562Y859718I-1298J0D01*
G01X1395472Y859701D01*
X1394665Y858304D01*
X1394696Y858217D01*
G02X1394768Y857789I-1225J-426D01*
G02X1392174I-1297J0D01*
G02X1393229Y859064I1298J0D01*
G01X1393319Y859081D01*
X1394126Y860478D01*
X1394095Y860565D01*
G02X1394022Y860993I1225J429D01*
G37*
G36*
G01X1401422D02*
G02X1404018I1298J0D01*
G02X1402962Y859718I-1298J0D01*
G01X1402872Y859701D01*
X1402065Y858304D01*
X1402096Y858217D01*
G02X1402168Y857789I-1225J-426D01*
G02X1399574I-1297J0D01*
G02X1400629Y859064I1298J0D01*
G01X1400719Y859081D01*
X1401526Y860478D01*
X1401495Y860565D01*
G02X1401422Y860993I1225J429D01*
G37*
G36*
G01X1408824D02*
G02X1411418I1297J0D01*
G02X1410363Y859718I-1298J0D01*
G01X1410273Y859701D01*
X1409466Y858303D01*
X1409496Y858217D01*
G02X1409568Y857789I-1225J-426D01*
G02X1406974I-1297J0D01*
G02X1408030Y859064I1298J0D01*
G01X1408120Y859081D01*
X1408927Y860478D01*
X1408896Y860565D01*
G02X1408824Y860993I1225J426D01*
G37*
G36*
G01X1416222D02*
G02X1418818I1298J0D01*
G02X1418745Y860564I-1297J0D01*
G01X1418714Y860478D01*
X1419520Y859081D01*
X1419610Y859064D01*
G02X1420668Y857789I-239J-1275D01*
G02X1418074I-1297J0D01*
G02X1418145Y858215I1297J3D01*
G01X1418176Y858302D01*
X1417368Y859701D01*
X1417278Y859718D01*
G02X1416222Y860993I242J1275D01*
G37*
G36*
G01X1423624D02*
G02X1426218I1297J0D01*
G02X1426146Y860564I-1297J-3D01*
G01X1426115Y860478D01*
X1426921Y859081D01*
X1427011Y859064D01*
G02X1428068Y857789I-240J-1275D01*
G02X1425474I-1297J0D01*
G01Y857791D01*
G02X1425546Y858216I1297J-1D01*
G01X1425576Y858303D01*
X1424769Y859701D01*
X1424679Y859718D01*
G02X1423624Y860993I243J1275D01*
G37*
G36*
G01X1431022D02*
G02X1433618I1298J0D01*
G02X1433545Y860564I-1297J0D01*
G01X1433514Y860478D01*
X1434320Y859081D01*
X1434410Y859064D01*
G02X1435468Y857789I-239J-1275D01*
G02X1432874I-1297J0D01*
G02X1432945Y858215I1297J3D01*
G01X1432976Y858302D01*
X1432168Y859701D01*
X1432078Y859718D01*
G02X1431022Y860993I242J1275D01*
G37*
G36*
G01X1438422D02*
G02X1441018I1298J0D01*
G02X1440945Y860564I-1297J0D01*
G01X1440914Y860478D01*
X1441720Y859081D01*
X1441810Y859064D01*
G02X1442868Y857789I-239J-1275D01*
G02X1440274I-1297J0D01*
G02X1440345Y858215I1297J3D01*
G01X1440376Y858302D01*
X1439568Y859701D01*
X1439478Y859718D01*
G02X1438422Y860993I242J1275D01*
G37*
G36*
G01X1445822D02*
G02X1448418I1298J0D01*
G02X1448345Y860564I-1297J0D01*
G01X1448314Y860478D01*
X1449120Y859081D01*
X1449210Y859064D01*
G02X1450268Y857789I-239J-1275D01*
G02X1447674I-1297J0D01*
G02X1447745Y858215I1297J3D01*
G01X1447776Y858302D01*
X1446968Y859701D01*
X1446878Y859718D01*
G02X1445822Y860993I242J1275D01*
G37*
G36*
G01X1453222D02*
G02X1455818I1298J0D01*
G02X1455745Y860564I-1297J0D01*
G01X1455714Y860478D01*
X1456520Y859081D01*
X1456610Y859064D01*
G02X1457668Y857789I-239J-1275D01*
G02X1455074I-1297J0D01*
G02X1455145Y858215I1297J3D01*
G01X1455176Y858302D01*
X1454368Y859701D01*
X1454278Y859718D01*
G02X1453222Y860993I242J1275D01*
G37*
G36*
G01X1460622D02*
G02X1463218I1298J0D01*
G02X1463145Y860564I-1297J0D01*
G01X1463114Y860478D01*
X1463920Y859081D01*
X1464010Y859064D01*
G02X1465068Y857789I-239J-1275D01*
G02X1462474I-1297J0D01*
G02X1462545Y858215I1297J3D01*
G01X1462576Y858302D01*
X1461768Y859701D01*
X1461678Y859718D01*
G02X1460622Y860993I242J1275D01*
G37*
G36*
G01X1468022D02*
G02X1470618I1298J0D01*
G02X1470545Y860564I-1297J0D01*
G01X1470514Y860478D01*
X1471320Y859081D01*
X1471410Y859064D01*
G02X1472468Y857789I-239J-1275D01*
G02X1469874I-1297J0D01*
G02X1469945Y858215I1297J3D01*
G01X1469976Y858302D01*
X1469168Y859701D01*
X1469078Y859718D01*
G02X1468022Y860993I242J1275D01*
G37*
G36*
G01X1475422D02*
G02X1478018I1298J0D01*
G02X1477945Y860564I-1297J0D01*
G01X1477914Y860478D01*
X1478720Y859081D01*
X1478810Y859064D01*
G02X1479868Y857789I-239J-1275D01*
G02X1477274I-1297J0D01*
G02X1477345Y858215I1297J3D01*
G01X1477376Y858302D01*
X1476568Y859701D01*
X1476478Y859718D01*
G02X1475422Y860993I242J1275D01*
G37*
G36*
G01X1482822D02*
G02X1485418I1298J0D01*
G02X1485345Y860564I-1297J0D01*
G01X1485314Y860478D01*
X1486120Y859081D01*
X1486210Y859064D01*
G02X1487268Y857789I-239J-1275D01*
G02X1484674I-1297J0D01*
G02X1484745Y858215I1297J3D01*
G01X1484776Y858302D01*
X1483968Y859701D01*
X1483878Y859718D01*
G02X1482822Y860993I242J1275D01*
G37*
G36*
G01X1490222D02*
G02X1492818I1298J0D01*
G02X1492745Y860564I-1297J0D01*
G01X1492714Y860478D01*
X1493520Y859081D01*
X1493610Y859064D01*
G02X1494668Y857789I-239J-1275D01*
G02X1492074I-1297J0D01*
G02X1492145Y858215I1297J3D01*
G01X1492176Y858302D01*
X1491368Y859701D01*
X1491278Y859718D01*
G02X1490222Y860993I242J1275D01*
G37*
G36*
G01X1497622D02*
G02X1500218I1298J0D01*
G02X1500145Y860564I-1297J0D01*
G01X1500114Y860478D01*
X1500920Y859081D01*
X1501010Y859064D01*
G02X1502068Y857789I-239J-1275D01*
G02X1499474I-1297J0D01*
G02X1499545Y858215I1297J3D01*
G01X1499576Y858302D01*
X1498768Y859701D01*
X1498678Y859718D01*
G02X1497622Y860993I242J1275D01*
G37*
G36*
G01X353132Y870606D02*
G02X355726I1297J0D01*
G02X355654Y870177I-1297J-3D01*
G01X355623Y870091D01*
X356430Y868693D01*
X356520Y868676D01*
G02X357576Y867401I-242J-1275D01*
G02X354980I-1298J0D01*
G02X355053Y867830I1297J0D01*
G01X355084Y867916D01*
X354277Y869314D01*
X354187Y869331D01*
G02X353132Y870606I243J1275D01*
G37*
G36*
G01X360532D02*
G02X363126I1297J0D01*
G02X363054Y870177I-1297J-3D01*
G01X363023Y870091D01*
X363830Y868693D01*
X363920Y868676D01*
G02X364976Y867401I-242J-1275D01*
G02X362380I-1298J0D01*
G02X362453Y867830I1297J0D01*
G01X362484Y867916D01*
X361677Y869314D01*
X361587Y869331D01*
G02X360532Y870606I243J1275D01*
G37*
G36*
G01X367932D02*
G02X370526I1297J0D01*
G02X370454Y870177I-1297J-3D01*
G01X370423Y870091D01*
X371230Y868693D01*
X371320Y868676D01*
G02X372376Y867401I-242J-1275D01*
G02X369780I-1298J0D01*
G02X369853Y867830I1297J0D01*
G01X369884Y867916D01*
X369077Y869314D01*
X368987Y869331D01*
G02X367932Y870606I243J1275D01*
G37*
G36*
G01X375332D02*
G02X377926I1297J0D01*
G02X377854Y870177I-1297J-3D01*
G01X377823Y870091D01*
X378630Y868693D01*
X378720Y868676D01*
G02X379776Y867401I-242J-1275D01*
G02X377180I-1298J0D01*
G02X377253Y867830I1297J0D01*
G01X377284Y867916D01*
X376477Y869314D01*
X376387Y869331D01*
G02X375332Y870606I243J1275D01*
G37*
G36*
G01X382732D02*
G02X385326I1297J0D01*
G02X385254Y870177I-1297J-3D01*
G01X385223Y870091D01*
X386030Y868693D01*
X386120Y868676D01*
G02X387176Y867401I-242J-1275D01*
G02X384580I-1298J0D01*
G02X384653Y867830I1297J0D01*
G01X384684Y867916D01*
X383877Y869314D01*
X383787Y869331D01*
G02X382732Y870606I243J1275D01*
G37*
G36*
G01X390132D02*
G02X392726I1297J0D01*
G02X392654Y870177I-1297J-3D01*
G01X392623Y870091D01*
X393430Y868693D01*
X393520Y868676D01*
G02X394576Y867401I-242J-1275D01*
G02X391980I-1298J0D01*
G02X392053Y867830I1297J0D01*
G01X392084Y867916D01*
X391277Y869314D01*
X391187Y869331D01*
G02X390132Y870606I243J1275D01*
G37*
G36*
G01X397532D02*
G02X400126I1297J0D01*
G02X400054Y870177I-1297J-3D01*
G01X400023Y870091D01*
X400830Y868693D01*
X400920Y868676D01*
G02X401976Y867401I-242J-1275D01*
G02X399380I-1298J0D01*
G02X399453Y867830I1297J0D01*
G01X399484Y867916D01*
X398677Y869314D01*
X398587Y869331D01*
G02X397532Y870606I243J1275D01*
G37*
G36*
G01X404932D02*
G02X407526I1297J0D01*
G02X407454Y870177I-1297J-3D01*
G01X407423Y870091D01*
X408230Y868693D01*
X408320Y868676D01*
G02X409376Y867401I-242J-1275D01*
G02X406780I-1298J0D01*
G02X406853Y867830I1297J0D01*
G01X406884Y867916D01*
X406077Y869314D01*
X405987Y869331D01*
G02X404932Y870606I243J1275D01*
G37*
G36*
G01X416032D02*
G02X418626I1297J0D01*
G02X417571Y869331I-1298J0D01*
G01X417481Y869314D01*
X416673Y867915D01*
X416703Y867828D01*
G02X416776Y867401I-1225J-429D01*
G02X414180I-1298J0D01*
G02X415238Y868676I1297J0D01*
G01X415328Y868693D01*
X416135Y870091D01*
X416104Y870178D01*
G02X416032Y870606I1225J426D01*
G37*
G36*
G01X423432D02*
G02X426026I1297J0D01*
G02X424971Y869331I-1298J0D01*
G01X424881Y869314D01*
X424073Y867915D01*
X424103Y867828D01*
G02X424176Y867401I-1225J-429D01*
G02X421580I-1298J0D01*
G02X422638Y868676I1297J0D01*
G01X422728Y868693D01*
X423535Y870091D01*
X423504Y870178D01*
G02X423432Y870606I1225J426D01*
G37*
G36*
G01X430832D02*
G02X433426I1297J0D01*
G02X432371Y869331I-1298J0D01*
G01X432281Y869314D01*
X431473Y867915D01*
X431503Y867828D01*
G02X431576Y867401I-1225J-429D01*
G02X428980I-1298J0D01*
G02X430038Y868676I1297J0D01*
G01X430128Y868693D01*
X430935Y870091D01*
X430904Y870178D01*
G02X430832Y870606I1225J426D01*
G37*
G36*
G01X438232D02*
G02X440826I1297J0D01*
G02X439771Y869331I-1298J0D01*
G01X439681Y869314D01*
X438873Y867915D01*
X438903Y867828D01*
G02X438976Y867401I-1225J-429D01*
G02X436380I-1298J0D01*
G02X437438Y868676I1297J0D01*
G01X437528Y868693D01*
X438335Y870091D01*
X438304Y870178D01*
G02X438232Y870606I1225J426D01*
G37*
G36*
G01X445632D02*
G02X448226I1297J0D01*
G02X447171Y869331I-1298J0D01*
G01X447081Y869314D01*
X446273Y867915D01*
X446303Y867828D01*
G02X446376Y867401I-1225J-429D01*
G02X443780I-1298J0D01*
G02X444838Y868676I1297J0D01*
G01X444928Y868693D01*
X445735Y870091D01*
X445704Y870178D01*
G02X445632Y870606I1225J426D01*
G37*
G36*
G01X453032D02*
G02X455626I1297J0D01*
G02X454571Y869331I-1298J0D01*
G01X454481Y869314D01*
X453673Y867915D01*
X453703Y867828D01*
G02X453776Y867401I-1225J-429D01*
G02X451180I-1298J0D01*
G02X452238Y868676I1297J0D01*
G01X452328Y868693D01*
X453135Y870091D01*
X453104Y870178D01*
G02X453032Y870606I1225J426D01*
G37*
G36*
G01X460432D02*
G02X463026I1297J0D01*
G02X461971Y869331I-1298J0D01*
G01X461881Y869314D01*
X461073Y867915D01*
X461103Y867828D01*
G02X461176Y867401I-1225J-429D01*
G02X458580I-1298J0D01*
G02X459638Y868676I1297J0D01*
G01X459728Y868693D01*
X460535Y870091D01*
X460504Y870178D01*
G02X460432Y870606I1225J426D01*
G37*
G36*
G01X467832D02*
G02X470426I1297J0D01*
G02X469371Y869331I-1298J0D01*
G01X469281Y869314D01*
X468473Y867915D01*
X468503Y867828D01*
G02X468576Y867401I-1225J-429D01*
G02X465980I-1298J0D01*
G02X467038Y868676I1297J0D01*
G01X467128Y868693D01*
X467935Y870091D01*
X467904Y870178D01*
G02X467832Y870606I1225J426D01*
G37*
G36*
G01X475232D02*
G02X477826I1297J0D01*
G02X476771Y869331I-1298J0D01*
G01X476681Y869314D01*
X475873Y867915D01*
X475903Y867828D01*
G02X475976Y867401I-1225J-429D01*
G02X473380I-1298J0D01*
G02X474438Y868676I1297J0D01*
G01X474528Y868693D01*
X475335Y870091D01*
X475304Y870178D01*
G02X475232Y870606I1225J426D01*
G37*
G36*
G01X482632D02*
G02X485226I1297J0D01*
G02X484171Y869331I-1298J0D01*
G01X484081Y869314D01*
X483273Y867915D01*
X483303Y867828D01*
G02X483376Y867401I-1225J-429D01*
G02X480780I-1298J0D01*
G02X481838Y868676I1297J0D01*
G01X481928Y868693D01*
X482735Y870091D01*
X482704Y870178D01*
G02X482632Y870606I1225J426D01*
G37*
G36*
G01X490032D02*
G02X492626I1297J0D01*
G02X491571Y869331I-1298J0D01*
G01X491481Y869314D01*
X490673Y867915D01*
X490703Y867828D01*
G02X490776Y867401I-1225J-429D01*
G02X488180I-1298J0D01*
G02X489238Y868676I1297J0D01*
G01X489328Y868693D01*
X490135Y870091D01*
X490104Y870178D01*
G02X490032Y870606I1225J426D01*
G37*
G36*
G01X497432D02*
G02X500026I1297J0D01*
G02X498971Y869331I-1298J0D01*
G01X498881Y869314D01*
X498073Y867915D01*
X498103Y867828D01*
G02X498176Y867401I-1225J-429D01*
G02X495580I-1298J0D01*
G02X496638Y868676I1297J0D01*
G01X496728Y868693D01*
X497535Y870091D01*
X497504Y870178D01*
G02X497432Y870606I1225J426D01*
G37*
G36*
G01X504832D02*
G02X507426I1297J0D01*
G02X506371Y869331I-1298J0D01*
G01X506281Y869314D01*
X505473Y867915D01*
X505503Y867828D01*
G02X505576Y867401I-1225J-429D01*
G02X502980I-1298J0D01*
G02X504038Y868676I1297J0D01*
G01X504128Y868693D01*
X504935Y870091D01*
X504904Y870178D01*
G02X504832Y870606I1225J426D01*
G37*
G36*
G01X512232D02*
G02X514826I1297J0D01*
G02X513771Y869331I-1298J0D01*
G01X513681Y869314D01*
X512873Y867915D01*
X512903Y867828D01*
G02X512976Y867401I-1225J-429D01*
G02X510380I-1298J0D01*
G02X511438Y868676I1297J0D01*
G01X511528Y868693D01*
X512335Y870091D01*
X512304Y870178D01*
G02X512232Y870606I1225J426D01*
G37*
G36*
G01X519632D02*
G02X522226I1297J0D01*
G02X521171Y869331I-1298J0D01*
G01X521081Y869314D01*
X520273Y867915D01*
X520303Y867828D01*
G02X520376Y867401I-1225J-429D01*
G02X517780I-1298J0D01*
G02X518838Y868676I1297J0D01*
G01X518928Y868693D01*
X519735Y870091D01*
X519704Y870178D01*
G02X519632Y870606I1225J426D01*
G37*
G36*
G01X527032D02*
G02X529626I1297J0D01*
G02X528571Y869331I-1298J0D01*
G01X528481Y869314D01*
X527674Y867916D01*
X527704Y867829D01*
G02X527776Y867401I-1225J-426D01*
G02X525182I-1297J0D01*
G02X526238Y868676I1298J0D01*
G01X526328Y868693D01*
X527135Y870091D01*
X527104Y870178D01*
G02X527032Y870606I1225J426D01*
G37*
G36*
G01X1329274D02*
G02X1331868I1297J0D01*
G02X1331796Y870177I-1297J-3D01*
G01X1331765Y870091D01*
X1332572Y868693D01*
X1332662Y868676D01*
G02X1333718Y867401I-242J-1275D01*
G02X1331122I-1298J0D01*
G02X1331195Y867830I1297J0D01*
G01X1331226Y867916D01*
X1330419Y869314D01*
X1330329Y869331D01*
G02X1329274Y870606I243J1275D01*
G37*
G36*
G01X1336674D02*
G02X1339268I1297J0D01*
G02X1339196Y870177I-1297J-3D01*
G01X1339165Y870091D01*
X1339972Y868693D01*
X1340062Y868676D01*
G02X1341118Y867401I-242J-1275D01*
G02X1338522I-1298J0D01*
G02X1338595Y867830I1297J0D01*
G01X1338626Y867916D01*
X1337819Y869314D01*
X1337729Y869331D01*
G02X1336674Y870606I243J1275D01*
G37*
G36*
G01X1344074D02*
G02X1346668I1297J0D01*
G02X1346596Y870177I-1297J-3D01*
G01X1346565Y870091D01*
X1347372Y868693D01*
X1347462Y868676D01*
G02X1348518Y867401I-242J-1275D01*
G02X1345922I-1298J0D01*
G02X1345995Y867830I1297J0D01*
G01X1346026Y867916D01*
X1345219Y869314D01*
X1345129Y869331D01*
G02X1344074Y870606I243J1275D01*
G37*
G36*
G01X1351474D02*
G02X1354068I1297J0D01*
G02X1353996Y870177I-1297J-3D01*
G01X1353965Y870091D01*
X1354772Y868693D01*
X1354862Y868676D01*
G02X1355918Y867401I-242J-1275D01*
G02X1353322I-1298J0D01*
G02X1353395Y867830I1297J0D01*
G01X1353426Y867916D01*
X1352619Y869314D01*
X1352529Y869331D01*
G02X1351474Y870606I243J1275D01*
G37*
G36*
G01X1358874D02*
G02X1361468I1297J0D01*
G02X1361396Y870177I-1297J-3D01*
G01X1361365Y870091D01*
X1362172Y868693D01*
X1362262Y868676D01*
G02X1363318Y867401I-242J-1275D01*
G02X1360722I-1298J0D01*
G02X1360795Y867830I1297J0D01*
G01X1360826Y867916D01*
X1360019Y869314D01*
X1359929Y869331D01*
G02X1358874Y870606I243J1275D01*
G37*
G36*
G01X1366274D02*
G02X1368868I1297J0D01*
G02X1368796Y870177I-1297J-3D01*
G01X1368765Y870091D01*
X1369572Y868693D01*
X1369662Y868676D01*
G02X1370718Y867401I-242J-1275D01*
G02X1368122I-1298J0D01*
G02X1368195Y867830I1297J0D01*
G01X1368226Y867916D01*
X1367419Y869314D01*
X1367329Y869331D01*
G02X1366274Y870606I243J1275D01*
G37*
G36*
G01X1373674D02*
G02X1376268I1297J0D01*
G02X1376196Y870177I-1297J-3D01*
G01X1376165Y870091D01*
X1376972Y868693D01*
X1377062Y868676D01*
G02X1378118Y867401I-242J-1275D01*
G02X1375522I-1298J0D01*
G02X1375595Y867830I1297J0D01*
G01X1375626Y867916D01*
X1374819Y869314D01*
X1374729Y869331D01*
G02X1373674Y870606I243J1275D01*
G37*
G36*
G01X1381074D02*
G02X1383668I1297J0D01*
G02X1383596Y870177I-1297J-3D01*
G01X1383565Y870091D01*
X1384372Y868693D01*
X1384462Y868676D01*
G02X1385518Y867401I-242J-1275D01*
G02X1382922I-1298J0D01*
G02X1382995Y867830I1297J0D01*
G01X1383026Y867916D01*
X1382219Y869314D01*
X1382129Y869331D01*
G02X1381074Y870606I243J1275D01*
G37*
G36*
G01X1392174D02*
G02X1394768I1297J0D01*
G02X1393713Y869331I-1298J0D01*
G01X1393623Y869314D01*
X1392815Y867915D01*
X1392845Y867828D01*
G02X1392918Y867401I-1225J-429D01*
G02X1390322I-1298J0D01*
G02X1391380Y868676I1297J0D01*
G01X1391470Y868693D01*
X1392277Y870091D01*
X1392246Y870178D01*
G02X1392174Y870606I1225J426D01*
G37*
G36*
G01X1399574D02*
G02X1402168I1297J0D01*
G02X1401113Y869331I-1298J0D01*
G01X1401023Y869314D01*
X1400215Y867915D01*
X1400245Y867828D01*
G02X1400318Y867401I-1225J-429D01*
G02X1397722I-1298J0D01*
G02X1398780Y868676I1297J0D01*
G01X1398870Y868693D01*
X1399677Y870091D01*
X1399646Y870178D01*
G02X1399574Y870606I1225J426D01*
G37*
G36*
G01X1406974D02*
G02X1409568I1297J0D01*
G02X1408513Y869331I-1298J0D01*
G01X1408423Y869314D01*
X1407615Y867915D01*
X1407645Y867828D01*
G02X1407718Y867401I-1225J-429D01*
G02X1405122I-1298J0D01*
G02X1406180Y868676I1297J0D01*
G01X1406270Y868693D01*
X1407077Y870091D01*
X1407046Y870178D01*
G02X1406974Y870606I1225J426D01*
G37*
G36*
G01X1414374D02*
G02X1416968I1297J0D01*
G02X1415913Y869331I-1298J0D01*
G01X1415823Y869314D01*
X1415015Y867915D01*
X1415045Y867828D01*
G02X1415118Y867401I-1225J-429D01*
G02X1412522I-1298J0D01*
G02X1413580Y868676I1297J0D01*
G01X1413670Y868693D01*
X1414477Y870091D01*
X1414446Y870178D01*
G02X1414374Y870606I1225J426D01*
G37*
G36*
G01X1421774D02*
G02X1424368I1297J0D01*
G02X1423313Y869331I-1298J0D01*
G01X1423223Y869314D01*
X1422415Y867915D01*
X1422445Y867828D01*
G02X1422518Y867401I-1225J-429D01*
G02X1419922I-1298J0D01*
G02X1420980Y868676I1297J0D01*
G01X1421070Y868693D01*
X1421877Y870091D01*
X1421846Y870178D01*
G02X1421774Y870606I1225J426D01*
G37*
G36*
G01X1429174D02*
G02X1431768I1297J0D01*
G02X1430713Y869331I-1298J0D01*
G01X1430623Y869314D01*
X1429815Y867915D01*
X1429845Y867828D01*
G02X1429918Y867401I-1225J-429D01*
G02X1427322I-1298J0D01*
G02X1428380Y868676I1297J0D01*
G01X1428470Y868693D01*
X1429277Y870091D01*
X1429246Y870178D01*
G02X1429174Y870606I1225J426D01*
G37*
G36*
G01X1436574D02*
G02X1439168I1297J0D01*
G02X1438113Y869331I-1298J0D01*
G01X1438023Y869314D01*
X1437215Y867915D01*
X1437245Y867828D01*
G02X1437318Y867401I-1225J-429D01*
G02X1434722I-1298J0D01*
G02X1435780Y868676I1297J0D01*
G01X1435870Y868693D01*
X1436677Y870091D01*
X1436646Y870178D01*
G02X1436574Y870606I1225J426D01*
G37*
G36*
G01X1443974D02*
G02X1446568I1297J0D01*
G02X1445513Y869331I-1298J0D01*
G01X1445423Y869314D01*
X1444615Y867915D01*
X1444645Y867828D01*
G02X1444718Y867401I-1225J-429D01*
G02X1442122I-1298J0D01*
G02X1443180Y868676I1297J0D01*
G01X1443270Y868693D01*
X1444077Y870091D01*
X1444046Y870178D01*
G02X1443974Y870606I1225J426D01*
G37*
G36*
G01X1451374D02*
G02X1453968I1297J0D01*
G02X1452913Y869331I-1298J0D01*
G01X1452823Y869314D01*
X1452015Y867915D01*
X1452045Y867828D01*
G02X1452118Y867401I-1225J-429D01*
G02X1449522I-1298J0D01*
G02X1450580Y868676I1297J0D01*
G01X1450670Y868693D01*
X1451477Y870091D01*
X1451446Y870178D01*
G02X1451374Y870606I1225J426D01*
G37*
G36*
G01X1458774D02*
G02X1461368I1297J0D01*
G02X1460313Y869331I-1298J0D01*
G01X1460223Y869314D01*
X1459415Y867915D01*
X1459445Y867828D01*
G02X1459518Y867401I-1225J-429D01*
G02X1456922I-1298J0D01*
G02X1457980Y868676I1297J0D01*
G01X1458070Y868693D01*
X1458877Y870091D01*
X1458846Y870178D01*
G02X1458774Y870606I1225J426D01*
G37*
G36*
G01X1466174D02*
G02X1468768I1297J0D01*
G02X1467713Y869331I-1298J0D01*
G01X1467623Y869314D01*
X1466815Y867915D01*
X1466845Y867828D01*
G02X1466918Y867401I-1225J-429D01*
G02X1464322I-1298J0D01*
G02X1465380Y868676I1297J0D01*
G01X1465470Y868693D01*
X1466277Y870091D01*
X1466246Y870178D01*
G02X1466174Y870606I1225J426D01*
G37*
G36*
G01X1473574D02*
G02X1476168I1297J0D01*
G02X1475113Y869331I-1298J0D01*
G01X1475023Y869314D01*
X1474215Y867915D01*
X1474245Y867828D01*
G02X1474318Y867401I-1225J-429D01*
G02X1471722I-1298J0D01*
G02X1472780Y868676I1297J0D01*
G01X1472870Y868693D01*
X1473677Y870091D01*
X1473646Y870178D01*
G02X1473574Y870606I1225J426D01*
G37*
G36*
G01X1480974D02*
G02X1483568I1297J0D01*
G02X1482513Y869331I-1298J0D01*
G01X1482423Y869314D01*
X1481615Y867915D01*
X1481645Y867828D01*
G02X1481718Y867401I-1225J-429D01*
G02X1479122I-1298J0D01*
G02X1480180Y868676I1297J0D01*
G01X1480270Y868693D01*
X1481077Y870091D01*
X1481046Y870178D01*
G02X1480974Y870606I1225J426D01*
G37*
G36*
G01X1488374D02*
G02X1490968I1297J0D01*
G02X1489913Y869331I-1298J0D01*
G01X1489823Y869314D01*
X1489015Y867915D01*
X1489045Y867828D01*
G02X1489118Y867401I-1225J-429D01*
G02X1486522I-1298J0D01*
G02X1487580Y868676I1297J0D01*
G01X1487670Y868693D01*
X1488477Y870091D01*
X1488446Y870178D01*
G02X1488374Y870606I1225J426D01*
G37*
G36*
G01X1495774D02*
G02X1498368I1297J0D01*
G02X1497313Y869331I-1298J0D01*
G01X1497223Y869314D01*
X1496415Y867915D01*
X1496445Y867828D01*
G02X1496518Y867401I-1225J-429D01*
G02X1493922I-1298J0D01*
G02X1494980Y868676I1297J0D01*
G01X1495070Y868693D01*
X1495877Y870091D01*
X1495846Y870178D01*
G02X1495774Y870606I1225J426D01*
G37*
G36*
G01X1503174D02*
G02X1505768I1297J0D01*
G02X1504713Y869331I-1298J0D01*
G01X1504623Y869314D01*
X1503816Y867916D01*
X1503846Y867829D01*
G02X1503918Y867401I-1225J-426D01*
G02X1501324I-1297J0D01*
G02X1502380Y868676I1298J0D01*
G01X1502470Y868693D01*
X1503277Y870091D01*
X1503246Y870178D01*
G02X1503174Y870606I1225J426D01*
G37*
G36*
G01X351280Y873810D02*
G02X353876I1298J0D01*
G02X352820Y872535I-1298J0D01*
G01X352730Y872518D01*
X351923Y871121D01*
X351954Y871034D01*
G02X352026Y870606I-1225J-426D01*
G02X349432I-1297J0D01*
G02X350487Y871881I1298J0D01*
G01X350577Y871898D01*
X351384Y873295D01*
X351353Y873382D01*
G02X351280Y873810I1225J429D01*
G37*
G36*
G01X358680D02*
G02X361276I1298J0D01*
G02X360220Y872535I-1298J0D01*
G01X360130Y872518D01*
X359323Y871121D01*
X359354Y871034D01*
G02X359426Y870606I-1225J-426D01*
G02X356832I-1297J0D01*
G02X357887Y871881I1298J0D01*
G01X357977Y871898D01*
X358784Y873295D01*
X358753Y873382D01*
G02X358680Y873810I1225J429D01*
G37*
G36*
G01X366080D02*
G02X368676I1298J0D01*
G02X367620Y872535I-1298J0D01*
G01X367530Y872518D01*
X366723Y871121D01*
X366754Y871034D01*
G02X366826Y870606I-1225J-426D01*
G02X364232I-1297J0D01*
G02X365287Y871881I1298J0D01*
G01X365377Y871898D01*
X366184Y873295D01*
X366153Y873382D01*
G02X366080Y873810I1225J429D01*
G37*
G36*
G01X373480D02*
G02X376076I1298J0D01*
G02X375020Y872535I-1298J0D01*
G01X374930Y872518D01*
X374123Y871121D01*
X374154Y871034D01*
G02X374226Y870606I-1225J-426D01*
G02X371632I-1297J0D01*
G02X372687Y871881I1298J0D01*
G01X372777Y871898D01*
X373584Y873295D01*
X373553Y873382D01*
G02X373480Y873810I1225J429D01*
G37*
G36*
G01X380880D02*
G02X383476I1298J0D01*
G02X382420Y872535I-1298J0D01*
G01X382330Y872518D01*
X381523Y871121D01*
X381554Y871034D01*
G02X381626Y870606I-1225J-426D01*
G02X379032I-1297J0D01*
G02X380087Y871881I1298J0D01*
G01X380177Y871898D01*
X380984Y873295D01*
X380953Y873382D01*
G02X380880Y873810I1225J429D01*
G37*
G36*
G01X388280D02*
G02X390876I1298J0D01*
G02X389820Y872535I-1298J0D01*
G01X389730Y872518D01*
X388923Y871121D01*
X388954Y871034D01*
G02X389026Y870606I-1225J-426D01*
G02X386432I-1297J0D01*
G02X387487Y871881I1298J0D01*
G01X387577Y871898D01*
X388384Y873295D01*
X388353Y873382D01*
G02X388280Y873810I1225J429D01*
G37*
G36*
G01X395680D02*
G02X398276I1298J0D01*
G02X397220Y872535I-1298J0D01*
G01X397130Y872518D01*
X396323Y871121D01*
X396354Y871034D01*
G02X396426Y870606I-1225J-426D01*
G02X393832I-1297J0D01*
G02X394887Y871881I1298J0D01*
G01X394977Y871898D01*
X395784Y873295D01*
X395753Y873382D01*
G02X395680Y873810I1225J429D01*
G37*
G36*
G01X403080D02*
G02X405676I1298J0D01*
G02X404620Y872535I-1298J0D01*
G01X404530Y872518D01*
X403723Y871121D01*
X403754Y871034D01*
G02X403826Y870606I-1225J-426D01*
G02X401232I-1297J0D01*
G02X402287Y871881I1298J0D01*
G01X402377Y871898D01*
X403184Y873295D01*
X403153Y873382D01*
G02X403080Y873810I1225J429D01*
G37*
G36*
G01X410480D02*
G02X413076I1298J0D01*
G02X413003Y873381I-1297J0D01*
G01X412972Y873295D01*
X413778Y871898D01*
X413868Y871881D01*
G02X414926Y870606I-239J-1275D01*
G02X412332I-1297J0D01*
G02X412403Y871032I1297J3D01*
G01X412434Y871119D01*
X411626Y872518D01*
X411536Y872535D01*
G02X410480Y873810I242J1275D01*
G37*
G36*
G01X417880D02*
G02X420476I1298J0D01*
G02X420403Y873381I-1297J0D01*
G01X420372Y873295D01*
X421178Y871898D01*
X421268Y871881D01*
G02X422326Y870606I-239J-1275D01*
G02X419732I-1297J0D01*
G02X419803Y871032I1297J3D01*
G01X419834Y871119D01*
X419026Y872518D01*
X418936Y872535D01*
G02X417880Y873810I242J1275D01*
G37*
G36*
G01X425280D02*
G02X427876I1298J0D01*
G02X427803Y873381I-1297J0D01*
G01X427772Y873295D01*
X428578Y871898D01*
X428668Y871881D01*
G02X429726Y870606I-239J-1275D01*
G02X427132I-1297J0D01*
G02X427203Y871032I1297J3D01*
G01X427234Y871119D01*
X426426Y872518D01*
X426336Y872535D01*
G02X425280Y873810I242J1275D01*
G37*
G36*
G01X432682D02*
G02X435276I1297J0D01*
G02X435204Y873381I-1297J-3D01*
G01X435173Y873295D01*
X435979Y871898D01*
X436069Y871881D01*
G02X437126Y870606I-240J-1275D01*
G02X434532I-1297J0D01*
G01Y870608D01*
G02X434604Y871033I1297J-1D01*
G01X434634Y871120D01*
X433827Y872518D01*
X433737Y872535D01*
G02X432682Y873810I243J1275D01*
G37*
G36*
G01X440080D02*
G02X442676I1298J0D01*
G02X442603Y873381I-1297J0D01*
G01X442572Y873295D01*
X443378Y871898D01*
X443468Y871881D01*
G02X444526Y870606I-239J-1275D01*
G02X441932I-1297J0D01*
G02X442003Y871032I1297J3D01*
G01X442034Y871119D01*
X441226Y872518D01*
X441136Y872535D01*
G02X440080Y873810I242J1275D01*
G37*
G36*
G01X447482D02*
G02X450076I1297J0D01*
G02X450004Y873381I-1297J-3D01*
G01X449973Y873295D01*
X450779Y871898D01*
X450869Y871881D01*
G02X451926Y870606I-240J-1275D01*
G02X449332I-1297J0D01*
G01Y870608D01*
G02X449404Y871033I1297J-1D01*
G01X449434Y871120D01*
X448627Y872518D01*
X448537Y872535D01*
G02X447482Y873810I243J1275D01*
G37*
G36*
G01X454880D02*
G02X457476I1298J0D01*
G02X457403Y873381I-1297J0D01*
G01X457372Y873295D01*
X458178Y871898D01*
X458268Y871881D01*
G02X459326Y870606I-239J-1275D01*
G02X456732I-1297J0D01*
G02X456803Y871032I1297J3D01*
G01X456834Y871119D01*
X456026Y872518D01*
X455936Y872535D01*
G02X454880Y873810I242J1275D01*
G37*
G36*
G01X462280D02*
G02X464876I1298J0D01*
G02X464803Y873381I-1297J0D01*
G01X464772Y873295D01*
X465578Y871898D01*
X465668Y871881D01*
G02X466726Y870606I-239J-1275D01*
G02X464132I-1297J0D01*
G02X464203Y871032I1297J3D01*
G01X464234Y871119D01*
X463426Y872518D01*
X463336Y872535D01*
G02X462280Y873810I242J1275D01*
G37*
G36*
G01X477080D02*
G02X479676I1298J0D01*
G02X479603Y873381I-1297J0D01*
G01X479572Y873295D01*
X480378Y871898D01*
X480468Y871881D01*
G02X481526Y870606I-239J-1275D01*
G02X478932I-1297J0D01*
G02X479003Y871032I1297J3D01*
G01X479034Y871119D01*
X478226Y872518D01*
X478136Y872535D01*
G02X477080Y873810I242J1275D01*
G37*
G36*
G01X484480D02*
G02X487076I1298J0D01*
G02X487003Y873381I-1297J0D01*
G01X486972Y873295D01*
X487778Y871898D01*
X487868Y871881D01*
G02X488926Y870606I-239J-1275D01*
G02X486332I-1297J0D01*
G02X486403Y871032I1297J3D01*
G01X486434Y871119D01*
X485626Y872518D01*
X485536Y872535D01*
G02X484480Y873810I242J1275D01*
G37*
G36*
G01X491880D02*
G02X494476I1298J0D01*
G02X494403Y873381I-1297J0D01*
G01X494372Y873295D01*
X495178Y871898D01*
X495268Y871881D01*
G02X496326Y870606I-239J-1275D01*
G02X493732I-1297J0D01*
G02X493803Y871032I1297J3D01*
G01X493834Y871119D01*
X493026Y872518D01*
X492936Y872535D01*
G02X491880Y873810I242J1275D01*
G37*
G36*
G01X499280D02*
G02X501876I1298J0D01*
G02X501803Y873381I-1297J0D01*
G01X501772Y873295D01*
X502578Y871898D01*
X502668Y871881D01*
G02X503726Y870606I-239J-1275D01*
G02X501132I-1297J0D01*
G02X501203Y871032I1297J3D01*
G01X501234Y871119D01*
X500426Y872518D01*
X500336Y872535D01*
G02X499280Y873810I242J1275D01*
G37*
G36*
G01X506680D02*
G02X509276I1298J0D01*
G02X509203Y873381I-1297J0D01*
G01X509172Y873295D01*
X509978Y871898D01*
X510068Y871881D01*
G02X511126Y870606I-239J-1275D01*
G02X508532I-1297J0D01*
G02X508603Y871032I1297J3D01*
G01X508634Y871119D01*
X507826Y872518D01*
X507736Y872535D01*
G02X506680Y873810I242J1275D01*
G37*
G36*
G01X514080D02*
G02X516676I1298J0D01*
G02X516603Y873381I-1297J0D01*
G01X516572Y873295D01*
X517378Y871898D01*
X517468Y871881D01*
G02X518526Y870606I-239J-1275D01*
G02X515932I-1297J0D01*
G02X516003Y871032I1297J3D01*
G01X516034Y871119D01*
X515226Y872518D01*
X515136Y872535D01*
G02X514080Y873810I242J1275D01*
G37*
G36*
G01X1327422D02*
G02X1330018I1298J0D01*
G02X1328962Y872535I-1298J0D01*
G01X1328872Y872518D01*
X1328065Y871121D01*
X1328096Y871034D01*
G02X1328168Y870606I-1225J-426D01*
G02X1325574I-1297J0D01*
G02X1326629Y871881I1298J0D01*
G01X1326719Y871898D01*
X1327526Y873295D01*
X1327495Y873382D01*
G02X1327422Y873810I1225J429D01*
G37*
G36*
G01X1334822D02*
G02X1337418I1298J0D01*
G02X1336362Y872535I-1298J0D01*
G01X1336272Y872518D01*
X1335465Y871121D01*
X1335496Y871034D01*
G02X1335568Y870606I-1225J-426D01*
G02X1332974I-1297J0D01*
G02X1334029Y871881I1298J0D01*
G01X1334119Y871898D01*
X1334926Y873295D01*
X1334895Y873382D01*
G02X1334822Y873810I1225J429D01*
G37*
G36*
G01X1342222D02*
G02X1344818I1298J0D01*
G02X1343762Y872535I-1298J0D01*
G01X1343672Y872518D01*
X1342865Y871121D01*
X1342896Y871034D01*
G02X1342968Y870606I-1225J-426D01*
G02X1340374I-1297J0D01*
G02X1341429Y871881I1298J0D01*
G01X1341519Y871898D01*
X1342326Y873295D01*
X1342295Y873382D01*
G02X1342222Y873810I1225J429D01*
G37*
G36*
G01X1349622D02*
G02X1352218I1298J0D01*
G02X1351162Y872535I-1298J0D01*
G01X1351072Y872518D01*
X1350265Y871121D01*
X1350296Y871034D01*
G02X1350368Y870606I-1225J-426D01*
G02X1347774I-1297J0D01*
G02X1348829Y871881I1298J0D01*
G01X1348919Y871898D01*
X1349726Y873295D01*
X1349695Y873382D01*
G02X1349622Y873810I1225J429D01*
G37*
G36*
G01X1357022D02*
G02X1359618I1298J0D01*
G02X1358562Y872535I-1298J0D01*
G01X1358472Y872518D01*
X1357665Y871121D01*
X1357696Y871034D01*
G02X1357768Y870606I-1225J-426D01*
G02X1355174I-1297J0D01*
G02X1356229Y871881I1298J0D01*
G01X1356319Y871898D01*
X1357126Y873295D01*
X1357095Y873382D01*
G02X1357022Y873810I1225J429D01*
G37*
G36*
G01X1364422D02*
G02X1367018I1298J0D01*
G02X1365962Y872535I-1298J0D01*
G01X1365872Y872518D01*
X1365065Y871121D01*
X1365096Y871034D01*
G02X1365168Y870606I-1225J-426D01*
G02X1362574I-1297J0D01*
G02X1363629Y871881I1298J0D01*
G01X1363719Y871898D01*
X1364526Y873295D01*
X1364495Y873382D01*
G02X1364422Y873810I1225J429D01*
G37*
G36*
G01X1371822D02*
G02X1374418I1298J0D01*
G02X1373362Y872535I-1298J0D01*
G01X1373272Y872518D01*
X1372465Y871121D01*
X1372496Y871034D01*
G02X1372568Y870606I-1225J-426D01*
G02X1369974I-1297J0D01*
G02X1371029Y871881I1298J0D01*
G01X1371119Y871898D01*
X1371926Y873295D01*
X1371895Y873382D01*
G02X1371822Y873810I1225J429D01*
G37*
G36*
G01X1379222D02*
G02X1381818I1298J0D01*
G02X1380762Y872535I-1298J0D01*
G01X1380672Y872518D01*
X1379865Y871121D01*
X1379896Y871034D01*
G02X1379968Y870606I-1225J-426D01*
G02X1377374I-1297J0D01*
G02X1378429Y871881I1298J0D01*
G01X1378519Y871898D01*
X1379326Y873295D01*
X1379295Y873382D01*
G02X1379222Y873810I1225J429D01*
G37*
G36*
G01X1386622D02*
G02X1389218I1298J0D01*
G02X1389145Y873381I-1297J0D01*
G01X1389114Y873295D01*
X1389920Y871898D01*
X1390010Y871881D01*
G02X1391068Y870606I-239J-1275D01*
G02X1388474I-1297J0D01*
G02X1388545Y871032I1297J3D01*
G01X1388576Y871119D01*
X1387768Y872518D01*
X1387678Y872535D01*
G02X1386622Y873810I242J1275D01*
G37*
G36*
G01X1394022D02*
G02X1396618I1298J0D01*
G02X1396545Y873381I-1297J0D01*
G01X1396514Y873295D01*
X1397320Y871898D01*
X1397410Y871881D01*
G02X1398468Y870606I-239J-1275D01*
G02X1395874I-1297J0D01*
G02X1395945Y871032I1297J3D01*
G01X1395976Y871119D01*
X1395168Y872518D01*
X1395078Y872535D01*
G02X1394022Y873810I242J1275D01*
G37*
G36*
G01X1401422D02*
G02X1404018I1298J0D01*
G02X1403945Y873381I-1297J0D01*
G01X1403914Y873295D01*
X1404720Y871898D01*
X1404810Y871881D01*
G02X1405868Y870606I-239J-1275D01*
G02X1403274I-1297J0D01*
G02X1403345Y871032I1297J3D01*
G01X1403376Y871119D01*
X1402568Y872518D01*
X1402478Y872535D01*
G02X1401422Y873810I242J1275D01*
G37*
G36*
G01X1408824D02*
G02X1411418I1297J0D01*
G02X1411346Y873381I-1297J-3D01*
G01X1411315Y873295D01*
X1412121Y871898D01*
X1412211Y871881D01*
G02X1413268Y870606I-240J-1275D01*
G02X1410674I-1297J0D01*
G01Y870608D01*
G02X1410746Y871033I1297J-1D01*
G01X1410776Y871120D01*
X1409969Y872518D01*
X1409879Y872535D01*
G02X1408824Y873810I243J1275D01*
G37*
G36*
G01X1416222D02*
G02X1418818I1298J0D01*
G02X1418745Y873381I-1297J0D01*
G01X1418714Y873295D01*
X1419520Y871898D01*
X1419610Y871881D01*
G02X1420668Y870606I-239J-1275D01*
G02X1418074I-1297J0D01*
G02X1418145Y871032I1297J3D01*
G01X1418176Y871119D01*
X1417368Y872518D01*
X1417278Y872535D01*
G02X1416222Y873810I242J1275D01*
G37*
G36*
G01X1423624D02*
G02X1426218I1297J0D01*
G02X1426146Y873381I-1297J-3D01*
G01X1426115Y873295D01*
X1426921Y871898D01*
X1427011Y871881D01*
G02X1428068Y870606I-240J-1275D01*
G02X1425474I-1297J0D01*
G01Y870608D01*
G02X1425546Y871033I1297J-1D01*
G01X1425576Y871120D01*
X1424769Y872518D01*
X1424679Y872535D01*
G02X1423624Y873810I243J1275D01*
G37*
G36*
G01X1431022D02*
G02X1433618I1298J0D01*
G02X1433545Y873381I-1297J0D01*
G01X1433514Y873295D01*
X1434320Y871898D01*
X1434410Y871881D01*
G02X1435468Y870606I-239J-1275D01*
G02X1432874I-1297J0D01*
G02X1432945Y871032I1297J3D01*
G01X1432976Y871119D01*
X1432168Y872518D01*
X1432078Y872535D01*
G02X1431022Y873810I242J1275D01*
G37*
G36*
G01X1438422D02*
G02X1441018I1298J0D01*
G02X1440945Y873381I-1297J0D01*
G01X1440914Y873295D01*
X1441720Y871898D01*
X1441810Y871881D01*
G02X1442868Y870606I-239J-1275D01*
G02X1440274I-1297J0D01*
G02X1440345Y871032I1297J3D01*
G01X1440376Y871119D01*
X1439568Y872518D01*
X1439478Y872535D01*
G02X1438422Y873810I242J1275D01*
G37*
G36*
G01X1453222D02*
G02X1455818I1298J0D01*
G02X1455745Y873381I-1297J0D01*
G01X1455714Y873295D01*
X1456520Y871898D01*
X1456610Y871881D01*
G02X1457668Y870606I-239J-1275D01*
G02X1455074I-1297J0D01*
G02X1455145Y871032I1297J3D01*
G01X1455176Y871119D01*
X1454368Y872518D01*
X1454278Y872535D01*
G02X1453222Y873810I242J1275D01*
G37*
G36*
G01X1460622D02*
G02X1463218I1298J0D01*
G02X1463145Y873381I-1297J0D01*
G01X1463114Y873295D01*
X1463920Y871898D01*
X1464010Y871881D01*
G02X1465068Y870606I-239J-1275D01*
G02X1462474I-1297J0D01*
G02X1462545Y871032I1297J3D01*
G01X1462576Y871119D01*
X1461768Y872518D01*
X1461678Y872535D01*
G02X1460622Y873810I242J1275D01*
G37*
G36*
G01X1468022D02*
G02X1470618I1298J0D01*
G02X1470545Y873381I-1297J0D01*
G01X1470514Y873295D01*
X1471320Y871898D01*
X1471410Y871881D01*
G02X1472468Y870606I-239J-1275D01*
G02X1469874I-1297J0D01*
G02X1469945Y871032I1297J3D01*
G01X1469976Y871119D01*
X1469168Y872518D01*
X1469078Y872535D01*
G02X1468022Y873810I242J1275D01*
G37*
G36*
G01X1475422D02*
G02X1478018I1298J0D01*
G02X1477945Y873381I-1297J0D01*
G01X1477914Y873295D01*
X1478720Y871898D01*
X1478810Y871881D01*
G02X1479868Y870606I-239J-1275D01*
G02X1477274I-1297J0D01*
G02X1477345Y871032I1297J3D01*
G01X1477376Y871119D01*
X1476568Y872518D01*
X1476478Y872535D01*
G02X1475422Y873810I242J1275D01*
G37*
G36*
G01X1482822D02*
G02X1485418I1298J0D01*
G02X1485345Y873381I-1297J0D01*
G01X1485314Y873295D01*
X1486120Y871898D01*
X1486210Y871881D01*
G02X1487268Y870606I-239J-1275D01*
G02X1484674I-1297J0D01*
G02X1484745Y871032I1297J3D01*
G01X1484776Y871119D01*
X1483968Y872518D01*
X1483878Y872535D01*
G02X1482822Y873810I242J1275D01*
G37*
G36*
G01X1490222D02*
G02X1492818I1298J0D01*
G02X1492745Y873381I-1297J0D01*
G01X1492714Y873295D01*
X1493520Y871898D01*
X1493610Y871881D01*
G02X1494668Y870606I-239J-1275D01*
G02X1492074I-1297J0D01*
G02X1492145Y871032I1297J3D01*
G01X1492176Y871119D01*
X1491368Y872518D01*
X1491278Y872535D01*
G02X1490222Y873810I242J1275D01*
G37*
G36*
G01X367932Y883423D02*
G02X370526I1297J0D01*
G02X370454Y882994I-1297J-3D01*
G01X370423Y882908D01*
X371229Y881511D01*
X371319Y881494D01*
G02X372376Y880219I-240J-1275D01*
G02X369780I-1298J0D01*
G02X369853Y880647I1298J-1D01*
G01X369883Y880734D01*
X369077Y882131D01*
X368987Y882148D01*
G02X367932Y883423I243J1275D01*
G37*
G36*
G01X375332D02*
G02X377926I1297J0D01*
G02X377854Y882994I-1297J-3D01*
G01X377823Y882908D01*
X378629Y881511D01*
X378719Y881494D01*
G02X379776Y880219I-240J-1275D01*
G02X377180I-1298J0D01*
G02X377253Y880647I1298J-1D01*
G01X377283Y880734D01*
X376477Y882131D01*
X376387Y882148D01*
G02X375332Y883423I243J1275D01*
G37*
G36*
G01X382732D02*
G02X385326I1297J0D01*
G02X385254Y882994I-1297J-3D01*
G01X385223Y882908D01*
X386029Y881511D01*
X386119Y881494D01*
G02X387176Y880219I-240J-1275D01*
G02X384580I-1298J0D01*
G02X384653Y880647I1298J-1D01*
G01X384683Y880734D01*
X383877Y882131D01*
X383787Y882148D01*
G02X382732Y883423I243J1275D01*
G37*
G36*
G01X390132D02*
G02X392726I1297J0D01*
G02X392654Y882994I-1297J-3D01*
G01X392623Y882908D01*
X393429Y881511D01*
X393519Y881494D01*
G02X394576Y880219I-240J-1275D01*
G02X391980I-1298J0D01*
G02X392053Y880647I1298J-1D01*
G01X392083Y880734D01*
X391277Y882131D01*
X391187Y882148D01*
G02X390132Y883423I243J1275D01*
G37*
G36*
G01X397532D02*
G02X400126I1297J0D01*
G02X400054Y882994I-1297J-3D01*
G01X400023Y882908D01*
X400829Y881511D01*
X400919Y881494D01*
G02X401976Y880219I-240J-1275D01*
G02X399380I-1298J0D01*
G02X399453Y880647I1298J-1D01*
G01X399483Y880734D01*
X398677Y882131D01*
X398587Y882148D01*
G02X397532Y883423I243J1275D01*
G37*
G36*
G01X404932D02*
G02X407526I1297J0D01*
G02X407454Y882994I-1297J-3D01*
G01X407423Y882908D01*
X408229Y881511D01*
X408319Y881494D01*
G02X409376Y880219I-240J-1275D01*
G02X406780I-1298J0D01*
G02X406853Y880647I1298J-1D01*
G01X406883Y880734D01*
X406077Y882131D01*
X405987Y882148D01*
G02X404932Y883423I243J1275D01*
G37*
G36*
G01X412332D02*
G02X414926I1297J0D01*
G02X414854Y882994I-1297J-3D01*
G01X414823Y882908D01*
X415629Y881511D01*
X415719Y881494D01*
G02X416776Y880219I-240J-1275D01*
G02X414180I-1298J0D01*
G02X414253Y880647I1298J-1D01*
G01X414283Y880734D01*
X413477Y882131D01*
X413387Y882148D01*
G02X412332Y883423I243J1275D01*
G37*
G36*
G01X419732D02*
G02X422326I1297J0D01*
G02X422254Y882994I-1297J-3D01*
G01X422223Y882908D01*
X423029Y881511D01*
X423119Y881494D01*
G02X424176Y880219I-240J-1275D01*
G02X421580I-1298J0D01*
G02X421653Y880647I1298J-1D01*
G01X421683Y880734D01*
X420877Y882131D01*
X420787Y882148D01*
G02X419732Y883423I243J1275D01*
G37*
G36*
G01X427132D02*
G02X429726I1297J0D01*
G02X429654Y882994I-1297J-3D01*
G01X429623Y882908D01*
X430429Y881511D01*
X430519Y881494D01*
G02X431576Y880219I-240J-1275D01*
G02X428980I-1298J0D01*
G02X429053Y880647I1298J-1D01*
G01X429083Y880734D01*
X428277Y882131D01*
X428187Y882148D01*
G02X427132Y883423I243J1275D01*
G37*
G36*
G01X434532D02*
G02X437126I1297J0D01*
G02X437054Y882994I-1297J-3D01*
G01X437023Y882908D01*
X437829Y881511D01*
X437919Y881494D01*
G02X438976Y880219I-240J-1275D01*
G02X436380I-1298J0D01*
G02X436453Y880647I1298J-1D01*
G01X436483Y880734D01*
X435677Y882131D01*
X435587Y882148D01*
G02X434532Y883423I243J1275D01*
G37*
G36*
G01X441932D02*
G02X444526I1297J0D01*
G02X444454Y882994I-1297J-3D01*
G01X444423Y882908D01*
X445229Y881511D01*
X445319Y881494D01*
G02X446376Y880219I-240J-1275D01*
G02X443780I-1298J0D01*
G02X443853Y880647I1298J-1D01*
G01X443883Y880734D01*
X443077Y882131D01*
X442987Y882148D01*
G02X441932Y883423I243J1275D01*
G37*
G36*
G01X449332D02*
G02X451926I1297J0D01*
G02X451854Y882994I-1297J-3D01*
G01X451823Y882908D01*
X452629Y881511D01*
X452719Y881494D01*
G02X453776Y880219I-240J-1275D01*
G02X451182I-1297J0D01*
G01Y880221D01*
G02X451254Y880646I1297J-1D01*
G01X451284Y880733D01*
X450477Y882131D01*
X450387Y882148D01*
G02X449332Y883423I243J1275D01*
G37*
G36*
G01X456732D02*
G02X459326I1297J0D01*
G02X459254Y882994I-1297J-3D01*
G01X459223Y882908D01*
X460029Y881511D01*
X460119Y881494D01*
G02X461176Y880219I-240J-1275D01*
G02X458580I-1298J0D01*
G02X458653Y880647I1298J-1D01*
G01X458683Y880734D01*
X457877Y882131D01*
X457787Y882148D01*
G02X456732Y883423I243J1275D01*
G37*
G36*
G01X464132D02*
G02X466726I1297J0D01*
G02X466654Y882994I-1297J-3D01*
G01X466623Y882908D01*
X467429Y881511D01*
X467519Y881494D01*
G02X468576Y880219I-240J-1275D01*
G02X465980I-1298J0D01*
G02X466053Y880647I1298J-1D01*
G01X466083Y880734D01*
X465277Y882131D01*
X465187Y882148D01*
G02X464132Y883423I243J1275D01*
G37*
G36*
G01X471532D02*
G02X474126I1297J0D01*
G02X474054Y882994I-1297J-3D01*
G01X474023Y882908D01*
X474829Y881511D01*
X474919Y881494D01*
G02X475976Y880219I-240J-1275D01*
G02X473380I-1298J0D01*
G02X473453Y880647I1298J-1D01*
G01X473483Y880734D01*
X472677Y882131D01*
X472587Y882148D01*
G02X471532Y883423I243J1275D01*
G37*
G36*
G01X478932D02*
G02X481526I1297J0D01*
G02X481454Y882994I-1297J-3D01*
G01X481423Y882908D01*
X482229Y881511D01*
X482319Y881494D01*
G02X483376Y880219I-240J-1275D01*
G02X480780I-1298J0D01*
G02X480853Y880647I1298J-1D01*
G01X480883Y880734D01*
X480077Y882131D01*
X479987Y882148D01*
G02X478932Y883423I243J1275D01*
G37*
G36*
G01X486332D02*
G02X488926I1297J0D01*
G02X488854Y882994I-1297J-3D01*
G01X488823Y882908D01*
X489629Y881511D01*
X489719Y881494D01*
G02X490776Y880219I-240J-1275D01*
G02X488180I-1298J0D01*
G02X488253Y880647I1298J-1D01*
G01X488283Y880734D01*
X487477Y882131D01*
X487387Y882148D01*
G02X486332Y883423I243J1275D01*
G37*
G36*
G01X493732D02*
G02X496326I1297J0D01*
G02X496254Y882994I-1297J-3D01*
G01X496223Y882908D01*
X497029Y881511D01*
X497119Y881494D01*
G02X498176Y880219I-240J-1275D01*
G02X495580I-1298J0D01*
G02X495653Y880647I1298J-1D01*
G01X495683Y880734D01*
X494877Y882131D01*
X494787Y882148D01*
G02X493732Y883423I243J1275D01*
G37*
G36*
G01X501132D02*
G02X503726I1297J0D01*
G02X503654Y882994I-1297J-3D01*
G01X503623Y882908D01*
X504429Y881511D01*
X504519Y881494D01*
G02X505576Y880219I-240J-1275D01*
G02X502980I-1298J0D01*
G02X503053Y880647I1298J-1D01*
G01X503083Y880734D01*
X502277Y882131D01*
X502187Y882148D01*
G02X501132Y883423I243J1275D01*
G37*
G36*
G01X508532D02*
G02X511126I1297J0D01*
G02X511054Y882994I-1297J-3D01*
G01X511023Y882908D01*
X511829Y881511D01*
X511919Y881494D01*
G02X512976Y880219I-240J-1275D01*
G02X510380I-1298J0D01*
G02X510453Y880647I1298J-1D01*
G01X510483Y880734D01*
X509677Y882131D01*
X509587Y882148D01*
G02X508532Y883423I243J1275D01*
G37*
G36*
G01X1344074D02*
G02X1346668I1297J0D01*
G02X1346596Y882994I-1297J-3D01*
G01X1346565Y882908D01*
X1347371Y881511D01*
X1347461Y881494D01*
G02X1348518Y880219I-240J-1275D01*
G02X1345922I-1298J0D01*
G02X1345995Y880647I1298J-1D01*
G01X1346025Y880734D01*
X1345219Y882131D01*
X1345129Y882148D01*
G02X1344074Y883423I243J1275D01*
G37*
G36*
G01X1351474D02*
G02X1354068I1297J0D01*
G02X1353996Y882994I-1297J-3D01*
G01X1353965Y882908D01*
X1354771Y881511D01*
X1354861Y881494D01*
G02X1355918Y880219I-240J-1275D01*
G02X1353322I-1298J0D01*
G02X1353395Y880647I1298J-1D01*
G01X1353425Y880734D01*
X1352619Y882131D01*
X1352529Y882148D01*
G02X1351474Y883423I243J1275D01*
G37*
G36*
G01X1358874D02*
G02X1361468I1297J0D01*
G02X1361396Y882994I-1297J-3D01*
G01X1361365Y882908D01*
X1362171Y881511D01*
X1362261Y881494D01*
G02X1363318Y880219I-240J-1275D01*
G02X1360722I-1298J0D01*
G02X1360795Y880647I1298J-1D01*
G01X1360825Y880734D01*
X1360019Y882131D01*
X1359929Y882148D01*
G02X1358874Y883423I243J1275D01*
G37*
G36*
G01X1366274D02*
G02X1368868I1297J0D01*
G02X1368796Y882994I-1297J-3D01*
G01X1368765Y882908D01*
X1369571Y881511D01*
X1369661Y881494D01*
G02X1370718Y880219I-240J-1275D01*
G02X1368122I-1298J0D01*
G02X1368195Y880647I1298J-1D01*
G01X1368225Y880734D01*
X1367419Y882131D01*
X1367329Y882148D01*
G02X1366274Y883423I243J1275D01*
G37*
G36*
G01X1373674D02*
G02X1376268I1297J0D01*
G02X1376196Y882994I-1297J-3D01*
G01X1376165Y882908D01*
X1376971Y881511D01*
X1377061Y881494D01*
G02X1378118Y880219I-240J-1275D01*
G02X1375522I-1298J0D01*
G02X1375595Y880647I1298J-1D01*
G01X1375625Y880734D01*
X1374819Y882131D01*
X1374729Y882148D01*
G02X1373674Y883423I243J1275D01*
G37*
G36*
G01X1381074D02*
G02X1383668I1297J0D01*
G02X1383596Y882994I-1297J-3D01*
G01X1383565Y882908D01*
X1384371Y881511D01*
X1384461Y881494D01*
G02X1385518Y880219I-240J-1275D01*
G02X1382922I-1298J0D01*
G02X1382995Y880647I1298J-1D01*
G01X1383025Y880734D01*
X1382219Y882131D01*
X1382129Y882148D01*
G02X1381074Y883423I243J1275D01*
G37*
G36*
G01X1388474D02*
G02X1391068I1297J0D01*
G02X1390996Y882994I-1297J-3D01*
G01X1390965Y882908D01*
X1391771Y881511D01*
X1391861Y881494D01*
G02X1392918Y880219I-240J-1275D01*
G02X1390322I-1298J0D01*
G02X1390395Y880647I1298J-1D01*
G01X1390425Y880734D01*
X1389619Y882131D01*
X1389529Y882148D01*
G02X1388474Y883423I243J1275D01*
G37*
G36*
G01X1395874D02*
G02X1398468I1297J0D01*
G02X1398396Y882994I-1297J-3D01*
G01X1398365Y882908D01*
X1399171Y881511D01*
X1399261Y881494D01*
G02X1400318Y880219I-240J-1275D01*
G02X1397722I-1298J0D01*
G02X1397795Y880647I1298J-1D01*
G01X1397825Y880734D01*
X1397019Y882131D01*
X1396929Y882148D01*
G02X1395874Y883423I243J1275D01*
G37*
G36*
G01X1403274D02*
G02X1405868I1297J0D01*
G02X1405796Y882994I-1297J-3D01*
G01X1405765Y882908D01*
X1406571Y881511D01*
X1406661Y881494D01*
G02X1407718Y880219I-240J-1275D01*
G02X1405122I-1298J0D01*
G02X1405195Y880647I1298J-1D01*
G01X1405225Y880734D01*
X1404419Y882131D01*
X1404329Y882148D01*
G02X1403274Y883423I243J1275D01*
G37*
G36*
G01X1410674D02*
G02X1413268I1297J0D01*
G02X1413196Y882994I-1297J-3D01*
G01X1413165Y882908D01*
X1413971Y881511D01*
X1414061Y881494D01*
G02X1415118Y880219I-240J-1275D01*
G02X1412522I-1298J0D01*
G02X1412595Y880647I1298J-1D01*
G01X1412625Y880734D01*
X1411819Y882131D01*
X1411729Y882148D01*
G02X1410674Y883423I243J1275D01*
G37*
G36*
G01X1418074D02*
G02X1420668I1297J0D01*
G02X1420596Y882994I-1297J-3D01*
G01X1420565Y882908D01*
X1421371Y881511D01*
X1421461Y881494D01*
G02X1422518Y880219I-240J-1275D01*
G02X1419922I-1298J0D01*
G02X1419995Y880647I1298J-1D01*
G01X1420025Y880734D01*
X1419219Y882131D01*
X1419129Y882148D01*
G02X1418074Y883423I243J1275D01*
G37*
G36*
G01X1425474D02*
G02X1428068I1297J0D01*
G02X1427996Y882994I-1297J-3D01*
G01X1427965Y882908D01*
X1428771Y881511D01*
X1428861Y881494D01*
G02X1429918Y880219I-240J-1275D01*
G02X1427324I-1297J0D01*
G01Y880221D01*
G02X1427396Y880646I1297J-1D01*
G01X1427426Y880733D01*
X1426619Y882131D01*
X1426529Y882148D01*
G02X1425474Y883423I243J1275D01*
G37*
G36*
G01X1432874D02*
G02X1435468I1297J0D01*
G02X1435396Y882994I-1297J-3D01*
G01X1435365Y882908D01*
X1436171Y881511D01*
X1436261Y881494D01*
G02X1437318Y880219I-240J-1275D01*
G02X1434722I-1298J0D01*
G02X1434795Y880647I1298J-1D01*
G01X1434825Y880734D01*
X1434019Y882131D01*
X1433929Y882148D01*
G02X1432874Y883423I243J1275D01*
G37*
G36*
G01X1440274D02*
G02X1442868I1297J0D01*
G02X1442796Y882994I-1297J-3D01*
G01X1442765Y882908D01*
X1443571Y881511D01*
X1443661Y881494D01*
G02X1444718Y880219I-240J-1275D01*
G02X1442122I-1298J0D01*
G02X1442195Y880647I1298J-1D01*
G01X1442225Y880734D01*
X1441419Y882131D01*
X1441329Y882148D01*
G02X1440274Y883423I243J1275D01*
G37*
G36*
G01X1447674D02*
G02X1450268I1297J0D01*
G02X1450196Y882994I-1297J-3D01*
G01X1450165Y882908D01*
X1450971Y881511D01*
X1451061Y881494D01*
G02X1452118Y880219I-240J-1275D01*
G02X1449522I-1298J0D01*
G02X1449595Y880647I1298J-1D01*
G01X1449625Y880734D01*
X1448819Y882131D01*
X1448729Y882148D01*
G02X1447674Y883423I243J1275D01*
G37*
G36*
G01X1455074D02*
G02X1457668I1297J0D01*
G02X1457596Y882994I-1297J-3D01*
G01X1457565Y882908D01*
X1458371Y881511D01*
X1458461Y881494D01*
G02X1459518Y880219I-240J-1275D01*
G02X1456922I-1298J0D01*
G02X1456995Y880647I1298J-1D01*
G01X1457025Y880734D01*
X1456219Y882131D01*
X1456129Y882148D01*
G02X1455074Y883423I243J1275D01*
G37*
G36*
G01X1462474D02*
G02X1465068I1297J0D01*
G02X1464996Y882994I-1297J-3D01*
G01X1464965Y882908D01*
X1465771Y881511D01*
X1465861Y881494D01*
G02X1466918Y880219I-240J-1275D01*
G02X1464322I-1298J0D01*
G02X1464395Y880647I1298J-1D01*
G01X1464425Y880734D01*
X1463619Y882131D01*
X1463529Y882148D01*
G02X1462474Y883423I243J1275D01*
G37*
G36*
G01X1469874D02*
G02X1472468I1297J0D01*
G02X1472396Y882994I-1297J-3D01*
G01X1472365Y882908D01*
X1473171Y881511D01*
X1473261Y881494D01*
G02X1474318Y880219I-240J-1275D01*
G02X1471722I-1298J0D01*
G02X1471795Y880647I1298J-1D01*
G01X1471825Y880734D01*
X1471019Y882131D01*
X1470929Y882148D01*
G02X1469874Y883423I243J1275D01*
G37*
G36*
G01X1477274D02*
G02X1479868I1297J0D01*
G02X1479796Y882994I-1297J-3D01*
G01X1479765Y882908D01*
X1480571Y881511D01*
X1480661Y881494D01*
G02X1481718Y880219I-240J-1275D01*
G02X1479122I-1298J0D01*
G02X1479195Y880647I1298J-1D01*
G01X1479225Y880734D01*
X1478419Y882131D01*
X1478329Y882148D01*
G02X1477274Y883423I243J1275D01*
G37*
G36*
G01X1484674D02*
G02X1487268I1297J0D01*
G02X1487196Y882994I-1297J-3D01*
G01X1487165Y882908D01*
X1487971Y881511D01*
X1488061Y881494D01*
G02X1489118Y880219I-240J-1275D01*
G02X1486522I-1298J0D01*
G02X1486595Y880647I1298J-1D01*
G01X1486625Y880734D01*
X1485819Y882131D01*
X1485729Y882148D01*
G02X1484674Y883423I243J1275D01*
G37*
G36*
G01X373480Y886627D02*
G02X376076I1298J0D01*
G02X375020Y885352I-1298J0D01*
G01X374930Y885335D01*
X374123Y883938D01*
X374154Y883851D01*
G02X374226Y883423I-1225J-426D01*
G02X371632I-1297J0D01*
G02X372687Y884698I1298J0D01*
G01X372777Y884715D01*
X373584Y886112D01*
X373553Y886199D01*
G02X373480Y886627I1225J429D01*
G37*
G36*
G01X380880D02*
G02X383476I1298J0D01*
G02X382420Y885352I-1298J0D01*
G01X382330Y885335D01*
X381523Y883938D01*
X381554Y883851D01*
G02X381626Y883423I-1225J-426D01*
G02X379032I-1297J0D01*
G02X380087Y884698I1298J0D01*
G01X380177Y884715D01*
X380984Y886112D01*
X380953Y886199D01*
G02X380880Y886627I1225J429D01*
G37*
G36*
G01X388280D02*
G02X390876I1298J0D01*
G02X389820Y885352I-1298J0D01*
G01X389730Y885335D01*
X388923Y883938D01*
X388954Y883851D01*
G02X389026Y883423I-1225J-426D01*
G02X386432I-1297J0D01*
G02X387487Y884698I1298J0D01*
G01X387577Y884715D01*
X388384Y886112D01*
X388353Y886199D01*
G02X388280Y886627I1225J429D01*
G37*
G36*
G01X395680D02*
G02X398276I1298J0D01*
G02X397220Y885352I-1298J0D01*
G01X397130Y885335D01*
X396323Y883938D01*
X396354Y883851D01*
G02X396426Y883423I-1225J-426D01*
G02X393832I-1297J0D01*
G02X394887Y884698I1298J0D01*
G01X394977Y884715D01*
X395784Y886112D01*
X395753Y886199D01*
G02X395680Y886627I1225J429D01*
G37*
G36*
G01X403080D02*
G02X405676I1298J0D01*
G02X404620Y885352I-1298J0D01*
G01X404530Y885335D01*
X403723Y883938D01*
X403754Y883851D01*
G02X403826Y883423I-1225J-426D01*
G02X401232I-1297J0D01*
G02X402287Y884698I1298J0D01*
G01X402377Y884715D01*
X403184Y886112D01*
X403153Y886199D01*
G02X403080Y886627I1225J429D01*
G37*
G36*
G01X410480D02*
G02X413076I1298J0D01*
G02X412020Y885352I-1298J0D01*
G01X411930Y885335D01*
X411123Y883938D01*
X411154Y883851D01*
G02X411226Y883423I-1225J-426D01*
G02X408632I-1297J0D01*
G02X409687Y884698I1298J0D01*
G01X409777Y884715D01*
X410584Y886112D01*
X410553Y886199D01*
G02X410480Y886627I1225J429D01*
G37*
G36*
G01X417880D02*
G02X420476I1298J0D01*
G02X419420Y885352I-1298J0D01*
G01X419330Y885335D01*
X418523Y883938D01*
X418554Y883851D01*
G02X418626Y883423I-1225J-426D01*
G02X416032I-1297J0D01*
G02X417087Y884698I1298J0D01*
G01X417177Y884715D01*
X417984Y886112D01*
X417953Y886199D01*
G02X417880Y886627I1225J429D01*
G37*
G36*
G01X425280D02*
G02X427876I1298J0D01*
G02X426820Y885352I-1298J0D01*
G01X426730Y885335D01*
X425923Y883938D01*
X425954Y883851D01*
G02X426026Y883423I-1225J-426D01*
G02X423432I-1297J0D01*
G02X424487Y884698I1298J0D01*
G01X424577Y884715D01*
X425384Y886112D01*
X425353Y886199D01*
G02X425280Y886627I1225J429D01*
G37*
G36*
G01X432680D02*
G02X435276I1298J0D01*
G02X434220Y885352I-1298J0D01*
G01X434130Y885335D01*
X433323Y883938D01*
X433354Y883851D01*
G02X433426Y883423I-1225J-426D01*
G02X430832I-1297J0D01*
G02X431887Y884698I1298J0D01*
G01X431977Y884715D01*
X432784Y886112D01*
X432753Y886199D01*
G02X432680Y886627I1225J429D01*
G37*
G36*
G01X440080D02*
G02X442676I1298J0D01*
G02X441620Y885352I-1298J0D01*
G01X441530Y885335D01*
X440723Y883938D01*
X440754Y883851D01*
G02X440826Y883423I-1225J-426D01*
G02X438232I-1297J0D01*
G02X439287Y884698I1298J0D01*
G01X439377Y884715D01*
X440184Y886112D01*
X440153Y886199D01*
G02X440080Y886627I1225J429D01*
G37*
G36*
G01X447480D02*
G02X450076I1298J0D01*
G02X449020Y885352I-1298J0D01*
G01X448930Y885335D01*
X448123Y883938D01*
X448154Y883851D01*
G02X448226Y883423I-1225J-426D01*
G02X445632I-1297J0D01*
G02X446687Y884698I1298J0D01*
G01X446777Y884715D01*
X447584Y886112D01*
X447553Y886199D01*
G02X447480Y886627I1225J429D01*
G37*
G36*
G01X454880D02*
G02X457476I1298J0D01*
G02X456420Y885352I-1298J0D01*
G01X456330Y885335D01*
X455523Y883938D01*
X455554Y883851D01*
G02X455626Y883423I-1225J-426D01*
G02X453032I-1297J0D01*
G02X454087Y884698I1298J0D01*
G01X454177Y884715D01*
X454984Y886112D01*
X454953Y886199D01*
G02X454880Y886627I1225J429D01*
G37*
G36*
G01X462280D02*
G02X464876I1298J0D01*
G02X463820Y885352I-1298J0D01*
G01X463730Y885335D01*
X462923Y883938D01*
X462954Y883851D01*
G02X463026Y883423I-1225J-426D01*
G02X460432I-1297J0D01*
G02X461487Y884698I1298J0D01*
G01X461577Y884715D01*
X462384Y886112D01*
X462353Y886199D01*
G02X462280Y886627I1225J429D01*
G37*
G36*
G01X469680D02*
G02X472276I1298J0D01*
G02X471220Y885352I-1298J0D01*
G01X471130Y885335D01*
X470323Y883938D01*
X470354Y883851D01*
G02X470426Y883423I-1225J-426D01*
G02X467832I-1297J0D01*
G02X468887Y884698I1298J0D01*
G01X468977Y884715D01*
X469784Y886112D01*
X469753Y886199D01*
G02X469680Y886627I1225J429D01*
G37*
G36*
G01X477080D02*
G02X479676I1298J0D01*
G02X478620Y885352I-1298J0D01*
G01X478530Y885335D01*
X477723Y883938D01*
X477754Y883851D01*
G02X477826Y883423I-1225J-426D01*
G02X475232I-1297J0D01*
G02X476287Y884698I1298J0D01*
G01X476377Y884715D01*
X477184Y886112D01*
X477153Y886199D01*
G02X477080Y886627I1225J429D01*
G37*
G36*
G01X484480D02*
G02X487076I1298J0D01*
G02X486020Y885352I-1298J0D01*
G01X485930Y885335D01*
X485123Y883938D01*
X485154Y883851D01*
G02X485226Y883423I-1225J-426D01*
G02X482632I-1297J0D01*
G02X483687Y884698I1298J0D01*
G01X483777Y884715D01*
X484584Y886112D01*
X484553Y886199D01*
G02X484480Y886627I1225J429D01*
G37*
G36*
G01X491880D02*
G02X494476I1298J0D01*
G02X493420Y885352I-1298J0D01*
G01X493330Y885335D01*
X492523Y883938D01*
X492554Y883851D01*
G02X492626Y883423I-1225J-426D01*
G02X490032I-1297J0D01*
G02X491087Y884698I1298J0D01*
G01X491177Y884715D01*
X491984Y886112D01*
X491953Y886199D01*
G02X491880Y886627I1225J429D01*
G37*
G36*
G01X499280D02*
G02X501876I1298J0D01*
G02X500820Y885352I-1298J0D01*
G01X500730Y885335D01*
X499923Y883938D01*
X499954Y883851D01*
G02X500026Y883423I-1225J-426D01*
G02X497432I-1297J0D01*
G02X498487Y884698I1298J0D01*
G01X498577Y884715D01*
X499384Y886112D01*
X499353Y886199D01*
G02X499280Y886627I1225J429D01*
G37*
G36*
G01X506680D02*
G02X509276I1298J0D01*
G02X508220Y885352I-1298J0D01*
G01X508130Y885335D01*
X507323Y883938D01*
X507354Y883851D01*
G02X507426Y883423I-1225J-426D01*
G02X504832I-1297J0D01*
G02X505887Y884698I1298J0D01*
G01X505977Y884715D01*
X506784Y886112D01*
X506753Y886199D01*
G02X506680Y886627I1225J429D01*
G37*
G36*
G01X514080D02*
G02X516676I1298J0D01*
G02X515620Y885352I-1298J0D01*
G01X515530Y885335D01*
X514723Y883938D01*
X514754Y883851D01*
G02X514826Y883423I-1225J-426D01*
G02X512232I-1297J0D01*
G02X513287Y884698I1298J0D01*
G01X513377Y884715D01*
X514184Y886112D01*
X514153Y886199D01*
G02X514080Y886627I1225J429D01*
G37*
G36*
G01X521480D02*
G02X524076I1298J0D01*
G02X523020Y885352I-1298J0D01*
G01X522930Y885335D01*
X522123Y883938D01*
X522154Y883851D01*
G02X522226Y883423I-1225J-426D01*
G02X519632I-1297J0D01*
G02X520687Y884698I1298J0D01*
G01X520777Y884715D01*
X521584Y886112D01*
X521553Y886199D01*
G02X521480Y886627I1225J429D01*
G37*
G36*
G01X1349622D02*
G02X1352218I1298J0D01*
G02X1351162Y885352I-1298J0D01*
G01X1351072Y885335D01*
X1350265Y883938D01*
X1350296Y883851D01*
G02X1350368Y883423I-1225J-426D01*
G02X1347774I-1297J0D01*
G02X1348829Y884698I1298J0D01*
G01X1348919Y884715D01*
X1349726Y886112D01*
X1349695Y886199D01*
G02X1349622Y886627I1225J429D01*
G37*
G36*
G01X1357022D02*
G02X1359618I1298J0D01*
G02X1358562Y885352I-1298J0D01*
G01X1358472Y885335D01*
X1357665Y883938D01*
X1357696Y883851D01*
G02X1357768Y883423I-1225J-426D01*
G02X1355174I-1297J0D01*
G02X1356229Y884698I1298J0D01*
G01X1356319Y884715D01*
X1357126Y886112D01*
X1357095Y886199D01*
G02X1357022Y886627I1225J429D01*
G37*
G36*
G01X1364422D02*
G02X1367018I1298J0D01*
G02X1365962Y885352I-1298J0D01*
G01X1365872Y885335D01*
X1365065Y883938D01*
X1365096Y883851D01*
G02X1365168Y883423I-1225J-426D01*
G02X1362574I-1297J0D01*
G02X1363629Y884698I1298J0D01*
G01X1363719Y884715D01*
X1364526Y886112D01*
X1364495Y886199D01*
G02X1364422Y886627I1225J429D01*
G37*
G36*
G01X1371822D02*
G02X1374418I1298J0D01*
G02X1373362Y885352I-1298J0D01*
G01X1373272Y885335D01*
X1372465Y883938D01*
X1372496Y883851D01*
G02X1372568Y883423I-1225J-426D01*
G02X1369974I-1297J0D01*
G02X1371029Y884698I1298J0D01*
G01X1371119Y884715D01*
X1371926Y886112D01*
X1371895Y886199D01*
G02X1371822Y886627I1225J429D01*
G37*
G36*
G01X1379222D02*
G02X1381818I1298J0D01*
G02X1380762Y885352I-1298J0D01*
G01X1380672Y885335D01*
X1379865Y883938D01*
X1379896Y883851D01*
G02X1379968Y883423I-1225J-426D01*
G02X1377374I-1297J0D01*
G02X1378429Y884698I1298J0D01*
G01X1378519Y884715D01*
X1379326Y886112D01*
X1379295Y886199D01*
G02X1379222Y886627I1225J429D01*
G37*
G36*
G01X1386622D02*
G02X1389218I1298J0D01*
G02X1388162Y885352I-1298J0D01*
G01X1388072Y885335D01*
X1387265Y883938D01*
X1387296Y883851D01*
G02X1387368Y883423I-1225J-426D01*
G02X1384774I-1297J0D01*
G02X1385829Y884698I1298J0D01*
G01X1385919Y884715D01*
X1386726Y886112D01*
X1386695Y886199D01*
G02X1386622Y886627I1225J429D01*
G37*
G36*
G01X1394022D02*
G02X1396618I1298J0D01*
G02X1395562Y885352I-1298J0D01*
G01X1395472Y885335D01*
X1394665Y883938D01*
X1394696Y883851D01*
G02X1394768Y883423I-1225J-426D01*
G02X1392174I-1297J0D01*
G02X1393229Y884698I1298J0D01*
G01X1393319Y884715D01*
X1394126Y886112D01*
X1394095Y886199D01*
G02X1394022Y886627I1225J429D01*
G37*
G36*
G01X1401422D02*
G02X1404018I1298J0D01*
G02X1402962Y885352I-1298J0D01*
G01X1402872Y885335D01*
X1402065Y883938D01*
X1402096Y883851D01*
G02X1402168Y883423I-1225J-426D01*
G02X1399574I-1297J0D01*
G02X1400629Y884698I1298J0D01*
G01X1400719Y884715D01*
X1401526Y886112D01*
X1401495Y886199D01*
G02X1401422Y886627I1225J429D01*
G37*
G36*
G01X1408822D02*
G02X1411418I1298J0D01*
G02X1410362Y885352I-1298J0D01*
G01X1410272Y885335D01*
X1409465Y883938D01*
X1409496Y883851D01*
G02X1409568Y883423I-1225J-426D01*
G02X1406974I-1297J0D01*
G02X1408029Y884698I1298J0D01*
G01X1408119Y884715D01*
X1408926Y886112D01*
X1408895Y886199D01*
G02X1408822Y886627I1225J429D01*
G37*
G36*
G01X1416222D02*
G02X1418818I1298J0D01*
G02X1417762Y885352I-1298J0D01*
G01X1417672Y885335D01*
X1416865Y883938D01*
X1416896Y883851D01*
G02X1416968Y883423I-1225J-426D01*
G02X1414374I-1297J0D01*
G02X1415429Y884698I1298J0D01*
G01X1415519Y884715D01*
X1416326Y886112D01*
X1416295Y886199D01*
G02X1416222Y886627I1225J429D01*
G37*
G36*
G01X1423622D02*
G02X1426218I1298J0D01*
G02X1425162Y885352I-1298J0D01*
G01X1425072Y885335D01*
X1424265Y883938D01*
X1424296Y883851D01*
G02X1424368Y883423I-1225J-426D01*
G02X1421774I-1297J0D01*
G02X1422829Y884698I1298J0D01*
G01X1422919Y884715D01*
X1423726Y886112D01*
X1423695Y886199D01*
G02X1423622Y886627I1225J429D01*
G37*
G36*
G01X1431022D02*
G02X1433618I1298J0D01*
G02X1432562Y885352I-1298J0D01*
G01X1432472Y885335D01*
X1431665Y883938D01*
X1431696Y883851D01*
G02X1431768Y883423I-1225J-426D01*
G02X1429174I-1297J0D01*
G02X1430229Y884698I1298J0D01*
G01X1430319Y884715D01*
X1431126Y886112D01*
X1431095Y886199D01*
G02X1431022Y886627I1225J429D01*
G37*
G36*
G01X1438422D02*
G02X1441018I1298J0D01*
G02X1439962Y885352I-1298J0D01*
G01X1439872Y885335D01*
X1439065Y883938D01*
X1439096Y883851D01*
G02X1439168Y883423I-1225J-426D01*
G02X1436574I-1297J0D01*
G02X1437629Y884698I1298J0D01*
G01X1437719Y884715D01*
X1438526Y886112D01*
X1438495Y886199D01*
G02X1438422Y886627I1225J429D01*
G37*
G36*
G01X1445822D02*
G02X1448418I1298J0D01*
G02X1447362Y885352I-1298J0D01*
G01X1447272Y885335D01*
X1446465Y883938D01*
X1446496Y883851D01*
G02X1446568Y883423I-1225J-426D01*
G02X1443974I-1297J0D01*
G02X1445029Y884698I1298J0D01*
G01X1445119Y884715D01*
X1445926Y886112D01*
X1445895Y886199D01*
G02X1445822Y886627I1225J429D01*
G37*
G36*
G01X1453222D02*
G02X1455818I1298J0D01*
G02X1454762Y885352I-1298J0D01*
G01X1454672Y885335D01*
X1453865Y883938D01*
X1453896Y883851D01*
G02X1453968Y883423I-1225J-426D01*
G02X1451374I-1297J0D01*
G02X1452429Y884698I1298J0D01*
G01X1452519Y884715D01*
X1453326Y886112D01*
X1453295Y886199D01*
G02X1453222Y886627I1225J429D01*
G37*
G36*
G01X1460622D02*
G02X1463218I1298J0D01*
G02X1462162Y885352I-1298J0D01*
G01X1462072Y885335D01*
X1461265Y883938D01*
X1461296Y883851D01*
G02X1461368Y883423I-1225J-426D01*
G02X1458774I-1297J0D01*
G02X1459829Y884698I1298J0D01*
G01X1459919Y884715D01*
X1460726Y886112D01*
X1460695Y886199D01*
G02X1460622Y886627I1225J429D01*
G37*
G36*
G01X1468022D02*
G02X1470618I1298J0D01*
G02X1469562Y885352I-1298J0D01*
G01X1469472Y885335D01*
X1468665Y883938D01*
X1468696Y883851D01*
G02X1468768Y883423I-1225J-426D01*
G02X1466174I-1297J0D01*
G02X1467229Y884698I1298J0D01*
G01X1467319Y884715D01*
X1468126Y886112D01*
X1468095Y886199D01*
G02X1468022Y886627I1225J429D01*
G37*
G36*
G01X1475422D02*
G02X1478018I1298J0D01*
G02X1476962Y885352I-1298J0D01*
G01X1476872Y885335D01*
X1476065Y883938D01*
X1476096Y883851D01*
G02X1476168Y883423I-1225J-426D01*
G02X1473574I-1297J0D01*
G02X1474629Y884698I1298J0D01*
G01X1474719Y884715D01*
X1475526Y886112D01*
X1475495Y886199D01*
G02X1475422Y886627I1225J429D01*
G37*
G36*
G01X1482822D02*
G02X1485418I1298J0D01*
G02X1484362Y885352I-1298J0D01*
G01X1484272Y885335D01*
X1483465Y883938D01*
X1483496Y883851D01*
G02X1483568Y883423I-1225J-426D01*
G02X1480974I-1297J0D01*
G02X1482029Y884698I1298J0D01*
G01X1482119Y884715D01*
X1482926Y886112D01*
X1482895Y886199D01*
G02X1482822Y886627I1225J429D01*
G37*
G36*
G01X1490222D02*
G02X1492818I1298J0D01*
G02X1491762Y885352I-1298J0D01*
G01X1491672Y885335D01*
X1490865Y883938D01*
X1490896Y883851D01*
G02X1490968Y883423I-1225J-426D01*
G02X1488374I-1297J0D01*
G02X1489429Y884698I1298J0D01*
G01X1489519Y884715D01*
X1490326Y886112D01*
X1490295Y886199D01*
G02X1490222Y886627I1225J429D01*
G37*
G36*
G01X1497622D02*
G02X1500218I1298J0D01*
G02X1499162Y885352I-1298J0D01*
G01X1499072Y885335D01*
X1498265Y883938D01*
X1498296Y883851D01*
G02X1498368Y883423I-1225J-426D01*
G02X1495774I-1297J0D01*
G02X1496829Y884698I1298J0D01*
G01X1496919Y884715D01*
X1497726Y886112D01*
X1497695Y886199D01*
G02X1497622Y886627I1225J429D01*
G37*
G36*
G01X429414Y1079791D02*
G02X432008I1297J0D01*
G02X430953Y1078516I-1298J0D01*
G01X430863Y1078499D01*
X430056Y1077101D01*
X430086Y1077015D01*
G02X430158Y1076587I-1225J-426D01*
G02X427564I-1297J0D01*
G02X428620Y1077862I1298J0D01*
G01X428710Y1077879D01*
X429517Y1079276D01*
X429486Y1079363D01*
G02X429414Y1079791I1225J426D01*
G37*
G36*
G01X1405556D02*
G02X1408150I1297J0D01*
G02X1407095Y1078516I-1298J0D01*
G01X1407005Y1078499D01*
X1406198Y1077101D01*
X1406228Y1077015D01*
G02X1406300Y1076587I-1225J-426D01*
G02X1403706I-1297J0D01*
G02X1404762Y1077862I1298J0D01*
G01X1404852Y1077879D01*
X1405659Y1079276D01*
X1405628Y1079363D01*
G02X1405556Y1079791I1225J426D01*
G37*
G36*
G01X402962Y1084292D02*
G02X404001Y1083772I0J-1298D01*
G01X405623D01*
G02X406662Y1084292I1039J-778D01*
G02Y1081698I0J-1297D01*
G02X405623Y1082218I0J1298D01*
G01X404001D01*
G02X402962Y1081698I-1039J778D01*
G02Y1084292I0J1297D01*
G37*
G36*
G01X409064Y1082995D02*
G02X411660I1298J0D01*
G02X410604Y1081720I-1298J0D01*
G01X410514Y1081703D01*
X409706Y1080304D01*
X409736Y1080218D01*
G02X409808Y1079793I-1225J-426D01*
G01Y1079791D01*
G02X407214I-1297J0D01*
G02X408271Y1081066I1297J0D01*
G01X408361Y1081083D01*
X409168Y1082480D01*
X409137Y1082567D01*
G02X409064Y1082995I1225J429D01*
G37*
G36*
G01X1379104Y1084292D02*
G02X1380143Y1083772I0J-1298D01*
G01X1381765D01*
G02X1382804Y1084292I1039J-778D01*
G02Y1081698I0J-1297D01*
G02X1381765Y1082218I0J1298D01*
G01X1380143D01*
G02X1379104Y1081698I-1039J778D01*
G02Y1084292I0J1297D01*
G37*
G36*
G01X1385206Y1082995D02*
G02X1387802I1298J0D01*
G02X1386746Y1081720I-1298J0D01*
G01X1386656Y1081703D01*
X1385848Y1080304D01*
X1385878Y1080218D01*
G02X1385950Y1079793I-1225J-426D01*
G01Y1079791D01*
G02X1383356I-1297J0D01*
G02X1384413Y1081066I1297J0D01*
G01X1384503Y1081083D01*
X1385310Y1082480D01*
X1385279Y1082567D01*
G02X1385206Y1082995I1225J429D01*
G37*
G36*
G01X410914Y1086200D02*
G02X413508I1297J0D01*
G02X413436Y1085772I-1297J-2D01*
G01X413405Y1085685D01*
X414212Y1084287D01*
X414303Y1084270D01*
G02X415360Y1082995I-240J-1275D01*
G02X412764I-1298J0D01*
G02X412837Y1083422I1298J-2D01*
G01X412867Y1083509D01*
X412059Y1084908D01*
X411969Y1084925D01*
G02X410914Y1086200I243J1275D01*
G37*
G36*
G01X419611Y1087498D02*
G02X420650Y1086978I0J-1298D01*
G01X422272D01*
G02X423311Y1087498I1039J-778D01*
G02Y1084902I0J-1298D01*
G02X422272Y1085422I0J1298D01*
G01X420650D01*
G02X419611Y1084902I-1039J778D01*
G02Y1087498I0J1298D01*
G37*
G36*
G01X425714Y1086200D02*
G02X428310I1298J0D01*
G02X427254Y1084925I-1298J0D01*
G01X427164Y1084908D01*
X426356Y1083510D01*
X426387Y1083423D01*
G02X426460Y1082995I-1225J-429D01*
G02X423864I-1298J0D01*
G02X424920Y1084270I1298J0D01*
G01X425010Y1084287D01*
X425818Y1085685D01*
X425787Y1085772D01*
G02X425714Y1086200I1225J429D01*
G37*
G36*
G01X1387056D02*
G02X1389650I1297J0D01*
G02X1389578Y1085772I-1297J-2D01*
G01X1389547Y1085685D01*
X1390354Y1084287D01*
X1390445Y1084270D01*
G02X1391502Y1082995I-240J-1275D01*
G02X1388906I-1298J0D01*
G02X1388979Y1083422I1298J-2D01*
G01X1389009Y1083509D01*
X1388201Y1084908D01*
X1388111Y1084925D01*
G02X1387056Y1086200I243J1275D01*
G37*
G36*
G01X1395753Y1087498D02*
G02X1396792Y1086978I0J-1298D01*
G01X1398414D01*
G02X1399453Y1087498I1039J-778D01*
G02Y1084902I0J-1298D01*
G02X1398414Y1085422I0J1298D01*
G01X1396792D01*
G02X1395753Y1084902I-1039J778D01*
G02Y1087498I0J1298D01*
G37*
G36*
G01X1401856Y1086200D02*
G02X1404452I1298J0D01*
G02X1403396Y1084925I-1298J0D01*
G01X1403306Y1084908D01*
X1402498Y1083510D01*
X1402529Y1083423D01*
G02X1402602Y1082995I-1225J-429D01*
G02X1400006I-1298J0D01*
G02X1401062Y1084270I1298J0D01*
G01X1401152Y1084287D01*
X1401960Y1085685D01*
X1401929Y1085772D01*
G02X1401856Y1086200I1225J429D01*
G37*
G36*
G01X401664Y1089404D02*
G02X404258I1297J0D01*
G02X404186Y1088976I-1297J-2D01*
G01X404155Y1088889D01*
X404962Y1087492D01*
X405052Y1087475D01*
G02X406108Y1086200I-242J-1275D01*
G02X403514I-1297J0D01*
G02X403586Y1086628I1297J2D01*
G01X403616Y1086714D01*
X402809Y1088112D01*
X402719Y1088129D01*
G02X401664Y1089404I243J1275D01*
G37*
G36*
G01X410362Y1090702D02*
G02X411401Y1090182I0J-1298D01*
G01X413023D01*
G02X414062Y1090702I1039J-778D01*
G02Y1088106I0J-1298D01*
G02X413023Y1088626I0J1298D01*
G01X411401D01*
G02X410362Y1088106I-1039J778D01*
G02Y1090702I0J1298D01*
G37*
G36*
G01X427564Y1089404D02*
G02X430158I1297J0D01*
G02X430086Y1088976I-1297J-2D01*
G01X430055Y1088889D01*
X430862Y1087492D01*
X430952Y1087475D01*
G02X432008Y1086200I-242J-1275D01*
G02X429412I-1298J0D01*
G02X429485Y1086629I1297J0D01*
G01X429516Y1086715D01*
X428709Y1088112D01*
X428619Y1088129D01*
G02X427564Y1089404I243J1275D01*
G37*
G36*
G01X1377806D02*
G02X1380400I1297J0D01*
G02X1380328Y1088976I-1297J-2D01*
G01X1380297Y1088889D01*
X1381104Y1087492D01*
X1381194Y1087475D01*
G02X1382250Y1086200I-242J-1275D01*
G02X1379656I-1297J0D01*
G02X1379728Y1086628I1297J2D01*
G01X1379758Y1086714D01*
X1378951Y1088112D01*
X1378861Y1088129D01*
G02X1377806Y1089404I243J1275D01*
G37*
G36*
G01X1386504Y1090702D02*
G02X1387543Y1090182I0J-1298D01*
G01X1389165D01*
G02X1390204Y1090702I1039J-778D01*
G02Y1088106I0J-1298D01*
G02X1389165Y1088626I0J1298D01*
G01X1387543D01*
G02X1386504Y1088106I-1039J778D01*
G02Y1090702I0J1298D01*
G37*
G36*
G01X1403706Y1089404D02*
G02X1406300I1297J0D01*
G02X1406228Y1088976I-1297J-2D01*
G01X1406197Y1088889D01*
X1407004Y1087492D01*
X1407094Y1087475D01*
G02X1408150Y1086200I-242J-1275D01*
G02X1405554I-1298J0D01*
G02X1405627Y1086629I1297J0D01*
G01X1405658Y1086715D01*
X1404851Y1088112D01*
X1404761Y1088129D01*
G02X1403706Y1089404I243J1275D01*
G37*
G36*
G01X407214Y1092608D02*
G02X409808I1297J0D01*
G02X408753Y1091333I-1298J0D01*
G01X408663Y1091316D01*
X407856Y1089919D01*
X407887Y1089833D01*
G02X407960Y1089404I-1224J-429D01*
G02X405364I-1298J0D01*
G02X406420Y1090679I1298J0D01*
G01X406510Y1090696D01*
X407317Y1092093D01*
X407286Y1092180D01*
G02X407214Y1092608I1225J426D01*
G37*
G36*
G01X418314D02*
G02X420908I1297J0D01*
G02X420836Y1092180I-1297J-2D01*
G01X420805Y1092093D01*
X421612Y1090696D01*
X421702Y1090679D01*
G02X422760Y1089404I-239J-1275D01*
G02X420164I-1298J0D01*
G02X420237Y1089831I1298J-2D01*
G01X420267Y1089917D01*
X419459Y1091316D01*
X419369Y1091333D01*
G02X418314Y1092608I243J1275D01*
G37*
G36*
G01X427011Y1093906D02*
G02X428050Y1093386I0J-1298D01*
G01X429672D01*
G02X430711Y1093906I1039J-778D01*
G02Y1091310I0J-1298D01*
G02X429672Y1091830I0J1298D01*
G01X428050D01*
G02X427011Y1091310I-1039J778D01*
G02Y1093906I0J1298D01*
G37*
G36*
G01X1383356Y1092608D02*
G02X1385950I1297J0D01*
G02X1384895Y1091333I-1298J0D01*
G01X1384805Y1091316D01*
X1383998Y1089919D01*
X1384029Y1089833D01*
G02X1384102Y1089404I-1224J-429D01*
G02X1381506I-1298J0D01*
G02X1382562Y1090679I1298J0D01*
G01X1382652Y1090696D01*
X1383459Y1092093D01*
X1383428Y1092180D01*
G02X1383356Y1092608I1225J426D01*
G37*
G36*
G01X1394456D02*
G02X1397050I1297J0D01*
G02X1396978Y1092180I-1297J-2D01*
G01X1396947Y1092093D01*
X1397754Y1090696D01*
X1397844Y1090679D01*
G02X1398902Y1089404I-239J-1275D01*
G02X1396306I-1298J0D01*
G02X1396379Y1089831I1298J-2D01*
G01X1396409Y1089917D01*
X1395601Y1091316D01*
X1395511Y1091333D01*
G02X1394456Y1092608I243J1275D01*
G37*
G36*
G01X1403153Y1093906D02*
G02X1404192Y1093386I0J-1298D01*
G01X1405814D01*
G02X1406853Y1093906I1039J-778D01*
G02Y1091310I0J-1298D01*
G02X1405814Y1091830I0J1298D01*
G01X1404192D01*
G02X1403153Y1091310I-1039J778D01*
G02Y1093906I0J1298D01*
G37*
G36*
G01X423864Y1095813D02*
G02X426460I1298J0D01*
G02X425404Y1094538I-1298J0D01*
G01X425314Y1094521D01*
X424506Y1093122D01*
X424536Y1093035D01*
G02X424608Y1092610I-1225J-426D01*
G01Y1092608D01*
G02X422014I-1297J0D01*
G02X423070Y1093883I1298J0D01*
G01X423161Y1093900D01*
X423968Y1095298D01*
X423937Y1095385D01*
G02X423864Y1095813I1225J429D01*
G37*
G36*
G01X1400006D02*
G02X1402602I1298J0D01*
G02X1401546Y1094538I-1298J0D01*
G01X1401456Y1094521D01*
X1400648Y1093122D01*
X1400678Y1093035D01*
G02X1400750Y1092610I-1225J-426D01*
G01Y1092608D01*
G02X1398156I-1297J0D01*
G02X1399212Y1093883I1298J0D01*
G01X1399303Y1093900D01*
X1400110Y1095298D01*
X1400079Y1095385D01*
G02X1400006Y1095813I1225J429D01*
G37*
G36*
G01X404811Y1100314D02*
G02X405850Y1099794I0J-1298D01*
G01X407472D01*
G02X408511Y1100314I1039J-778D01*
G02Y1097720I0J-1297D01*
G02X407472Y1098240I0J1298D01*
G01X405850D01*
G02X404811Y1097720I-1039J778D01*
G02Y1100314I0J1297D01*
G37*
G36*
G01X1380953D02*
G02X1381992Y1099794I0J-1298D01*
G01X1383614D01*
G02X1384653Y1100314I1039J-778D01*
G02Y1097720I0J-1297D01*
G02X1383614Y1098240I0J1298D01*
G01X1381992D01*
G02X1380953Y1097720I-1039J778D01*
G02Y1100314I0J1297D01*
G37*
G36*
G01X351161Y1103518D02*
G02X352200Y1102998I0J-1298D01*
G01X353822D01*
G02X354861Y1103518I1039J-778D01*
G02Y1100924I0J-1297D01*
G02X353822Y1101444I0J1298D01*
G01X352200D01*
G02X351161Y1100924I-1039J778D01*
G02Y1103518I0J1297D01*
G37*
G36*
G01X401664Y1102221D02*
G02X404260I1298J0D01*
G02X403204Y1100946I-1298J0D01*
G01X403114Y1100929D01*
X402306Y1099530D01*
X402336Y1099444D01*
G02X402408Y1099019I-1225J-426D01*
G01Y1099017D01*
G02X399814I-1297J0D01*
G02X400871Y1100292I1297J0D01*
G01X400961Y1100309D01*
X401768Y1101706D01*
X401737Y1101793D01*
G02X401664Y1102221I1225J429D01*
G37*
G36*
G01X1327303Y1103518D02*
G02X1328342Y1102998I0J-1298D01*
G01X1329964D01*
G02X1331003Y1103518I1039J-778D01*
G02Y1100924I0J-1297D01*
G02X1329964Y1101444I0J1298D01*
G01X1328342D01*
G02X1327303Y1100924I-1039J778D01*
G02Y1103518I0J1297D01*
G37*
G36*
G01X1377806Y1102221D02*
G02X1380402I1298J0D01*
G02X1379346Y1100946I-1298J0D01*
G01X1379256Y1100929D01*
X1378448Y1099530D01*
X1378478Y1099444D01*
G02X1378550Y1099019I-1225J-426D01*
G01Y1099017D01*
G02X1375956I-1297J0D01*
G02X1377013Y1100292I1297J0D01*
G01X1377103Y1100309D01*
X1377910Y1101706D01*
X1377879Y1101793D01*
G02X1377806Y1102221I1225J429D01*
G37*
G36*
G01X375211Y1106724D02*
G02X376250Y1106204I0J-1298D01*
G01X377873D01*
G02X378912Y1106724I1039J-778D01*
G02Y1104128I0J-1298D01*
G02X377873Y1104648I0J1298D01*
G01X376250D01*
G02X375211Y1104128I-1039J778D01*
G02Y1106724I0J1298D01*
G37*
G36*
G01X381314Y1105426D02*
G02X383908I1297J0D01*
G02X382853Y1104151I-1298J0D01*
G01X382763Y1104134D01*
X381956Y1102737D01*
X381986Y1102650D01*
G02X382060Y1102221I-1223J-432D01*
G02X379464I-1298J0D01*
G02X380519Y1103496I1298J0D01*
G01X380609Y1103513D01*
X381417Y1104911D01*
X381386Y1104998D01*
G02X381314Y1105426I1225J426D01*
G37*
G36*
G01X410914D02*
G02X413508I1297J0D01*
G02X413436Y1104998I-1297J-2D01*
G01X413405Y1104911D01*
X414212Y1103513D01*
X414303Y1103496D01*
G02X415360Y1102221I-240J-1275D01*
G02X412764I-1298J0D01*
G02X412837Y1102648I1298J-2D01*
G01X412867Y1102735D01*
X412059Y1104134D01*
X411969Y1104151D01*
G02X410914Y1105426I243J1275D01*
G37*
G36*
G01X415911Y1106724D02*
G02X416950Y1106204I0J-1298D01*
G01X418572D01*
G02X419611Y1106724I1039J-778D01*
G02Y1104128I0J-1298D01*
G02X418572Y1104648I0J1298D01*
G01X416950D01*
G02X415911Y1104128I-1039J778D01*
G02Y1106724I0J1298D01*
G37*
G36*
G01X1351353D02*
G02X1352392Y1106204I0J-1298D01*
G01X1354015D01*
G02X1355054Y1106724I1039J-778D01*
G02Y1104128I0J-1298D01*
G02X1354015Y1104648I0J1298D01*
G01X1352392D01*
G02X1351353Y1104128I-1039J778D01*
G02Y1106724I0J1298D01*
G37*
G36*
G01X1357456Y1105426D02*
G02X1360050I1297J0D01*
G02X1358995Y1104151I-1298J0D01*
G01X1358905Y1104134D01*
X1358098Y1102737D01*
X1358128Y1102650D01*
G02X1358202Y1102221I-1223J-432D01*
G02X1355606I-1298J0D01*
G02X1356661Y1103496I1298J0D01*
G01X1356751Y1103513D01*
X1357559Y1104911D01*
X1357528Y1104998D01*
G02X1357456Y1105426I1225J426D01*
G37*
G36*
G01X1387056D02*
G02X1389650I1297J0D01*
G02X1389578Y1104998I-1297J-2D01*
G01X1389547Y1104911D01*
X1390354Y1103513D01*
X1390445Y1103496D01*
G02X1391502Y1102221I-240J-1275D01*
G02X1388906I-1298J0D01*
G02X1388979Y1102648I1298J-2D01*
G01X1389009Y1102735D01*
X1388201Y1104134D01*
X1388111Y1104151D01*
G02X1387056Y1105426I243J1275D01*
G37*
G36*
G01X1392053Y1106724D02*
G02X1393092Y1106204I0J-1298D01*
G01X1394714D01*
G02X1395753Y1106724I1039J-778D01*
G02Y1104128I0J-1298D01*
G02X1394714Y1104648I0J1298D01*
G01X1393092D01*
G02X1392053Y1104128I-1039J778D01*
G02Y1106724I0J1298D01*
G37*
G36*
G01X358561Y1109928D02*
G02X359600Y1109408I0J-1298D01*
G01X361222D01*
G02X362261Y1109928I1039J-778D01*
G02Y1107332I0J-1298D01*
G02X361222Y1107852I0J1298D01*
G01X359600D01*
G02X358561Y1107332I-1039J778D01*
G02Y1109928I0J1298D01*
G37*
G36*
G01X383164Y1108630D02*
G02X385760I1298J0D01*
G02X385687Y1108202I-1298J1D01*
G01X385656Y1108115D01*
X386463Y1106718D01*
X386553Y1106701D01*
G02X387608Y1105426I-243J-1275D01*
G02X385014I-1297J0D01*
G02X385086Y1105855I1297J3D01*
G01X385117Y1105941D01*
X384310Y1107338D01*
X384220Y1107355D01*
G02X383164Y1108630I242J1275D01*
G37*
G36*
G01X391862Y1109928D02*
G02X392901Y1109408I0J-1298D01*
G01X394523D01*
G02X395562Y1109928I1039J-778D01*
G02Y1107332I0J-1298D01*
G02X394523Y1107852I0J1298D01*
G01X392901D01*
G02X391862Y1107332I-1039J778D01*
G02Y1109928I0J1298D01*
G37*
G36*
G01X397964Y1108630D02*
G02X400560I1298J0D01*
G02X399504Y1107355I-1298J0D01*
G01X399414Y1107338D01*
X398606Y1105939D01*
X398636Y1105853D01*
G02X398708Y1105428I-1225J-426D01*
G01Y1105426D01*
G02X396114I-1297J0D01*
G02X397171Y1106701I1297J0D01*
G01X397261Y1106718D01*
X398068Y1108115D01*
X398037Y1108202D01*
G02X397964Y1108630I1225J429D01*
G37*
G36*
G01X409064D02*
G02X411660I1298J0D01*
G02X410604Y1107355I-1298J0D01*
G01X410514Y1107338D01*
X409706Y1105939D01*
X409736Y1105853D01*
G02X409808Y1105428I-1225J-426D01*
G01Y1105426D01*
G02X407214I-1297J0D01*
G02X408271Y1106701I1297J0D01*
G01X408361Y1106718D01*
X409168Y1108115D01*
X409137Y1108202D01*
G02X409064Y1108630I1225J429D01*
G37*
G36*
G01X1334703Y1109928D02*
G02X1335742Y1109408I0J-1298D01*
G01X1337364D01*
G02X1338403Y1109928I1039J-778D01*
G02Y1107332I0J-1298D01*
G02X1337364Y1107852I0J1298D01*
G01X1335742D01*
G02X1334703Y1107332I-1039J778D01*
G02Y1109928I0J1298D01*
G37*
G36*
G01X1359306Y1108630D02*
G02X1361902I1298J0D01*
G02X1361829Y1108202I-1298J1D01*
G01X1361798Y1108115D01*
X1362605Y1106718D01*
X1362695Y1106701D01*
G02X1363750Y1105426I-243J-1275D01*
G02X1361156I-1297J0D01*
G02X1361228Y1105855I1297J3D01*
G01X1361259Y1105941D01*
X1360452Y1107338D01*
X1360362Y1107355D01*
G02X1359306Y1108630I242J1275D01*
G37*
G36*
G01X1368004Y1109928D02*
G02X1369043Y1109408I0J-1298D01*
G01X1370665D01*
G02X1371704Y1109928I1039J-778D01*
G02Y1107332I0J-1298D01*
G02X1370665Y1107852I0J1298D01*
G01X1369043D01*
G02X1368004Y1107332I-1039J778D01*
G02Y1109928I0J1298D01*
G37*
G36*
G01X1374106Y1108630D02*
G02X1376702I1298J0D01*
G02X1375646Y1107355I-1298J0D01*
G01X1375556Y1107338D01*
X1374748Y1105939D01*
X1374778Y1105853D01*
G02X1374850Y1105428I-1225J-426D01*
G01Y1105426D01*
G02X1372256I-1297J0D01*
G02X1373313Y1106701I1297J0D01*
G01X1373403Y1106718D01*
X1374210Y1108115D01*
X1374179Y1108202D01*
G02X1374106Y1108630I1225J429D01*
G37*
G36*
G01X1385206D02*
G02X1387802I1298J0D01*
G02X1386746Y1107355I-1298J0D01*
G01X1386656Y1107338D01*
X1385848Y1105939D01*
X1385878Y1105853D01*
G02X1385950Y1105428I-1225J-426D01*
G01Y1105426D01*
G02X1383356I-1297J0D01*
G02X1384413Y1106701I1297J0D01*
G01X1384503Y1106718D01*
X1385310Y1108115D01*
X1385279Y1108202D01*
G02X1385206Y1108630I1225J429D01*
G37*
G36*
G01X366514Y1111834D02*
G02X369110I1298J0D01*
G02X369037Y1111406I-1298J1D01*
G01X369006Y1111319D01*
X369813Y1109922D01*
X369903Y1109905D01*
G02X370958Y1108630I-243J-1275D01*
G02X368364I-1297J0D01*
G02X368436Y1109059I1297J3D01*
G01X368467Y1109145D01*
X367660Y1110542D01*
X367570Y1110559D01*
G02X366514Y1111834I242J1275D01*
G37*
G36*
G01X373914D02*
G02X376508I1297J0D01*
G02X376436Y1111406I-1297J-2D01*
G01X376405Y1111319D01*
X377212Y1109922D01*
X377302Y1109905D01*
G02X378360Y1108630I-239J-1275D01*
G02X375764I-1298J0D01*
G02X375837Y1109057I1298J-2D01*
G01X375867Y1109143D01*
X375059Y1110542D01*
X374969Y1110559D01*
G02X373914Y1111834I243J1275D01*
G37*
G36*
G01X382611Y1113132D02*
G02X383650Y1112612I0J-1298D01*
G01X385272D01*
G02X386311Y1113132I1039J-778D01*
G02Y1110536I0J-1298D01*
G02X385272Y1111056I0J1298D01*
G01X383650D01*
G02X382611Y1110536I-1039J778D01*
G02Y1113132I0J1298D01*
G37*
G36*
G01X399814Y1111834D02*
G02X402408I1297J0D01*
G02X402336Y1111406I-1297J-2D01*
G01X402305Y1111319D01*
X403112Y1109922D01*
X403202Y1109905D01*
G02X404260Y1108630I-239J-1275D01*
G02X401664I-1298J0D01*
G02X401737Y1109057I1298J-2D01*
G01X401767Y1109143D01*
X400959Y1110542D01*
X400869Y1110559D01*
G02X399814Y1111834I243J1275D01*
G37*
G36*
G01X408511Y1113132D02*
G02X409550Y1112612I0J-1298D01*
G01X411172D01*
G02X412211Y1113132I1039J-778D01*
G02Y1110536I0J-1298D01*
G02X411172Y1111056I0J1298D01*
G01X409550D01*
G02X408511Y1110536I-1039J778D01*
G02Y1113132I0J1298D01*
G37*
G36*
G01X418314Y1111834D02*
G02X420908I1297J0D01*
G02X419853Y1110559I-1298J0D01*
G01X419763Y1110542D01*
X418956Y1109145D01*
X418987Y1109059D01*
G02X419060Y1108630I-1224J-429D01*
G02X416464I-1298J0D01*
G02X417520Y1109905I1298J0D01*
G01X417610Y1109922D01*
X418417Y1111319D01*
X418386Y1111406D01*
G02X418314Y1111834I1225J426D01*
G37*
G36*
G01X1342656D02*
G02X1345252I1298J0D01*
G02X1345179Y1111406I-1298J1D01*
G01X1345148Y1111319D01*
X1345955Y1109922D01*
X1346045Y1109905D01*
G02X1347100Y1108630I-243J-1275D01*
G02X1344506I-1297J0D01*
G02X1344578Y1109059I1297J3D01*
G01X1344609Y1109145D01*
X1343802Y1110542D01*
X1343712Y1110559D01*
G02X1342656Y1111834I242J1275D01*
G37*
G36*
G01X1350056D02*
G02X1352650I1297J0D01*
G02X1352578Y1111406I-1297J-2D01*
G01X1352547Y1111319D01*
X1353354Y1109922D01*
X1353444Y1109905D01*
G02X1354502Y1108630I-239J-1275D01*
G02X1351906I-1298J0D01*
G02X1351979Y1109057I1298J-2D01*
G01X1352009Y1109143D01*
X1351201Y1110542D01*
X1351111Y1110559D01*
G02X1350056Y1111834I243J1275D01*
G37*
G36*
G01X1358753Y1113132D02*
G02X1359792Y1112612I0J-1298D01*
G01X1361414D01*
G02X1362453Y1113132I1039J-778D01*
G02Y1110536I0J-1298D01*
G02X1361414Y1111056I0J1298D01*
G01X1359792D01*
G02X1358753Y1110536I-1039J778D01*
G02Y1113132I0J1298D01*
G37*
G36*
G01X1375956Y1111834D02*
G02X1378550I1297J0D01*
G02X1378478Y1111406I-1297J-2D01*
G01X1378447Y1111319D01*
X1379254Y1109922D01*
X1379344Y1109905D01*
G02X1380402Y1108630I-239J-1275D01*
G02X1377806I-1298J0D01*
G02X1377879Y1109057I1298J-2D01*
G01X1377909Y1109143D01*
X1377101Y1110542D01*
X1377011Y1110559D01*
G02X1375956Y1111834I243J1275D01*
G37*
G36*
G01X1384653Y1113132D02*
G02X1385692Y1112612I0J-1298D01*
G01X1387314D01*
G02X1388353Y1113132I1039J-778D01*
G02Y1110536I0J-1298D01*
G02X1387314Y1111056I0J1298D01*
G01X1385692D01*
G02X1384653Y1110536I-1039J778D01*
G02Y1113132I0J1298D01*
G37*
G36*
G01X1394456Y1111834D02*
G02X1397050I1297J0D01*
G02X1395995Y1110559I-1298J0D01*
G01X1395905Y1110542D01*
X1395098Y1109145D01*
X1395129Y1109059D01*
G02X1395202Y1108630I-1224J-429D01*
G02X1392606I-1298J0D01*
G02X1393662Y1109905I1298J0D01*
G01X1393752Y1109922D01*
X1394559Y1111319D01*
X1394528Y1111406D01*
G02X1394456Y1111834I1225J426D01*
G37*
G36*
G01X346164Y1115039D02*
G02X348758I1297J0D01*
G02X347703Y1113764I-1298J0D01*
G01X347613Y1113747D01*
X346805Y1112349D01*
X346836Y1112262D01*
G02X346908Y1111834I-1225J-426D01*
G02X344314I-1297J0D01*
G02X345369Y1113109I1298J0D01*
G01X345459Y1113126D01*
X346267Y1114524D01*
X346236Y1114611D01*
G02X346164Y1115039I1225J426D01*
G37*
G36*
G01X365961Y1116336D02*
G02X367000Y1115816I0J-1298D01*
G01X368622D01*
G02X369661Y1116336I1039J-778D01*
G02Y1113742I0J-1297D01*
G02X368622Y1114262I0J1298D01*
G01X367000D01*
G02X365961Y1113742I-1039J778D01*
G02Y1116336I0J1297D01*
G37*
G36*
G01X379464Y1115039D02*
G02X382060I1298J0D01*
G02X381004Y1113764I-1298J0D01*
G01X380914Y1113747D01*
X380106Y1112348D01*
X380136Y1112261D01*
G02X380208Y1111836I-1225J-426D01*
G01Y1111834D01*
G02X377614I-1297J0D01*
G02X378670Y1113109I1298J0D01*
G01X378761Y1113126D01*
X379568Y1114524D01*
X379537Y1114611D01*
G02X379464Y1115039I1225J429D01*
G37*
G36*
G01X390564D02*
G02X393160I1298J0D01*
G02X393087Y1114611I-1298J1D01*
G01X393056Y1114524D01*
X393864Y1113126D01*
X393954Y1113109D01*
G02X395008Y1111834I-244J-1275D01*
G02X392414I-1297J0D01*
G02X392487Y1112263I1297J0D01*
G01X392517Y1112350D01*
X391710Y1113747D01*
X391620Y1113764D01*
G02X390564Y1115039I242J1275D01*
G37*
G36*
G01X399262Y1116336D02*
G02X400301Y1115816I0J-1298D01*
G01X401923D01*
G02X402962Y1116336I1039J-778D01*
G02Y1113742I0J-1297D01*
G02X401923Y1114262I0J1298D01*
G01X400301D01*
G02X399262Y1113742I-1039J778D01*
G02Y1116336I0J1297D01*
G37*
G36*
G01X412764Y1115039D02*
G02X415360I1298J0D01*
G02X415287Y1114611I-1298J1D01*
G01X415256Y1114524D01*
X416064Y1113126D01*
X416154Y1113109D01*
G02X417208Y1111834I-244J-1275D01*
G02X414614I-1297J0D01*
G02X414687Y1112263I1297J0D01*
G01X414717Y1112350D01*
X413910Y1113747D01*
X413820Y1113764D01*
G02X412764Y1115039I242J1275D01*
G37*
G36*
G01X1322306D02*
G02X1324900I1297J0D01*
G02X1323845Y1113764I-1298J0D01*
G01X1323755Y1113747D01*
X1322947Y1112349D01*
X1322978Y1112262D01*
G02X1323050Y1111834I-1225J-426D01*
G02X1320456I-1297J0D01*
G02X1321511Y1113109I1298J0D01*
G01X1321601Y1113126D01*
X1322409Y1114524D01*
X1322378Y1114611D01*
G02X1322306Y1115039I1225J426D01*
G37*
G36*
G01X1342103Y1116336D02*
G02X1343142Y1115816I0J-1298D01*
G01X1344764D01*
G02X1345803Y1116336I1039J-778D01*
G02Y1113742I0J-1297D01*
G02X1344764Y1114262I0J1298D01*
G01X1343142D01*
G02X1342103Y1113742I-1039J778D01*
G02Y1116336I0J1297D01*
G37*
G36*
G01X1355606Y1115039D02*
G02X1358202I1298J0D01*
G02X1357146Y1113764I-1298J0D01*
G01X1357056Y1113747D01*
X1356248Y1112348D01*
X1356278Y1112261D01*
G02X1356350Y1111836I-1225J-426D01*
G01Y1111834D01*
G02X1353756I-1297J0D01*
G02X1354812Y1113109I1298J0D01*
G01X1354903Y1113126D01*
X1355710Y1114524D01*
X1355679Y1114611D01*
G02X1355606Y1115039I1225J429D01*
G37*
G36*
G01X1366706D02*
G02X1369302I1298J0D01*
G02X1369229Y1114611I-1298J1D01*
G01X1369198Y1114524D01*
X1370006Y1113126D01*
X1370096Y1113109D01*
G02X1371150Y1111834I-244J-1275D01*
G02X1368556I-1297J0D01*
G02X1368629Y1112263I1297J0D01*
G01X1368659Y1112350D01*
X1367852Y1113747D01*
X1367762Y1113764D01*
G02X1366706Y1115039I242J1275D01*
G37*
G36*
G01X1375404Y1116336D02*
G02X1376443Y1115816I0J-1298D01*
G01X1378065D01*
G02X1379104Y1116336I1039J-778D01*
G02Y1113742I0J-1297D01*
G02X1378065Y1114262I0J1298D01*
G01X1376443D01*
G02X1375404Y1113742I-1039J778D01*
G02Y1116336I0J1297D01*
G37*
G36*
G01X1388906Y1115039D02*
G02X1391502I1298J0D01*
G02X1391429Y1114611I-1298J1D01*
G01X1391398Y1114524D01*
X1392206Y1113126D01*
X1392296Y1113109D01*
G02X1393350Y1111834I-244J-1275D01*
G02X1390756I-1297J0D01*
G02X1390829Y1112263I1297J0D01*
G01X1390859Y1112350D01*
X1390052Y1113747D01*
X1389962Y1113764D01*
G02X1388906Y1115039I242J1275D01*
G37*
G36*
G01X342464Y1121447D02*
G02X345058I1297J0D01*
G02X344003Y1120172I-1298J0D01*
G01X343913Y1120155D01*
X343106Y1118758D01*
X343137Y1118671D01*
G02X343210Y1118243I-1225J-429D01*
G02X340614I-1298J0D01*
G02X341670Y1119518I1298J0D01*
G01X341760Y1119535D01*
X342567Y1120932D01*
X342536Y1121019D01*
G02X342464Y1121447I1225J426D01*
G37*
G36*
G01X1318606D02*
G02X1321200I1297J0D01*
G02X1320145Y1120172I-1298J0D01*
G01X1320055Y1120155D01*
X1319248Y1118758D01*
X1319279Y1118671D01*
G02X1319352Y1118243I-1225J-429D01*
G02X1316756I-1298J0D01*
G02X1317812Y1119518I1298J0D01*
G01X1317902Y1119535D01*
X1318709Y1120932D01*
X1318678Y1121019D01*
G02X1318606Y1121447I1225J426D01*
G37*
G36*
G01X355414Y1124651D02*
G02X358010I1298J0D01*
G02X357937Y1124223I-1298J1D01*
G01X357906Y1124136D01*
X358713Y1122739D01*
X358803Y1122722D01*
G02X359858Y1121447I-243J-1275D01*
G02X357264I-1297J0D01*
G02X357336Y1121876I1297J3D01*
G01X357367Y1121962D01*
X356560Y1123359D01*
X356470Y1123376D01*
G02X355414Y1124651I242J1275D01*
G37*
G36*
G01X362814D02*
G02X365408I1297J0D01*
G02X365336Y1124223I-1297J-2D01*
G01X365305Y1124136D01*
X366112Y1122739D01*
X366202Y1122722D01*
G02X367260Y1121447I-239J-1275D01*
G02X364664I-1298J0D01*
G02X364737Y1121874I1298J-2D01*
G01X364767Y1121960D01*
X363959Y1123359D01*
X363869Y1123376D01*
G02X362814Y1124651I243J1275D01*
G37*
G36*
G01X370214D02*
G02X372808I1297J0D01*
G02X372736Y1124223I-1297J-2D01*
G01X372705Y1124136D01*
X373512Y1122739D01*
X373602Y1122722D01*
G02X374660Y1121447I-239J-1275D01*
G02X372064I-1298J0D01*
G02X372137Y1121874I1298J-2D01*
G01X372167Y1121960D01*
X371359Y1123359D01*
X371269Y1123376D01*
G02X370214Y1124651I243J1275D01*
G37*
G36*
G01X377614D02*
G02X380208I1297J0D01*
G02X380136Y1124223I-1297J-2D01*
G01X380105Y1124136D01*
X380912Y1122739D01*
X381002Y1122722D01*
G02X382060Y1121447I-239J-1275D01*
G02X379464I-1298J0D01*
G02X379537Y1121874I1298J-2D01*
G01X379567Y1121960D01*
X378759Y1123359D01*
X378669Y1123376D01*
G02X377614Y1124651I243J1275D01*
G37*
G36*
G01X385014D02*
G02X387608I1297J0D01*
G02X387536Y1124223I-1297J-2D01*
G01X387505Y1124136D01*
X388312Y1122739D01*
X388402Y1122722D01*
G02X389460Y1121447I-239J-1275D01*
G02X386864I-1298J0D01*
G02X386937Y1121874I1298J-2D01*
G01X386967Y1121960D01*
X386159Y1123359D01*
X386069Y1123376D01*
G02X385014Y1124651I243J1275D01*
G37*
G36*
G01X392414D02*
G02X395008I1297J0D01*
G02X394936Y1124223I-1297J-2D01*
G01X394905Y1124136D01*
X395712Y1122739D01*
X395802Y1122722D01*
G02X396860Y1121447I-239J-1275D01*
G02X394264I-1298J0D01*
G02X394337Y1121874I1298J-2D01*
G01X394367Y1121960D01*
X393559Y1123359D01*
X393469Y1123376D01*
G02X392414Y1124651I243J1275D01*
G37*
G36*
G01X399814D02*
G02X402408I1297J0D01*
G02X402336Y1124223I-1297J-2D01*
G01X402305Y1124136D01*
X403112Y1122739D01*
X403202Y1122722D01*
G02X404260Y1121447I-239J-1275D01*
G02X401664I-1298J0D01*
G02X401737Y1121874I1298J-2D01*
G01X401767Y1121960D01*
X400959Y1123359D01*
X400869Y1123376D01*
G02X399814Y1124651I243J1275D01*
G37*
G36*
G01X407214D02*
G02X409808I1297J0D01*
G02X409736Y1124223I-1297J-2D01*
G01X409705Y1124136D01*
X410512Y1122739D01*
X410602Y1122722D01*
G02X411660Y1121447I-239J-1275D01*
G02X409064I-1298J0D01*
G02X409137Y1121874I1298J-2D01*
G01X409167Y1121960D01*
X408359Y1123359D01*
X408269Y1123376D01*
G02X407214Y1124651I243J1275D01*
G37*
G36*
G01X470114D02*
G02X472708I1297J0D01*
G02X471653Y1123376I-1298J0D01*
G01X471563Y1123359D01*
X470756Y1121962D01*
X470787Y1121875D01*
G02X470860Y1121447I-1225J-429D01*
G02X468264I-1298J0D01*
G02X469320Y1122722I1298J0D01*
G01X469410Y1122739D01*
X470217Y1124136D01*
X470186Y1124223D01*
G02X470114Y1124651I1225J426D01*
G37*
G36*
G01X477514D02*
G02X480108I1297J0D01*
G02X479053Y1123376I-1298J0D01*
G01X478963Y1123359D01*
X478156Y1121962D01*
X478187Y1121875D01*
G02X478260Y1121447I-1225J-429D01*
G02X475664I-1298J0D01*
G02X476720Y1122722I1298J0D01*
G01X476810Y1122739D01*
X477617Y1124136D01*
X477586Y1124223D01*
G02X477514Y1124651I1225J426D01*
G37*
G36*
G01X484914D02*
G02X487508I1297J0D01*
G02X486453Y1123376I-1298J0D01*
G01X486363Y1123359D01*
X485556Y1121962D01*
X485587Y1121875D01*
G02X485660Y1121447I-1225J-429D01*
G02X483064I-1298J0D01*
G02X484120Y1122722I1298J0D01*
G01X484210Y1122739D01*
X485017Y1124136D01*
X484986Y1124223D01*
G02X484914Y1124651I1225J426D01*
G37*
G36*
G01X492314D02*
G02X494908I1297J0D01*
G02X493853Y1123376I-1298J0D01*
G01X493763Y1123359D01*
X492956Y1121962D01*
X492987Y1121875D01*
G02X493060Y1121447I-1225J-429D01*
G02X490464I-1298J0D01*
G02X491520Y1122722I1298J0D01*
G01X491610Y1122739D01*
X492417Y1124136D01*
X492386Y1124223D01*
G02X492314Y1124651I1225J426D01*
G37*
G36*
G01X499714D02*
G02X502308I1297J0D01*
G02X501253Y1123376I-1298J0D01*
G01X501163Y1123359D01*
X500356Y1121962D01*
X500387Y1121875D01*
G02X500460Y1121447I-1225J-429D01*
G02X497864I-1298J0D01*
G02X498920Y1122722I1298J0D01*
G01X499010Y1122739D01*
X499817Y1124136D01*
X499786Y1124223D01*
G02X499714Y1124651I1225J426D01*
G37*
G36*
G01X507114D02*
G02X509708I1297J0D01*
G02X508653Y1123376I-1298J0D01*
G01X508563Y1123359D01*
X507756Y1121962D01*
X507787Y1121875D01*
G02X507860Y1121447I-1225J-429D01*
G02X505264I-1298J0D01*
G02X506320Y1122722I1298J0D01*
G01X506410Y1122739D01*
X507217Y1124136D01*
X507186Y1124223D01*
G02X507114Y1124651I1225J426D01*
G37*
G36*
G01X514514D02*
G02X517108I1297J0D01*
G02X516053Y1123376I-1298J0D01*
G01X515963Y1123359D01*
X515156Y1121962D01*
X515187Y1121875D01*
G02X515260Y1121447I-1225J-429D01*
G02X512664I-1298J0D01*
G02X513720Y1122722I1298J0D01*
G01X513810Y1122739D01*
X514617Y1124136D01*
X514586Y1124223D01*
G02X514514Y1124651I1225J426D01*
G37*
G36*
G01X521914D02*
G02X524508I1297J0D01*
G02X523453Y1123376I-1298J0D01*
G01X523363Y1123359D01*
X522556Y1121962D01*
X522587Y1121875D01*
G02X522660Y1121447I-1225J-429D01*
G02X520064I-1298J0D01*
G02X521120Y1122722I1298J0D01*
G01X521210Y1122739D01*
X522017Y1124136D01*
X521986Y1124223D01*
G02X521914Y1124651I1225J426D01*
G37*
G36*
G01X1331556D02*
G02X1334152I1298J0D01*
G02X1334079Y1124223I-1298J1D01*
G01X1334048Y1124136D01*
X1334855Y1122739D01*
X1334945Y1122722D01*
G02X1336000Y1121447I-243J-1275D01*
G02X1333406I-1297J0D01*
G02X1333478Y1121876I1297J3D01*
G01X1333509Y1121962D01*
X1332702Y1123359D01*
X1332612Y1123376D01*
G02X1331556Y1124651I242J1275D01*
G37*
G36*
G01X1338956D02*
G02X1341550I1297J0D01*
G02X1341478Y1124223I-1297J-2D01*
G01X1341447Y1124136D01*
X1342254Y1122739D01*
X1342344Y1122722D01*
G02X1343402Y1121447I-239J-1275D01*
G02X1340806I-1298J0D01*
G02X1340879Y1121874I1298J-2D01*
G01X1340909Y1121960D01*
X1340101Y1123359D01*
X1340011Y1123376D01*
G02X1338956Y1124651I243J1275D01*
G37*
G36*
G01X1346356D02*
G02X1348950I1297J0D01*
G02X1348878Y1124223I-1297J-2D01*
G01X1348847Y1124136D01*
X1349654Y1122739D01*
X1349744Y1122722D01*
G02X1350802Y1121447I-239J-1275D01*
G02X1348206I-1298J0D01*
G02X1348279Y1121874I1298J-2D01*
G01X1348309Y1121960D01*
X1347501Y1123359D01*
X1347411Y1123376D01*
G02X1346356Y1124651I243J1275D01*
G37*
G36*
G01X1353756D02*
G02X1356350I1297J0D01*
G02X1356278Y1124223I-1297J-2D01*
G01X1356247Y1124136D01*
X1357054Y1122739D01*
X1357144Y1122722D01*
G02X1358202Y1121447I-239J-1275D01*
G02X1355606I-1298J0D01*
G02X1355679Y1121874I1298J-2D01*
G01X1355709Y1121960D01*
X1354901Y1123359D01*
X1354811Y1123376D01*
G02X1353756Y1124651I243J1275D01*
G37*
G36*
G01X1361156D02*
G02X1363750I1297J0D01*
G02X1363678Y1124223I-1297J-2D01*
G01X1363647Y1124136D01*
X1364454Y1122739D01*
X1364544Y1122722D01*
G02X1365602Y1121447I-239J-1275D01*
G02X1363006I-1298J0D01*
G02X1363079Y1121874I1298J-2D01*
G01X1363109Y1121960D01*
X1362301Y1123359D01*
X1362211Y1123376D01*
G02X1361156Y1124651I243J1275D01*
G37*
G36*
G01X1368556D02*
G02X1371150I1297J0D01*
G02X1371078Y1124223I-1297J-2D01*
G01X1371047Y1124136D01*
X1371854Y1122739D01*
X1371944Y1122722D01*
G02X1373002Y1121447I-239J-1275D01*
G02X1370406I-1298J0D01*
G02X1370479Y1121874I1298J-2D01*
G01X1370509Y1121960D01*
X1369701Y1123359D01*
X1369611Y1123376D01*
G02X1368556Y1124651I243J1275D01*
G37*
G36*
G01X1375956D02*
G02X1378550I1297J0D01*
G02X1378478Y1124223I-1297J-2D01*
G01X1378447Y1124136D01*
X1379254Y1122739D01*
X1379344Y1122722D01*
G02X1380402Y1121447I-239J-1275D01*
G02X1377806I-1298J0D01*
G02X1377879Y1121874I1298J-2D01*
G01X1377909Y1121960D01*
X1377101Y1123359D01*
X1377011Y1123376D01*
G02X1375956Y1124651I243J1275D01*
G37*
G36*
G01X1383356D02*
G02X1385950I1297J0D01*
G02X1385878Y1124223I-1297J-2D01*
G01X1385847Y1124136D01*
X1386654Y1122739D01*
X1386744Y1122722D01*
G02X1387802Y1121447I-239J-1275D01*
G02X1385206I-1298J0D01*
G02X1385279Y1121874I1298J-2D01*
G01X1385309Y1121960D01*
X1384501Y1123359D01*
X1384411Y1123376D01*
G02X1383356Y1124651I243J1275D01*
G37*
G36*
G01X1446256D02*
G02X1448850I1297J0D01*
G02X1447795Y1123376I-1298J0D01*
G01X1447705Y1123359D01*
X1446898Y1121962D01*
X1446929Y1121875D01*
G02X1447002Y1121447I-1225J-429D01*
G02X1444406I-1298J0D01*
G02X1445462Y1122722I1298J0D01*
G01X1445552Y1122739D01*
X1446359Y1124136D01*
X1446328Y1124223D01*
G02X1446256Y1124651I1225J426D01*
G37*
G36*
G01X1453656D02*
G02X1456250I1297J0D01*
G02X1455195Y1123376I-1298J0D01*
G01X1455105Y1123359D01*
X1454298Y1121962D01*
X1454329Y1121875D01*
G02X1454402Y1121447I-1225J-429D01*
G02X1451806I-1298J0D01*
G02X1452862Y1122722I1298J0D01*
G01X1452952Y1122739D01*
X1453759Y1124136D01*
X1453728Y1124223D01*
G02X1453656Y1124651I1225J426D01*
G37*
G36*
G01X1461056D02*
G02X1463650I1297J0D01*
G02X1462595Y1123376I-1298J0D01*
G01X1462505Y1123359D01*
X1461698Y1121962D01*
X1461729Y1121875D01*
G02X1461802Y1121447I-1225J-429D01*
G02X1459206I-1298J0D01*
G02X1460262Y1122722I1298J0D01*
G01X1460352Y1122739D01*
X1461159Y1124136D01*
X1461128Y1124223D01*
G02X1461056Y1124651I1225J426D01*
G37*
G36*
G01X1468456D02*
G02X1471050I1297J0D01*
G02X1469995Y1123376I-1298J0D01*
G01X1469905Y1123359D01*
X1469098Y1121962D01*
X1469129Y1121875D01*
G02X1469202Y1121447I-1225J-429D01*
G02X1466606I-1298J0D01*
G02X1467662Y1122722I1298J0D01*
G01X1467752Y1122739D01*
X1468559Y1124136D01*
X1468528Y1124223D01*
G02X1468456Y1124651I1225J426D01*
G37*
G36*
G01X1475856D02*
G02X1478450I1297J0D01*
G02X1477395Y1123376I-1298J0D01*
G01X1477305Y1123359D01*
X1476498Y1121962D01*
X1476529Y1121875D01*
G02X1476602Y1121447I-1225J-429D01*
G02X1474006I-1298J0D01*
G02X1475062Y1122722I1298J0D01*
G01X1475152Y1122739D01*
X1475959Y1124136D01*
X1475928Y1124223D01*
G02X1475856Y1124651I1225J426D01*
G37*
G36*
G01X1483256D02*
G02X1485850I1297J0D01*
G02X1484795Y1123376I-1298J0D01*
G01X1484705Y1123359D01*
X1483898Y1121962D01*
X1483929Y1121875D01*
G02X1484002Y1121447I-1225J-429D01*
G02X1481406I-1298J0D01*
G02X1482462Y1122722I1298J0D01*
G01X1482552Y1122739D01*
X1483359Y1124136D01*
X1483328Y1124223D01*
G02X1483256Y1124651I1225J426D01*
G37*
G36*
G01X1490656D02*
G02X1493250I1297J0D01*
G02X1492195Y1123376I-1298J0D01*
G01X1492105Y1123359D01*
X1491298Y1121962D01*
X1491329Y1121875D01*
G02X1491402Y1121447I-1225J-429D01*
G02X1488806I-1298J0D01*
G02X1489862Y1122722I1298J0D01*
G01X1489952Y1122739D01*
X1490759Y1124136D01*
X1490728Y1124223D01*
G02X1490656Y1124651I1225J426D01*
G37*
G36*
G01X1498056D02*
G02X1500650I1297J0D01*
G02X1499595Y1123376I-1298J0D01*
G01X1499505Y1123359D01*
X1498698Y1121962D01*
X1498729Y1121875D01*
G02X1498802Y1121447I-1225J-429D01*
G02X1496206I-1298J0D01*
G02X1497262Y1122722I1298J0D01*
G01X1497352Y1122739D01*
X1498159Y1124136D01*
X1498128Y1124223D01*
G02X1498056Y1124651I1225J426D01*
G37*
G36*
G01X353564Y1127856D02*
G02X356158I1297J0D01*
G02X355103Y1126581I-1298J0D01*
G01X355013Y1126564D01*
X354205Y1125166D01*
X354236Y1125079D01*
G02X354308Y1124651I-1225J-426D01*
G02X351714I-1297J0D01*
G02X352769Y1125926I1298J0D01*
G01X352859Y1125943D01*
X353667Y1127341D01*
X353636Y1127428D01*
G02X353564Y1127856I1225J426D01*
G37*
G36*
G01X360964D02*
G02X363560I1298J0D01*
G02X362504Y1126581I-1298J0D01*
G01X362414Y1126564D01*
X361606Y1125166D01*
X361637Y1125079D01*
G02X361710Y1124651I-1225J-429D01*
G02X359114I-1298J0D01*
G02X360170Y1125926I1298J0D01*
G01X360260Y1125943D01*
X361068Y1127341D01*
X361037Y1127428D01*
G02X360964Y1127856I1225J429D01*
G37*
G36*
G01X368364D02*
G02X370960I1298J0D01*
G02X369904Y1126581I-1298J0D01*
G01X369814Y1126564D01*
X369006Y1125165D01*
X369036Y1125078D01*
G02X369108Y1124653I-1225J-426D01*
G01Y1124651D01*
G02X366514I-1297J0D01*
G02X367570Y1125926I1298J0D01*
G01X367661Y1125943D01*
X368468Y1127341D01*
X368437Y1127428D01*
G02X368364Y1127856I1225J429D01*
G37*
G36*
G01X375764D02*
G02X378360I1298J0D01*
G02X377304Y1126581I-1298J0D01*
G01X377214Y1126564D01*
X376406Y1125165D01*
X376436Y1125078D01*
G02X376508Y1124653I-1225J-426D01*
G01Y1124651D01*
G02X373914I-1297J0D01*
G02X374970Y1125926I1298J0D01*
G01X375061Y1125943D01*
X375868Y1127341D01*
X375837Y1127428D01*
G02X375764Y1127856I1225J429D01*
G37*
G36*
G01X383164D02*
G02X385760I1298J0D01*
G02X384704Y1126581I-1298J0D01*
G01X384614Y1126564D01*
X383806Y1125165D01*
X383836Y1125078D01*
G02X383908Y1124653I-1225J-426D01*
G01Y1124651D01*
G02X381314I-1297J0D01*
G02X382370Y1125926I1298J0D01*
G01X382461Y1125943D01*
X383268Y1127341D01*
X383237Y1127428D01*
G02X383164Y1127856I1225J429D01*
G37*
G36*
G01X390564D02*
G02X393160I1298J0D01*
G02X392104Y1126581I-1298J0D01*
G01X392014Y1126564D01*
X391206Y1125165D01*
X391236Y1125078D01*
G02X391308Y1124653I-1225J-426D01*
G01Y1124651D01*
G02X388714I-1297J0D01*
G02X389770Y1125926I1298J0D01*
G01X389861Y1125943D01*
X390668Y1127341D01*
X390637Y1127428D01*
G02X390564Y1127856I1225J429D01*
G37*
G36*
G01X397964D02*
G02X400560I1298J0D01*
G02X399504Y1126581I-1298J0D01*
G01X399414Y1126564D01*
X398606Y1125165D01*
X398636Y1125078D01*
G02X398708Y1124653I-1225J-426D01*
G01Y1124651D01*
G02X396114I-1297J0D01*
G02X397170Y1125926I1298J0D01*
G01X397261Y1125943D01*
X398068Y1127341D01*
X398037Y1127428D01*
G02X397964Y1127856I1225J429D01*
G37*
G36*
G01X405364D02*
G02X407960I1298J0D01*
G02X406904Y1126581I-1298J0D01*
G01X406814Y1126564D01*
X406006Y1125165D01*
X406036Y1125078D01*
G02X406108Y1124653I-1225J-426D01*
G01Y1124651D01*
G02X403514I-1297J0D01*
G02X404570Y1125926I1298J0D01*
G01X404661Y1125943D01*
X405468Y1127341D01*
X405437Y1127428D01*
G02X405364Y1127856I1225J429D01*
G37*
G36*
G01X471964D02*
G02X474560I1298J0D01*
G02X474487Y1127427I-1297J0D01*
G01X474456Y1127341D01*
X475263Y1125943D01*
X475353Y1125926D01*
G02X476408Y1124651I-243J-1275D01*
G02X473814I-1297J0D01*
G02X473886Y1125080I1297J3D01*
G01X473917Y1125166D01*
X473110Y1126564D01*
X473020Y1126581D01*
G02X471964Y1127856I242J1275D01*
G37*
G36*
G01X479364D02*
G02X481960I1298J0D01*
G02X481887Y1127427I-1297J0D01*
G01X481856Y1127341D01*
X482663Y1125943D01*
X482753Y1125926D01*
G02X483808Y1124651I-243J-1275D01*
G02X481214I-1297J0D01*
G02X481286Y1125080I1297J3D01*
G01X481317Y1125166D01*
X480510Y1126564D01*
X480420Y1126581D01*
G02X479364Y1127856I242J1275D01*
G37*
G36*
G01X486764D02*
G02X489360I1298J0D01*
G02X489287Y1127427I-1297J0D01*
G01X489256Y1127341D01*
X490063Y1125943D01*
X490153Y1125926D01*
G02X491208Y1124651I-243J-1275D01*
G02X488614I-1297J0D01*
G02X488686Y1125080I1297J3D01*
G01X488717Y1125166D01*
X487910Y1126564D01*
X487820Y1126581D01*
G02X486764Y1127856I242J1275D01*
G37*
G36*
G01X494164D02*
G02X496760I1298J0D01*
G02X496687Y1127427I-1297J0D01*
G01X496656Y1127341D01*
X497463Y1125943D01*
X497553Y1125926D01*
G02X498608Y1124651I-243J-1275D01*
G02X496014I-1297J0D01*
G02X496086Y1125080I1297J3D01*
G01X496117Y1125166D01*
X495310Y1126564D01*
X495220Y1126581D01*
G02X494164Y1127856I242J1275D01*
G37*
G36*
G01X501564D02*
G02X504160I1298J0D01*
G02X504087Y1127427I-1297J0D01*
G01X504056Y1127341D01*
X504863Y1125943D01*
X504953Y1125926D01*
G02X506008Y1124651I-243J-1275D01*
G02X503414I-1297J0D01*
G02X503486Y1125080I1297J3D01*
G01X503517Y1125166D01*
X502710Y1126564D01*
X502620Y1126581D01*
G02X501564Y1127856I242J1275D01*
G37*
G36*
G01X508964D02*
G02X511560I1298J0D01*
G02X511487Y1127427I-1297J0D01*
G01X511456Y1127341D01*
X512263Y1125943D01*
X512353Y1125926D01*
G02X513408Y1124651I-243J-1275D01*
G02X510814I-1297J0D01*
G02X510886Y1125080I1297J3D01*
G01X510917Y1125166D01*
X510110Y1126564D01*
X510020Y1126581D01*
G02X508964Y1127856I242J1275D01*
G37*
G36*
G01X516364D02*
G02X518960I1298J0D01*
G02X518887Y1127427I-1297J0D01*
G01X518856Y1127341D01*
X519663Y1125943D01*
X519753Y1125926D01*
G02X520808Y1124651I-243J-1275D01*
G02X518214I-1297J0D01*
G02X518286Y1125080I1297J3D01*
G01X518317Y1125166D01*
X517510Y1126564D01*
X517420Y1126581D01*
G02X516364Y1127856I242J1275D01*
G37*
G36*
G01X523764D02*
G02X526360I1298J0D01*
G02X526287Y1127427I-1297J0D01*
G01X526256Y1127341D01*
X527063Y1125943D01*
X527153Y1125926D01*
G02X528208Y1124651I-243J-1275D01*
G02X525614I-1297J0D01*
G02X525686Y1125080I1297J3D01*
G01X525717Y1125166D01*
X524910Y1126564D01*
X524820Y1126581D01*
G02X523764Y1127856I242J1275D01*
G37*
G36*
G01X1329706D02*
G02X1332300I1297J0D01*
G02X1331245Y1126581I-1298J0D01*
G01X1331155Y1126564D01*
X1330347Y1125166D01*
X1330378Y1125079D01*
G02X1330450Y1124651I-1225J-426D01*
G02X1327856I-1297J0D01*
G02X1328911Y1125926I1298J0D01*
G01X1329001Y1125943D01*
X1329809Y1127341D01*
X1329778Y1127428D01*
G02X1329706Y1127856I1225J426D01*
G37*
G36*
G01X1337106D02*
G02X1339702I1298J0D01*
G02X1338646Y1126581I-1298J0D01*
G01X1338556Y1126564D01*
X1337748Y1125166D01*
X1337779Y1125079D01*
G02X1337852Y1124651I-1225J-429D01*
G02X1335256I-1298J0D01*
G02X1336312Y1125926I1298J0D01*
G01X1336402Y1125943D01*
X1337210Y1127341D01*
X1337179Y1127428D01*
G02X1337106Y1127856I1225J429D01*
G37*
G36*
G01X1344506D02*
G02X1347102I1298J0D01*
G02X1346046Y1126581I-1298J0D01*
G01X1345956Y1126564D01*
X1345148Y1125165D01*
X1345178Y1125078D01*
G02X1345250Y1124653I-1225J-426D01*
G01Y1124651D01*
G02X1342656I-1297J0D01*
G02X1343712Y1125926I1298J0D01*
G01X1343803Y1125943D01*
X1344610Y1127341D01*
X1344579Y1127428D01*
G02X1344506Y1127856I1225J429D01*
G37*
G36*
G01X1351906D02*
G02X1354502I1298J0D01*
G02X1353446Y1126581I-1298J0D01*
G01X1353356Y1126564D01*
X1352548Y1125165D01*
X1352578Y1125078D01*
G02X1352650Y1124653I-1225J-426D01*
G01Y1124651D01*
G02X1350056I-1297J0D01*
G02X1351112Y1125926I1298J0D01*
G01X1351203Y1125943D01*
X1352010Y1127341D01*
X1351979Y1127428D01*
G02X1351906Y1127856I1225J429D01*
G37*
G36*
G01X1359306D02*
G02X1361902I1298J0D01*
G02X1360846Y1126581I-1298J0D01*
G01X1360756Y1126564D01*
X1359948Y1125165D01*
X1359978Y1125078D01*
G02X1360050Y1124653I-1225J-426D01*
G01Y1124651D01*
G02X1357456I-1297J0D01*
G02X1358512Y1125926I1298J0D01*
G01X1358603Y1125943D01*
X1359410Y1127341D01*
X1359379Y1127428D01*
G02X1359306Y1127856I1225J429D01*
G37*
G36*
G01X1366706D02*
G02X1369302I1298J0D01*
G02X1368246Y1126581I-1298J0D01*
G01X1368156Y1126564D01*
X1367348Y1125165D01*
X1367378Y1125078D01*
G02X1367450Y1124653I-1225J-426D01*
G01Y1124651D01*
G02X1364856I-1297J0D01*
G02X1365912Y1125926I1298J0D01*
G01X1366003Y1125943D01*
X1366810Y1127341D01*
X1366779Y1127428D01*
G02X1366706Y1127856I1225J429D01*
G37*
G36*
G01X1374106D02*
G02X1376702I1298J0D01*
G02X1375646Y1126581I-1298J0D01*
G01X1375556Y1126564D01*
X1374748Y1125165D01*
X1374778Y1125078D01*
G02X1374850Y1124653I-1225J-426D01*
G01Y1124651D01*
G02X1372256I-1297J0D01*
G02X1373312Y1125926I1298J0D01*
G01X1373403Y1125943D01*
X1374210Y1127341D01*
X1374179Y1127428D01*
G02X1374106Y1127856I1225J429D01*
G37*
G36*
G01X1381506D02*
G02X1384102I1298J0D01*
G02X1383046Y1126581I-1298J0D01*
G01X1382956Y1126564D01*
X1382148Y1125165D01*
X1382178Y1125078D01*
G02X1382250Y1124653I-1225J-426D01*
G01Y1124651D01*
G02X1379656I-1297J0D01*
G02X1380712Y1125926I1298J0D01*
G01X1380803Y1125943D01*
X1381610Y1127341D01*
X1381579Y1127428D01*
G02X1381506Y1127856I1225J429D01*
G37*
G36*
G01X1448106D02*
G02X1450702I1298J0D01*
G02X1450629Y1127427I-1297J0D01*
G01X1450598Y1127341D01*
X1451405Y1125943D01*
X1451495Y1125926D01*
G02X1452550Y1124651I-243J-1275D01*
G02X1449956I-1297J0D01*
G02X1450028Y1125080I1297J3D01*
G01X1450059Y1125166D01*
X1449252Y1126564D01*
X1449162Y1126581D01*
G02X1448106Y1127856I242J1275D01*
G37*
G36*
G01X1455506D02*
G02X1458102I1298J0D01*
G02X1458029Y1127427I-1297J0D01*
G01X1457998Y1127341D01*
X1458805Y1125943D01*
X1458895Y1125926D01*
G02X1459950Y1124651I-243J-1275D01*
G02X1457356I-1297J0D01*
G02X1457428Y1125080I1297J3D01*
G01X1457459Y1125166D01*
X1456652Y1126564D01*
X1456562Y1126581D01*
G02X1455506Y1127856I242J1275D01*
G37*
G36*
G01X1462906D02*
G02X1465502I1298J0D01*
G02X1465429Y1127427I-1297J0D01*
G01X1465398Y1127341D01*
X1466205Y1125943D01*
X1466295Y1125926D01*
G02X1467350Y1124651I-243J-1275D01*
G02X1464756I-1297J0D01*
G02X1464828Y1125080I1297J3D01*
G01X1464859Y1125166D01*
X1464052Y1126564D01*
X1463962Y1126581D01*
G02X1462906Y1127856I242J1275D01*
G37*
G36*
G01X1470306D02*
G02X1472902I1298J0D01*
G02X1472829Y1127427I-1297J0D01*
G01X1472798Y1127341D01*
X1473605Y1125943D01*
X1473695Y1125926D01*
G02X1474750Y1124651I-243J-1275D01*
G02X1472156I-1297J0D01*
G02X1472228Y1125080I1297J3D01*
G01X1472259Y1125166D01*
X1471452Y1126564D01*
X1471362Y1126581D01*
G02X1470306Y1127856I242J1275D01*
G37*
G36*
G01X1477706D02*
G02X1480302I1298J0D01*
G02X1480229Y1127427I-1297J0D01*
G01X1480198Y1127341D01*
X1481005Y1125943D01*
X1481095Y1125926D01*
G02X1482150Y1124651I-243J-1275D01*
G02X1479556I-1297J0D01*
G02X1479628Y1125080I1297J3D01*
G01X1479659Y1125166D01*
X1478852Y1126564D01*
X1478762Y1126581D01*
G02X1477706Y1127856I242J1275D01*
G37*
G36*
G01X1485106D02*
G02X1487702I1298J0D01*
G02X1487629Y1127427I-1297J0D01*
G01X1487598Y1127341D01*
X1488405Y1125943D01*
X1488495Y1125926D01*
G02X1489550Y1124651I-243J-1275D01*
G02X1486956I-1297J0D01*
G02X1487028Y1125080I1297J3D01*
G01X1487059Y1125166D01*
X1486252Y1126564D01*
X1486162Y1126581D01*
G02X1485106Y1127856I242J1275D01*
G37*
G36*
G01X1492506D02*
G02X1495102I1298J0D01*
G02X1495029Y1127427I-1297J0D01*
G01X1494998Y1127341D01*
X1495805Y1125943D01*
X1495895Y1125926D01*
G02X1496950Y1124651I-243J-1275D01*
G02X1494356I-1297J0D01*
G02X1494428Y1125080I1297J3D01*
G01X1494459Y1125166D01*
X1493652Y1126564D01*
X1493562Y1126581D01*
G02X1492506Y1127856I242J1275D01*
G37*
G36*
G01X1499906D02*
G02X1502502I1298J0D01*
G02X1502429Y1127427I-1297J0D01*
G01X1502398Y1127341D01*
X1503205Y1125943D01*
X1503295Y1125926D01*
G02X1504350Y1124651I-243J-1275D01*
G02X1501756I-1297J0D01*
G02X1501828Y1125080I1297J3D01*
G01X1501859Y1125166D01*
X1501052Y1126564D01*
X1500962Y1126581D01*
G02X1499906Y1127856I242J1275D01*
G37*
G36*
G01X340614Y1131060D02*
G02X343208I1297J0D01*
G02X342153Y1129785I-1298J0D01*
G01X342063Y1129768D01*
X341256Y1128370D01*
X341286Y1128284D01*
G02X341358Y1127856I-1225J-426D01*
G02X338764I-1297J0D01*
G02X339819Y1129131I1298J0D01*
G01X339909Y1129148D01*
X340716Y1130546D01*
X340686Y1130632D01*
G02X340614Y1131060I1225J426D01*
G37*
G36*
G01X1316756D02*
G02X1319350I1297J0D01*
G02X1318295Y1129785I-1298J0D01*
G01X1318205Y1129768D01*
X1317398Y1128370D01*
X1317428Y1128284D01*
G02X1317500Y1127856I-1225J-426D01*
G02X1314906I-1297J0D01*
G02X1315961Y1129131I1298J0D01*
G01X1316051Y1129148D01*
X1316858Y1130546D01*
X1316828Y1130632D01*
G02X1316756Y1131060I1225J426D01*
G37*
G36*
G01X348014Y1137469D02*
G02X350610I1298J0D01*
G02X350537Y1137040I-1297J0D01*
G01X350506Y1136954D01*
X351313Y1135556D01*
X351403Y1135539D01*
G02X352458Y1134264I-243J-1275D01*
G02X349864I-1297J0D01*
G02X349936Y1134693I1297J3D01*
G01X349967Y1134779D01*
X349160Y1136177D01*
X349070Y1136194D01*
G02X348014Y1137469I242J1275D01*
G37*
G36*
G01X355414D02*
G02X358010I1298J0D01*
G02X357937Y1137040I-1297J0D01*
G01X357906Y1136954D01*
X358713Y1135556D01*
X358803Y1135539D01*
G02X359858Y1134264I-243J-1275D01*
G02X357264I-1297J0D01*
G02X357336Y1134693I1297J3D01*
G01X357367Y1134779D01*
X356560Y1136177D01*
X356470Y1136194D01*
G02X355414Y1137469I242J1275D01*
G37*
G36*
G01X362814D02*
G02X365410I1298J0D01*
G02X365337Y1137041I-1298J1D01*
G01X365306Y1136954D01*
X366114Y1135556D01*
X366204Y1135539D01*
G02X367260Y1134264I-242J-1275D01*
G02X364664I-1298J0D01*
G02X364737Y1134692I1298J-1D01*
G01X364768Y1134779D01*
X363960Y1136177D01*
X363870Y1136194D01*
G02X362814Y1137469I242J1275D01*
G37*
G36*
G01X370214D02*
G02X372810I1298J0D01*
G02X372737Y1137041I-1298J1D01*
G01X372706Y1136954D01*
X373514Y1135556D01*
X373604Y1135539D01*
G02X374660Y1134264I-242J-1275D01*
G02X372064I-1298J0D01*
G02X372137Y1134692I1298J-1D01*
G01X372168Y1134779D01*
X371360Y1136177D01*
X371270Y1136194D01*
G02X370214Y1137469I242J1275D01*
G37*
G36*
G01X377614D02*
G02X380210I1298J0D01*
G02X380137Y1137041I-1298J1D01*
G01X380106Y1136954D01*
X380914Y1135556D01*
X381004Y1135539D01*
G02X382060Y1134264I-242J-1275D01*
G02X379464I-1298J0D01*
G02X379537Y1134692I1298J-1D01*
G01X379568Y1134779D01*
X378760Y1136177D01*
X378670Y1136194D01*
G02X377614Y1137469I242J1275D01*
G37*
G36*
G01X385014D02*
G02X387610I1298J0D01*
G02X387537Y1137041I-1298J1D01*
G01X387506Y1136954D01*
X388314Y1135556D01*
X388404Y1135539D01*
G02X389460Y1134264I-242J-1275D01*
G02X386864I-1298J0D01*
G02X386937Y1134692I1298J-1D01*
G01X386968Y1134779D01*
X386160Y1136177D01*
X386070Y1136194D01*
G02X385014Y1137469I242J1275D01*
G37*
G36*
G01X392414D02*
G02X395010I1298J0D01*
G02X394937Y1137041I-1298J1D01*
G01X394906Y1136954D01*
X395714Y1135556D01*
X395804Y1135539D01*
G02X396860Y1134264I-242J-1275D01*
G02X394264I-1298J0D01*
G02X394337Y1134692I1298J-1D01*
G01X394368Y1134779D01*
X393560Y1136177D01*
X393470Y1136194D01*
G02X392414Y1137469I242J1275D01*
G37*
G36*
G01X399814D02*
G02X402410I1298J0D01*
G02X402337Y1137041I-1298J1D01*
G01X402306Y1136954D01*
X403114Y1135556D01*
X403204Y1135539D01*
G02X404260Y1134264I-242J-1275D01*
G02X401664I-1298J0D01*
G02X401737Y1134692I1298J-1D01*
G01X401768Y1134779D01*
X400960Y1136177D01*
X400870Y1136194D01*
G02X399814Y1137469I242J1275D01*
G37*
G36*
G01X407214D02*
G02X409810I1298J0D01*
G02X409737Y1137041I-1298J1D01*
G01X409706Y1136954D01*
X410514Y1135556D01*
X410604Y1135539D01*
G02X411660Y1134264I-242J-1275D01*
G02X409064I-1298J0D01*
G02X409137Y1134692I1298J-1D01*
G01X409168Y1134779D01*
X408360Y1136177D01*
X408270Y1136194D01*
G02X407214Y1137469I242J1275D01*
G37*
G36*
G01X477514D02*
G02X480110I1298J0D01*
G02X479054Y1136194I-1298J0D01*
G01X478964Y1136177D01*
X478156Y1134779D01*
X478187Y1134692D01*
G02X478260Y1134264I-1225J-429D01*
G02X475664I-1298J0D01*
G02X476720Y1135539I1298J0D01*
G01X476810Y1135556D01*
X477618Y1136954D01*
X477587Y1137041D01*
G02X477514Y1137469I1225J429D01*
G37*
G36*
G01X484914D02*
G02X487510I1298J0D01*
G02X486454Y1136194I-1298J0D01*
G01X486364Y1136177D01*
X485557Y1134779D01*
X485587Y1134692D01*
G02X485660Y1134264I-1225J-429D01*
G02X483064I-1298J0D01*
G02X484121Y1135539I1297J0D01*
G01X484211Y1135556D01*
X485018Y1136954D01*
X484987Y1137041D01*
G02X484914Y1137469I1225J429D01*
G37*
G36*
G01X492314D02*
G02X494910I1298J0D01*
G02X493854Y1136194I-1298J0D01*
G01X493764Y1136177D01*
X492957Y1134779D01*
X492987Y1134692D01*
G02X493060Y1134264I-1225J-429D01*
G02X490464I-1298J0D01*
G02X491521Y1135539I1297J0D01*
G01X491611Y1135556D01*
X492418Y1136954D01*
X492387Y1137041D01*
G02X492314Y1137469I1225J429D01*
G37*
G36*
G01X499714D02*
G02X502310I1298J0D01*
G02X501254Y1136194I-1298J0D01*
G01X501164Y1136177D01*
X500357Y1134779D01*
X500387Y1134692D01*
G02X500460Y1134264I-1225J-429D01*
G02X497864I-1298J0D01*
G02X498921Y1135539I1297J0D01*
G01X499011Y1135556D01*
X499818Y1136954D01*
X499787Y1137041D01*
G02X499714Y1137469I1225J429D01*
G37*
G36*
G01X507114D02*
G02X509710I1298J0D01*
G02X508654Y1136194I-1298J0D01*
G01X508564Y1136177D01*
X507757Y1134779D01*
X507787Y1134692D01*
G02X507860Y1134264I-1225J-429D01*
G02X505264I-1298J0D01*
G02X506321Y1135539I1297J0D01*
G01X506411Y1135556D01*
X507218Y1136954D01*
X507187Y1137041D01*
G02X507114Y1137469I1225J429D01*
G37*
G36*
G01X514514D02*
G02X517110I1298J0D01*
G02X516054Y1136194I-1298J0D01*
G01X515964Y1136177D01*
X515157Y1134779D01*
X515187Y1134692D01*
G02X515260Y1134264I-1225J-429D01*
G02X512664I-1298J0D01*
G02X513721Y1135539I1297J0D01*
G01X513811Y1135556D01*
X514618Y1136954D01*
X514587Y1137041D01*
G02X514514Y1137469I1225J429D01*
G37*
G36*
G01X521914D02*
G02X524510I1298J0D01*
G02X523454Y1136194I-1298J0D01*
G01X523364Y1136177D01*
X522557Y1134779D01*
X522587Y1134692D01*
G02X522660Y1134264I-1225J-429D01*
G02X520064I-1298J0D01*
G02X521121Y1135539I1297J0D01*
G01X521211Y1135556D01*
X522018Y1136954D01*
X521987Y1137041D01*
G02X521914Y1137469I1225J429D01*
G37*
G36*
G01X533014D02*
G02X535610I1298J0D01*
G02X534554Y1136194I-1298J0D01*
G01X534464Y1136177D01*
X533656Y1134779D01*
X533687Y1134692D01*
G02X533760Y1134264I-1225J-429D01*
G02X531164I-1298J0D01*
G02X532220Y1135539I1298J0D01*
G01X532310Y1135556D01*
X533118Y1136954D01*
X533087Y1137041D01*
G02X533014Y1137469I1225J429D01*
G37*
G36*
G01X1324156D02*
G02X1326752I1298J0D01*
G02X1326679Y1137040I-1297J0D01*
G01X1326648Y1136954D01*
X1327455Y1135556D01*
X1327545Y1135539D01*
G02X1328600Y1134264I-243J-1275D01*
G02X1326006I-1297J0D01*
G02X1326078Y1134693I1297J3D01*
G01X1326109Y1134779D01*
X1325302Y1136177D01*
X1325212Y1136194D01*
G02X1324156Y1137469I242J1275D01*
G37*
G36*
G01X1331556D02*
G02X1334152I1298J0D01*
G02X1334079Y1137040I-1297J0D01*
G01X1334048Y1136954D01*
X1334855Y1135556D01*
X1334945Y1135539D01*
G02X1336000Y1134264I-243J-1275D01*
G02X1333406I-1297J0D01*
G02X1333478Y1134693I1297J3D01*
G01X1333509Y1134779D01*
X1332702Y1136177D01*
X1332612Y1136194D01*
G02X1331556Y1137469I242J1275D01*
G37*
G36*
G01X1338956D02*
G02X1341552I1298J0D01*
G02X1341479Y1137041I-1298J1D01*
G01X1341448Y1136954D01*
X1342256Y1135556D01*
X1342346Y1135539D01*
G02X1343402Y1134264I-242J-1275D01*
G02X1340806I-1298J0D01*
G02X1340879Y1134692I1298J-1D01*
G01X1340910Y1134779D01*
X1340102Y1136177D01*
X1340012Y1136194D01*
G02X1338956Y1137469I242J1275D01*
G37*
G36*
G01X1346356D02*
G02X1348952I1298J0D01*
G02X1348879Y1137041I-1298J1D01*
G01X1348848Y1136954D01*
X1349656Y1135556D01*
X1349746Y1135539D01*
G02X1350802Y1134264I-242J-1275D01*
G02X1348206I-1298J0D01*
G02X1348279Y1134692I1298J-1D01*
G01X1348310Y1134779D01*
X1347502Y1136177D01*
X1347412Y1136194D01*
G02X1346356Y1137469I242J1275D01*
G37*
G36*
G01X1353756D02*
G02X1356352I1298J0D01*
G02X1356279Y1137041I-1298J1D01*
G01X1356248Y1136954D01*
X1357056Y1135556D01*
X1357146Y1135539D01*
G02X1358202Y1134264I-242J-1275D01*
G02X1355606I-1298J0D01*
G02X1355679Y1134692I1298J-1D01*
G01X1355710Y1134779D01*
X1354902Y1136177D01*
X1354812Y1136194D01*
G02X1353756Y1137469I242J1275D01*
G37*
G36*
G01X1361156D02*
G02X1363752I1298J0D01*
G02X1363679Y1137041I-1298J1D01*
G01X1363648Y1136954D01*
X1364456Y1135556D01*
X1364546Y1135539D01*
G02X1365602Y1134264I-242J-1275D01*
G02X1363006I-1298J0D01*
G02X1363079Y1134692I1298J-1D01*
G01X1363110Y1134779D01*
X1362302Y1136177D01*
X1362212Y1136194D01*
G02X1361156Y1137469I242J1275D01*
G37*
G36*
G01X1368556D02*
G02X1371152I1298J0D01*
G02X1371079Y1137041I-1298J1D01*
G01X1371048Y1136954D01*
X1371856Y1135556D01*
X1371946Y1135539D01*
G02X1373002Y1134264I-242J-1275D01*
G02X1370406I-1298J0D01*
G02X1370479Y1134692I1298J-1D01*
G01X1370510Y1134779D01*
X1369702Y1136177D01*
X1369612Y1136194D01*
G02X1368556Y1137469I242J1275D01*
G37*
G36*
G01X1375956D02*
G02X1378552I1298J0D01*
G02X1378479Y1137041I-1298J1D01*
G01X1378448Y1136954D01*
X1379256Y1135556D01*
X1379346Y1135539D01*
G02X1380402Y1134264I-242J-1275D01*
G02X1377806I-1298J0D01*
G02X1377879Y1134692I1298J-1D01*
G01X1377910Y1134779D01*
X1377102Y1136177D01*
X1377012Y1136194D01*
G02X1375956Y1137469I242J1275D01*
G37*
G36*
G01X1383356D02*
G02X1385952I1298J0D01*
G02X1385879Y1137041I-1298J1D01*
G01X1385848Y1136954D01*
X1386656Y1135556D01*
X1386746Y1135539D01*
G02X1387802Y1134264I-242J-1275D01*
G02X1385206I-1298J0D01*
G02X1385279Y1134692I1298J-1D01*
G01X1385310Y1134779D01*
X1384502Y1136177D01*
X1384412Y1136194D01*
G02X1383356Y1137469I242J1275D01*
G37*
G36*
G01X1453656D02*
G02X1456252I1298J0D01*
G02X1455196Y1136194I-1298J0D01*
G01X1455106Y1136177D01*
X1454298Y1134779D01*
X1454329Y1134692D01*
G02X1454402Y1134264I-1225J-429D01*
G02X1451806I-1298J0D01*
G02X1452862Y1135539I1298J0D01*
G01X1452952Y1135556D01*
X1453760Y1136954D01*
X1453729Y1137041D01*
G02X1453656Y1137469I1225J429D01*
G37*
G36*
G01X1461056D02*
G02X1463652I1298J0D01*
G02X1462596Y1136194I-1298J0D01*
G01X1462506Y1136177D01*
X1461699Y1134779D01*
X1461729Y1134692D01*
G02X1461802Y1134264I-1225J-429D01*
G02X1459206I-1298J0D01*
G02X1460263Y1135539I1297J0D01*
G01X1460353Y1135556D01*
X1461160Y1136954D01*
X1461129Y1137041D01*
G02X1461056Y1137469I1225J429D01*
G37*
G36*
G01X1468456D02*
G02X1471052I1298J0D01*
G02X1469996Y1136194I-1298J0D01*
G01X1469906Y1136177D01*
X1469099Y1134779D01*
X1469129Y1134692D01*
G02X1469202Y1134264I-1225J-429D01*
G02X1466606I-1298J0D01*
G02X1467663Y1135539I1297J0D01*
G01X1467753Y1135556D01*
X1468560Y1136954D01*
X1468529Y1137041D01*
G02X1468456Y1137469I1225J429D01*
G37*
G36*
G01X1475856D02*
G02X1478452I1298J0D01*
G02X1477396Y1136194I-1298J0D01*
G01X1477306Y1136177D01*
X1476499Y1134779D01*
X1476529Y1134692D01*
G02X1476602Y1134264I-1225J-429D01*
G02X1474006I-1298J0D01*
G02X1475063Y1135539I1297J0D01*
G01X1475153Y1135556D01*
X1475960Y1136954D01*
X1475929Y1137041D01*
G02X1475856Y1137469I1225J429D01*
G37*
G36*
G01X1483256D02*
G02X1485852I1298J0D01*
G02X1484796Y1136194I-1298J0D01*
G01X1484706Y1136177D01*
X1483899Y1134779D01*
X1483929Y1134692D01*
G02X1484002Y1134264I-1225J-429D01*
G02X1481406I-1298J0D01*
G02X1482463Y1135539I1297J0D01*
G01X1482553Y1135556D01*
X1483360Y1136954D01*
X1483329Y1137041D01*
G02X1483256Y1137469I1225J429D01*
G37*
G36*
G01X1490656D02*
G02X1493252I1298J0D01*
G02X1492196Y1136194I-1298J0D01*
G01X1492106Y1136177D01*
X1491299Y1134779D01*
X1491329Y1134692D01*
G02X1491402Y1134264I-1225J-429D01*
G02X1488806I-1298J0D01*
G02X1489863Y1135539I1297J0D01*
G01X1489953Y1135556D01*
X1490760Y1136954D01*
X1490729Y1137041D01*
G02X1490656Y1137469I1225J429D01*
G37*
G36*
G01X1498056D02*
G02X1500652I1298J0D01*
G02X1499596Y1136194I-1298J0D01*
G01X1499506Y1136177D01*
X1498699Y1134779D01*
X1498729Y1134692D01*
G02X1498802Y1134264I-1225J-429D01*
G02X1496206I-1298J0D01*
G02X1497263Y1135539I1297J0D01*
G01X1497353Y1135556D01*
X1498160Y1136954D01*
X1498129Y1137041D01*
G02X1498056Y1137469I1225J429D01*
G37*
G36*
G01X1509156D02*
G02X1511752I1298J0D01*
G02X1510696Y1136194I-1298J0D01*
G01X1510606Y1136177D01*
X1509798Y1134779D01*
X1509829Y1134692D01*
G02X1509902Y1134264I-1225J-429D01*
G02X1507306I-1298J0D01*
G02X1508362Y1135539I1298J0D01*
G01X1508452Y1135556D01*
X1509260Y1136954D01*
X1509229Y1137041D01*
G02X1509156Y1137469I1225J429D01*
G37*
G36*
G01X360964Y1140973D02*
G02X363558I1297J0D01*
G02X362496Y1139697I-1298J0D01*
G01X362401Y1139679D01*
X361559Y1138084D01*
X361598Y1137995D01*
G02X361710Y1137469I-1186J-527D01*
G02X359114I-1298J0D01*
G02X360177Y1138745I1297J0D01*
G01X360272Y1138763D01*
X361114Y1140358D01*
X361075Y1140447D01*
G02X360964Y1140971I1186J525D01*
G01Y1140973D01*
G37*
G36*
G01X368364D02*
G02X370958I1297J0D01*
G02X369896Y1139697I-1298J0D01*
G01X369801Y1139679D01*
X368959Y1138084D01*
X368998Y1137995D01*
G02X369110Y1137469I-1186J-527D01*
G02X366514I-1298J0D01*
G02X367577Y1138745I1297J0D01*
G01X367672Y1138763D01*
X368514Y1140358D01*
X368475Y1140447D01*
G02X368364Y1140971I1186J525D01*
G01Y1140973D01*
G37*
G36*
G01X375764D02*
G02X378358I1297J0D01*
G02X377296Y1139697I-1298J0D01*
G01X377201Y1139679D01*
X376359Y1138084D01*
X376398Y1137995D01*
G02X376510Y1137469I-1186J-527D01*
G02X373914I-1298J0D01*
G02X374977Y1138745I1297J0D01*
G01X375072Y1138763D01*
X375914Y1140358D01*
X375875Y1140447D01*
G02X375764Y1140971I1186J525D01*
G01Y1140973D01*
G37*
G36*
G01X383164D02*
G02X385758I1297J0D01*
G02X384696Y1139697I-1298J0D01*
G01X384601Y1139679D01*
X383759Y1138084D01*
X383798Y1137995D01*
G02X383910Y1137469I-1186J-527D01*
G02X381314I-1298J0D01*
G02X382377Y1138745I1297J0D01*
G01X382472Y1138763D01*
X383314Y1140358D01*
X383275Y1140447D01*
G02X383164Y1140971I1186J525D01*
G01Y1140973D01*
G37*
G36*
G01X390564D02*
G02X393158I1297J0D01*
G02X392096Y1139697I-1298J0D01*
G01X392001Y1139679D01*
X391159Y1138084D01*
X391198Y1137995D01*
G02X391310Y1137469I-1186J-527D01*
G02X388714I-1298J0D01*
G02X389777Y1138745I1297J0D01*
G01X389872Y1138763D01*
X390714Y1140358D01*
X390675Y1140447D01*
G02X390564Y1140971I1186J525D01*
G01Y1140973D01*
G37*
G36*
G01X397964D02*
G02X400558I1297J0D01*
G02X399496Y1139697I-1298J0D01*
G01X399401Y1139679D01*
X398559Y1138084D01*
X398598Y1137995D01*
G02X398710Y1137469I-1186J-527D01*
G02X396114I-1298J0D01*
G02X397177Y1138745I1297J0D01*
G01X397272Y1138763D01*
X398114Y1140358D01*
X398075Y1140447D01*
G02X397964Y1140971I1186J525D01*
G01Y1140973D01*
G37*
G36*
G01X405364D02*
G02X407958I1297J0D01*
G02X406896Y1139697I-1298J0D01*
G01X406801Y1139679D01*
X405959Y1138084D01*
X405998Y1137995D01*
G02X406110Y1137469I-1186J-527D01*
G02X403514I-1298J0D01*
G02X404577Y1138745I1297J0D01*
G01X404672Y1138763D01*
X405514Y1140358D01*
X405475Y1140447D01*
G02X405364Y1140971I1186J525D01*
G01Y1140973D01*
G37*
G36*
G01X471964D02*
G02X474558I1297J0D01*
G02X474447Y1140448I-1297J0D01*
G01X474408Y1140359D01*
X475252Y1138763D01*
X475347Y1138745D01*
G02X476410Y1137469I-234J-1276D01*
G02X473814I-1298J0D01*
G02X473926Y1137994I1297J-2D01*
G01X473965Y1138083D01*
X473121Y1139679D01*
X473026Y1139697D01*
G02X471964Y1140973I236J1276D01*
G37*
G36*
G01X479364D02*
G02X481958I1297J0D01*
G02X481847Y1140448I-1297J0D01*
G01X481808Y1140359D01*
X482652Y1138763D01*
X482747Y1138745D01*
G02X483810Y1137469I-234J-1276D01*
G02X481214I-1298J0D01*
G02X481326Y1137994I1297J-2D01*
G01X481365Y1138083D01*
X480521Y1139679D01*
X480426Y1139697D01*
G02X479364Y1140973I236J1276D01*
G37*
G36*
G01X486764D02*
G02X489358I1297J0D01*
G02X489247Y1140448I-1297J0D01*
G01X489208Y1140359D01*
X490052Y1138763D01*
X490147Y1138745D01*
G02X491210Y1137469I-234J-1276D01*
G02X488614I-1298J0D01*
G02X488726Y1137994I1297J-2D01*
G01X488765Y1138083D01*
X487921Y1139679D01*
X487826Y1139697D01*
G02X486764Y1140973I236J1276D01*
G37*
G36*
G01X494164D02*
G02X496758I1297J0D01*
G02X496647Y1140448I-1297J0D01*
G01X496608Y1140359D01*
X497452Y1138763D01*
X497547Y1138745D01*
G02X498610Y1137469I-234J-1276D01*
G02X496014I-1298J0D01*
G02X496126Y1137994I1297J-2D01*
G01X496165Y1138083D01*
X495321Y1139679D01*
X495226Y1139697D01*
G02X494164Y1140973I236J1276D01*
G37*
G36*
G01X501564D02*
G02X504158I1297J0D01*
G02X504047Y1140448I-1297J0D01*
G01X504008Y1140359D01*
X504852Y1138763D01*
X504947Y1138745D01*
G02X506010Y1137469I-234J-1276D01*
G02X503414I-1298J0D01*
G02X503526Y1137994I1297J-2D01*
G01X503565Y1138083D01*
X502721Y1139679D01*
X502626Y1139697D01*
G02X501564Y1140973I236J1276D01*
G37*
G36*
G01X508964D02*
G02X511558I1297J0D01*
G02X511447Y1140448I-1297J0D01*
G01X511408Y1140359D01*
X512252Y1138763D01*
X512347Y1138745D01*
G02X513410Y1137469I-234J-1276D01*
G02X510814I-1298J0D01*
G02X510926Y1137994I1297J-2D01*
G01X510965Y1138083D01*
X510121Y1139679D01*
X510026Y1139697D01*
G02X508964Y1140973I236J1276D01*
G37*
G36*
G01X516364D02*
G02X518958I1297J0D01*
G02X518847Y1140448I-1297J0D01*
G01X518808Y1140359D01*
X519652Y1138763D01*
X519747Y1138745D01*
G02X520810Y1137469I-234J-1276D01*
G02X518214I-1298J0D01*
G02X518326Y1137994I1297J-2D01*
G01X518365Y1138083D01*
X517521Y1139679D01*
X517426Y1139697D01*
G02X516364Y1140973I236J1276D01*
G37*
G36*
G01X523764D02*
G02X526358I1297J0D01*
G02X526247Y1140448I-1297J0D01*
G01X526208Y1140359D01*
X527052Y1138763D01*
X527147Y1138745D01*
G02X528210Y1137469I-234J-1276D01*
G02X525614I-1298J0D01*
G02X525726Y1137994I1297J-2D01*
G01X525765Y1138083D01*
X524921Y1139679D01*
X524826Y1139697D01*
G02X523764Y1140973I236J1276D01*
G37*
G36*
G01X1337106D02*
G02X1339700I1297J0D01*
G02X1338638Y1139697I-1298J0D01*
G01X1338543Y1139679D01*
X1337701Y1138084D01*
X1337740Y1137995D01*
G02X1337852Y1137469I-1186J-527D01*
G02X1335256I-1298J0D01*
G02X1336319Y1138745I1297J0D01*
G01X1336414Y1138763D01*
X1337256Y1140358D01*
X1337217Y1140447D01*
G02X1337106Y1140971I1186J525D01*
G01Y1140973D01*
G37*
G36*
G01X1344506D02*
G02X1347100I1297J0D01*
G02X1346038Y1139697I-1298J0D01*
G01X1345943Y1139679D01*
X1345101Y1138084D01*
X1345140Y1137995D01*
G02X1345252Y1137469I-1186J-527D01*
G02X1342656I-1298J0D01*
G02X1343719Y1138745I1297J0D01*
G01X1343814Y1138763D01*
X1344656Y1140358D01*
X1344617Y1140447D01*
G02X1344506Y1140971I1186J525D01*
G01Y1140973D01*
G37*
G36*
G01X1351906D02*
G02X1354500I1297J0D01*
G02X1353438Y1139697I-1298J0D01*
G01X1353343Y1139679D01*
X1352501Y1138084D01*
X1352540Y1137995D01*
G02X1352652Y1137469I-1186J-527D01*
G02X1350056I-1298J0D01*
G02X1351119Y1138745I1297J0D01*
G01X1351214Y1138763D01*
X1352056Y1140358D01*
X1352017Y1140447D01*
G02X1351906Y1140971I1186J525D01*
G01Y1140973D01*
G37*
G36*
G01X1359306D02*
G02X1361900I1297J0D01*
G02X1360838Y1139697I-1298J0D01*
G01X1360743Y1139679D01*
X1359901Y1138084D01*
X1359940Y1137995D01*
G02X1360052Y1137469I-1186J-527D01*
G02X1357456I-1298J0D01*
G02X1358519Y1138745I1297J0D01*
G01X1358614Y1138763D01*
X1359456Y1140358D01*
X1359417Y1140447D01*
G02X1359306Y1140971I1186J525D01*
G01Y1140973D01*
G37*
G36*
G01X1366706D02*
G02X1369300I1297J0D01*
G02X1368238Y1139697I-1298J0D01*
G01X1368143Y1139679D01*
X1367301Y1138084D01*
X1367340Y1137995D01*
G02X1367452Y1137469I-1186J-527D01*
G02X1364856I-1298J0D01*
G02X1365919Y1138745I1297J0D01*
G01X1366014Y1138763D01*
X1366856Y1140358D01*
X1366817Y1140447D01*
G02X1366706Y1140971I1186J525D01*
G01Y1140973D01*
G37*
G36*
G01X1374106D02*
G02X1376700I1297J0D01*
G02X1375638Y1139697I-1298J0D01*
G01X1375543Y1139679D01*
X1374701Y1138084D01*
X1374740Y1137995D01*
G02X1374852Y1137469I-1186J-527D01*
G02X1372256I-1298J0D01*
G02X1373319Y1138745I1297J0D01*
G01X1373414Y1138763D01*
X1374256Y1140358D01*
X1374217Y1140447D01*
G02X1374106Y1140971I1186J525D01*
G01Y1140973D01*
G37*
G36*
G01X1381506D02*
G02X1384100I1297J0D01*
G02X1383038Y1139697I-1298J0D01*
G01X1382943Y1139679D01*
X1382101Y1138084D01*
X1382140Y1137995D01*
G02X1382252Y1137469I-1186J-527D01*
G02X1379656I-1298J0D01*
G02X1380719Y1138745I1297J0D01*
G01X1380814Y1138763D01*
X1381656Y1140358D01*
X1381617Y1140447D01*
G02X1381506Y1140971I1186J525D01*
G01Y1140973D01*
G37*
G36*
G01X1448106D02*
G02X1450700I1297J0D01*
G02X1450589Y1140448I-1297J0D01*
G01X1450550Y1140359D01*
X1451394Y1138763D01*
X1451489Y1138745D01*
G02X1452552Y1137469I-234J-1276D01*
G02X1449956I-1298J0D01*
G02X1450068Y1137994I1297J-2D01*
G01X1450107Y1138083D01*
X1449263Y1139679D01*
X1449168Y1139697D01*
G02X1448106Y1140973I236J1276D01*
G37*
G36*
G01X1455506D02*
G02X1458100I1297J0D01*
G02X1457989Y1140448I-1297J0D01*
G01X1457950Y1140359D01*
X1458794Y1138763D01*
X1458889Y1138745D01*
G02X1459952Y1137469I-234J-1276D01*
G02X1457356I-1298J0D01*
G02X1457468Y1137994I1297J-2D01*
G01X1457507Y1138083D01*
X1456663Y1139679D01*
X1456568Y1139697D01*
G02X1455506Y1140973I236J1276D01*
G37*
G36*
G01X1462906D02*
G02X1465500I1297J0D01*
G02X1465389Y1140448I-1297J0D01*
G01X1465350Y1140359D01*
X1466194Y1138763D01*
X1466289Y1138745D01*
G02X1467352Y1137469I-234J-1276D01*
G02X1464756I-1298J0D01*
G02X1464868Y1137994I1297J-2D01*
G01X1464907Y1138083D01*
X1464063Y1139679D01*
X1463968Y1139697D01*
G02X1462906Y1140973I236J1276D01*
G37*
G36*
G01X1470306D02*
G02X1472900I1297J0D01*
G02X1472789Y1140448I-1297J0D01*
G01X1472750Y1140359D01*
X1473594Y1138763D01*
X1473689Y1138745D01*
G02X1474752Y1137469I-234J-1276D01*
G02X1472156I-1298J0D01*
G02X1472268Y1137994I1297J-2D01*
G01X1472307Y1138083D01*
X1471463Y1139679D01*
X1471368Y1139697D01*
G02X1470306Y1140973I236J1276D01*
G37*
G36*
G01X1477706D02*
G02X1480300I1297J0D01*
G02X1480189Y1140448I-1297J0D01*
G01X1480150Y1140359D01*
X1480994Y1138763D01*
X1481089Y1138745D01*
G02X1482152Y1137469I-234J-1276D01*
G02X1479556I-1298J0D01*
G02X1479668Y1137994I1297J-2D01*
G01X1479707Y1138083D01*
X1478863Y1139679D01*
X1478768Y1139697D01*
G02X1477706Y1140973I236J1276D01*
G37*
G36*
G01X1485106D02*
G02X1487700I1297J0D01*
G02X1487589Y1140448I-1297J0D01*
G01X1487550Y1140359D01*
X1488394Y1138763D01*
X1488489Y1138745D01*
G02X1489552Y1137469I-234J-1276D01*
G02X1486956I-1298J0D01*
G02X1487068Y1137994I1297J-2D01*
G01X1487107Y1138083D01*
X1486263Y1139679D01*
X1486168Y1139697D01*
G02X1485106Y1140973I236J1276D01*
G37*
G36*
G01X1492506D02*
G02X1495100I1297J0D01*
G02X1494989Y1140448I-1297J0D01*
G01X1494950Y1140359D01*
X1495794Y1138763D01*
X1495889Y1138745D01*
G02X1496952Y1137469I-234J-1276D01*
G02X1494356I-1298J0D01*
G02X1494468Y1137994I1297J-2D01*
G01X1494507Y1138083D01*
X1493663Y1139679D01*
X1493568Y1139697D01*
G02X1492506Y1140973I236J1276D01*
G37*
G36*
G01X1499906D02*
G02X1502500I1297J0D01*
G02X1502389Y1140448I-1297J0D01*
G01X1502350Y1140359D01*
X1503194Y1138763D01*
X1503289Y1138745D01*
G02X1504352Y1137469I-234J-1276D01*
G02X1501756I-1298J0D01*
G02X1501868Y1137994I1297J-2D01*
G01X1501907Y1138083D01*
X1501063Y1139679D01*
X1500968Y1139697D01*
G02X1499906Y1140973I236J1276D01*
G37*
G36*
G01X1143020Y1540382D02*
G03X1143411Y1540758I-8J400D01*
G02X1145410Y1542642I1999J-119D01*
G02X1147412Y1540640I0J-2002D01*
G02X1145450Y1538638I-2002J0D01*
G03X1145059Y1538262I8J-400D01*
G02X1143060Y1536378I-1999J119D01*
G02X1141058Y1538380I0J2002D01*
G02X1143020Y1540382I2002J0D01*
G37*
G36*
G01X1162980Y1551449D02*
G03X1163635I328J229D01*
G02X1166917I1641J-1147D01*
G03X1167572I327J229D01*
G02X1169213Y1552304I1641J-1147D01*
G02Y1548298I0J-2003D01*
G02X1167572Y1549153I0J2002D01*
G03X1166917I-328J-229D01*
G02X1163635I-1641J1147D01*
G03X1162980I-327J-229D01*
G02X1159698I-1641J1147D01*
G03X1159043I-328J-229D01*
G02X1155761I-1641J1147D01*
G03X1155106I-328J-229D01*
G02X1151824I-1641J1147D01*
G03X1151169I-328J-229D01*
G02X1149528Y1548298I-1641J1147D01*
G02Y1552304I0J2003D01*
G02X1151169Y1551449I0J-2002D01*
G03X1151824I327J229D01*
G02X1155106I1641J-1147D01*
G03X1155761I328J229D01*
G02X1159043I1641J-1147D01*
G03X1159698I327J229D01*
G02X1162980I1641J-1147D01*
G37*
G36*
G01X1139652Y1550301D02*
Y1550302D01*
G02X1140157Y1551631I2002J0D01*
G02X1139688Y1552918I1533J1288D01*
G01Y1552920D01*
G02X1143692I2002J0D01*
G01Y1552919D01*
G02X1143187Y1551590I-2002J0D01*
G02X1143656Y1550303I-1533J-1288D01*
G01Y1550301D01*
G02X1139652I-2002J0D01*
G37*
G36*
G01X1101405Y1550386D02*
G03X1101083Y1550900I-382J119D01*
G02X1098098Y1554364I517J3464D01*
G02X1105102I3502J0D01*
G02X1104945Y1553324I-3502J-3D01*
G03X1105267Y1552810I382J-119D01*
G02X1108252Y1549346I-517J-3464D01*
G02X1101248I-3502J0D01*
G02X1101405Y1550386I3502J3D01*
G37*
G36*
G01X1143823Y1573272D02*
G03X1143551I-136J-147D01*
G02X1142188Y1572736I-1363J1466D01*
G01X1142187D01*
G02Y1576740I0J2002D01*
G01X1142188D01*
G02X1143551Y1576204I0J-2002D01*
G03X1143823I136J147D01*
G02X1145186Y1576740I1363J-1466D01*
G01X1145187D01*
G02Y1572736I0J-2002D01*
G01X1145186D01*
G02X1143823Y1573272I0J2002D01*
G37*
G36*
G01X1153823D02*
G03X1153551I-136J-147D01*
G02X1152188Y1572736I-1363J1466D01*
G01X1152187D01*
G02Y1576740I0J2002D01*
G01X1152188D01*
G02X1153551Y1576204I0J-2002D01*
G03X1153823I136J147D01*
G02X1155186Y1576740I1363J-1466D01*
G01X1155187D01*
G02Y1572736I0J-2002D01*
G01X1155186D01*
G02X1153823Y1573272I0J2002D01*
G37*
G36*
G01X1163231D02*
G03X1162959I-136J-147D01*
G02X1161596Y1572736I-1363J1466D01*
G01X1161595D01*
G02Y1576740I0J2002D01*
G01X1161596D01*
G02X1162959Y1576204I0J-2002D01*
G03X1163231I136J147D01*
G02X1164594Y1576740I1363J-1466D01*
G01X1164595D01*
G02Y1572736I0J-2002D01*
G01X1164594D01*
G02X1163231Y1573272I0J2002D01*
G37*
G36*
G01X1173231D02*
G03X1172959I-136J-147D01*
G02X1171596Y1572736I-1363J1466D01*
G01X1171595D01*
G02Y1576740I0J2002D01*
G01X1171596D01*
G02X1172959Y1576204I0J-2002D01*
G03X1173231I136J147D01*
G02X1174594Y1576740I1363J-1466D01*
G01X1174595D01*
G02Y1572736I0J-2002D01*
G01X1174594D01*
G02X1173231Y1573272I0J2002D01*
G37*
G36*
G01X1133823Y1581272D02*
G03X1133551I-136J-147D01*
G02X1132188Y1580736I-1363J1466D01*
G01X1132187D01*
G02Y1584740I0J2002D01*
G01X1132188D01*
G02X1133551Y1584204I0J-2002D01*
G03X1133823I136J147D01*
G02X1135186Y1584740I1363J-1466D01*
G01X1135187D01*
G02Y1580736I0J-2002D01*
G01X1135186D01*
G02X1133823Y1581272I0J2002D01*
G37*
G36*
G01X1143823D02*
G03X1143551I-136J-147D01*
G02X1142188Y1580736I-1363J1466D01*
G01X1142187D01*
G02Y1584740I0J2002D01*
G01X1142188D01*
G02X1143551Y1584204I0J-2002D01*
G03X1143823I136J147D01*
G02X1145186Y1584740I1363J-1466D01*
G01X1145187D01*
G02Y1580736I0J-2002D01*
G01X1145186D01*
G02X1143823Y1581272I0J2002D01*
G37*
G36*
G01X1153823D02*
G03X1153551I-136J-147D01*
G02X1152188Y1580736I-1363J1466D01*
G01X1152187D01*
G02Y1584740I0J2002D01*
G01X1152188D01*
G02X1153551Y1584204I0J-2002D01*
G03X1153823I136J147D01*
G02X1155186Y1584740I1363J-1466D01*
G01X1155187D01*
G02Y1580736I0J-2002D01*
G01X1155186D01*
G02X1153823Y1581272I0J2002D01*
G37*
G36*
G01X1163231D02*
G03X1162959I-136J-147D01*
G02X1161596Y1580736I-1363J1466D01*
G01X1161595D01*
G02Y1584740I0J2002D01*
G01X1161596D01*
G02X1162959Y1584204I0J-2002D01*
G03X1163231I136J147D01*
G02X1164594Y1584740I1363J-1466D01*
G01X1164595D01*
G02Y1580736I0J-2002D01*
G01X1164594D01*
G02X1163231Y1581272I0J2002D01*
G37*
G36*
G01X1173231D02*
G03X1172959I-136J-147D01*
G02X1171596Y1580736I-1363J1466D01*
G01X1171595D01*
G02Y1584740I0J2002D01*
G01X1171596D01*
G02X1172959Y1584204I0J-2002D01*
G03X1173231I136J147D01*
G02X1174594Y1584740I1363J-1466D01*
G01X1174595D01*
G02Y1580736I0J-2002D01*
G01X1174594D01*
G02X1173231Y1581272I0J2002D01*
G37*
G36*
G01X1133823Y1589272D02*
G03X1133551I-136J-147D01*
G02X1132188Y1588736I-1363J1466D01*
G01X1132187D01*
G02Y1592740I0J2002D01*
G01X1132188D01*
G02X1133551Y1592204I0J-2002D01*
G03X1133823I136J147D01*
G02X1135186Y1592740I1363J-1466D01*
G01X1135187D01*
G02Y1588736I0J-2002D01*
G01X1135186D01*
G02X1133823Y1589272I0J2002D01*
G37*
G36*
G01X1143823D02*
G03X1143551I-136J-147D01*
G02X1142188Y1588736I-1363J1466D01*
G01X1142187D01*
G02Y1592740I0J2002D01*
G01X1142188D01*
G02X1143551Y1592204I0J-2002D01*
G03X1143823I136J147D01*
G02X1145186Y1592740I1363J-1466D01*
G01X1145187D01*
G02Y1588736I0J-2002D01*
G01X1145186D01*
G02X1143823Y1589272I0J2002D01*
G37*
G36*
G01X1153823D02*
G03X1153551I-136J-147D01*
G02X1152188Y1588736I-1363J1466D01*
G01X1152187D01*
G02Y1592740I0J2002D01*
G01X1152188D01*
G02X1153551Y1592204I0J-2002D01*
G03X1153823I136J147D01*
G02X1155186Y1592740I1363J-1466D01*
G01X1155187D01*
G02Y1588736I0J-2002D01*
G01X1155186D01*
G02X1153823Y1589272I0J2002D01*
G37*
G36*
G01X1163231D02*
G03X1162959I-136J-147D01*
G02X1161596Y1588736I-1363J1466D01*
G01X1161595D01*
G02Y1592740I0J2002D01*
G01X1161596D01*
G02X1162959Y1592204I0J-2002D01*
G03X1163231I136J147D01*
G02X1164594Y1592740I1363J-1466D01*
G01X1164595D01*
G02Y1588736I0J-2002D01*
G01X1164594D01*
G02X1163231Y1589272I0J2002D01*
G37*
G36*
G01X1173231D02*
G03X1172959I-136J-147D01*
G02X1171596Y1588736I-1363J1466D01*
G01X1171595D01*
G02Y1592740I0J2002D01*
G01X1171596D01*
G02X1172959Y1592204I0J-2002D01*
G03X1173231I136J147D01*
G02X1174594Y1592740I1363J-1466D01*
G01X1174595D01*
G02Y1588736I0J-2002D01*
G01X1174594D01*
G02X1173231Y1589272I0J2002D01*
G37*
G36*
G01X1411037Y1711457D02*
G03X1411142Y1712134I-151J370D01*
G02X1421732I5295J6330D01*
G03X1421837Y1711457I256J-307D01*
G02X1430690Y1698267I-5399J-13190D01*
G02X1402184I-14253J0D01*
G02X1411037Y1711457I14252J0D01*
G37*
G36*
G01X435643Y1711458D02*
G03X435748Y1712135I-151J370D01*
G02X446338I5295J6330D01*
G03X446443Y1711458I256J-307D01*
G02X455296Y1698268I-5399J-13190D01*
G02X426790I-14253J0D01*
G02X435643Y1711458I14252J0D01*
G37*
G54D104*
X1137717Y1558020D03*
G54D101*
X1290005Y293768D03*
G54D97*
X1455787Y1421784D03*
X1710550Y691327D03*
X93547Y692260D03*
X479646Y1421784D03*
G54D102*
X1175215Y1532913D03*
X1131715D03*
G54D82*
X1307572Y-26511D03*
X1040152Y-16511D03*
X1015152D03*
X1307572Y13489D03*
X1282572Y23489D03*
X1307572D03*
X1282572Y13489D03*
X1040152Y23489D03*
Y13489D03*
X973180Y-6500D03*
X998180D03*
X1015152Y13489D03*
X1282572Y-16511D03*
X973180Y-26500D03*
X998180D03*
Y-16500D03*
X1015152Y23489D03*
X1307572Y-16511D03*
X973180Y-16500D03*
X1474931Y23489D03*
X1499931D03*
X705760Y-26500D03*
X730760D03*
X705760Y-6500D03*
Y-16500D03*
X730760D03*
Y-6500D03*
X1474931Y13489D03*
X998180Y3500D03*
X973180D03*
X1499931Y13489D03*
X998180Y13500D03*
Y23500D03*
X973180D03*
Y13500D03*
X1499931Y-16511D03*
X1474931D03*
X1324471Y23489D03*
X1349471D03*
X822720Y3500D03*
X847720D03*
X822720Y23500D03*
Y13500D03*
X847720D03*
Y23500D03*
X1324471Y-16511D03*
X1349471D03*
X1324471Y13489D03*
X1349471D03*
X1307572Y-36511D03*
X1282572D03*
Y-26511D03*
X1307572Y-6511D03*
Y3489D03*
X1282572D03*
Y-6511D03*
X1015152Y-36511D03*
Y-26511D03*
X1040152D03*
Y-36511D03*
X1015152Y3489D03*
Y-6511D03*
X1040152D03*
Y3489D03*
X1499931Y-26511D03*
Y-36511D03*
X1474931D03*
Y-26511D03*
X1499931Y-6511D03*
Y3489D03*
X1474931D03*
Y-6511D03*
X1324471Y-36511D03*
Y-26511D03*
X1349471D03*
Y-36511D03*
X1324471Y3489D03*
Y-6511D03*
X1349471D03*
Y3489D03*
G54D89*
X70472Y173228D03*
Y236220D03*
G54D93*
X1565236Y184783D03*
Y264035D03*
G54D94*
X929331Y160413D03*
X922441Y237697D03*
X1534712Y20354D03*
X1787330Y24291D03*
X505185Y41142D03*
X757803Y45079D03*
X312921Y24291D03*
G54D92*
X676508Y224606D03*
G54D91*
Y145866D03*
G54D88*
X1829725Y130315D03*
G54D84*
X791280Y1704890D03*
X1066280D03*
G54D99*
X1405118Y112008D03*
G54D81*
X1341752Y-31511D03*
Y-21511D03*
Y-11511D03*
Y-1511D03*
X1482650Y-31511D03*
Y-21511D03*
Y-11511D03*
Y-1511D03*
X90998Y1517237D03*
X78120Y1517136D03*
X99750Y1563678D03*
X75922Y1560674D03*
X404030Y1593690D03*
X957156Y228863D03*
X899830Y973184D03*
X1380522Y261936D03*
X1388754Y255503D03*
X1380638Y247394D03*
X1386630Y240351D03*
X397406Y1634842D03*
X1031950Y385471D03*
X736710Y605542D03*
X527310Y96447D03*
X414406Y1626692D03*
X460910Y1627472D03*
X64410Y1600802D03*
X1340420Y540122D03*
X704770Y204921D03*
X896060Y482922D03*
X716698Y210721D03*
X704770Y216732D03*
X895340Y499582D03*
X907470Y213680D03*
X902350Y220768D03*
X953970Y206575D03*
X716698Y198887D03*
X704770Y193110D03*
Y181299D03*
X947496Y227835D03*
X705800Y169488D03*
X947496Y213697D03*
X907470Y227854D03*
X941050Y530552D03*
X968286Y482241D03*
X716698Y175387D03*
X902350Y206594D03*
X944032Y435931D03*
X716698Y187387D03*
X944250Y196189D03*
X954420Y512952D03*
Y498852D03*
G54D100*
X1247638Y269488D03*
G54D96*
X1550708Y991220D03*
X525275Y1171319D03*
X1332204D03*
X1326240Y811122D03*
X1501417Y1171319D03*
X1507381Y811122D03*
X1282913Y991220D03*
X306771D03*
X574566D03*
X350098Y811122D03*
X531240D03*
X356062Y1171319D03*
G54D80*
X723041Y-11500D03*
Y-21500D03*
X840001Y8500D03*
Y18500D03*
X980899Y-21500D03*
Y-11500D03*
Y8500D03*
Y18500D03*
X1032433Y-31511D03*
Y-21511D03*
Y-11511D03*
Y-1511D03*
X1290291Y-31511D03*
Y-21511D03*
Y-11511D03*
Y-1511D03*
X62813Y414300D03*
X47619Y417205D03*
X1386273Y270370D03*
X615573Y178034D03*
X628195Y174214D03*
X1282645Y253971D03*
X941059Y426211D03*
X901829Y514430D03*
X889439Y491299D03*
X1407029Y154432D03*
X922879Y530276D03*
X946727Y506252D03*
G54D95*
X1819208Y1420330D03*
X38346D03*
G54D83*
X19685Y-29134D03*
X1837795D03*
X1808192Y1569255D03*
X41870Y1511291D03*
X1812980Y502472D03*
X49280Y337402D03*
X441043Y1672205D03*
X1416437Y1672204D03*
X2081889Y1803261D03*
Y-29134D03*
G54D90*
X1057658Y204724D03*
X805690D03*
G54D98*
X763602Y605413D03*
X1739744D03*
X1094075Y605378D03*
X117933D03*
G54D103*
X841240Y1420330D03*
X1016240D03*
G54D87*
X1680327Y277236D03*
X1153555Y277208D03*
X704185Y277236D03*
X177413Y277208D03*
G54D85*
X177311Y1657953D03*
G54D86*
X1680232D03*
%LPC*%
G75*
G36*
G01X917186Y1656376D02*
G03X918070Y1656010I884J885D01*
G01X1064430D01*
X1084474Y1635966D01*
G03X1085358Y1635600I884J885D01*
G01X1101560D01*
X1103140Y1634020D01*
Y1607480D01*
X1102240Y1606580D01*
X944270D01*
X917966Y1632884D01*
G03X917082Y1633250I-884J-885D01*
G01X816320D01*
X812960Y1636610D01*
Y1714140D01*
X817460Y1718640D01*
X900700D01*
X907010Y1712330D01*
Y1667070D01*
G03X907376Y1666186I1251J0D01*
G01X917186Y1656376D01*
G37*
%LPD*%
G75*
G54D15*
X16925Y203366D03*
X17061Y196368D03*
X24720Y216362D03*
Y232362D03*
Y224362D03*
Y240362D03*
X16420Y420662D03*
X26500Y672862D03*
Y675862D03*
X27300Y764200D03*
X27520Y1245162D03*
X33500Y200862D03*
X33670Y192862D03*
Y208362D03*
X30795Y213358D03*
X33670Y232362D03*
X42500Y224409D03*
X30795Y227366D03*
X33670Y240362D03*
X40000Y298707D03*
X36000Y295952D03*
X40000Y293392D03*
X33105Y304972D03*
X35740Y363337D03*
X39320Y392269D03*
X40940Y387302D03*
X43020Y382942D03*
X41933Y395652D03*
X45960Y428806D03*
X38220Y589862D03*
Y592862D03*
X33020Y595232D03*
X32720Y598402D03*
X34790Y666595D03*
X31390D03*
X38470Y688122D03*
Y683122D03*
Y680622D03*
Y685622D03*
Y693122D03*
Y690622D03*
Y695622D03*
X34899Y711400D03*
X45700Y724100D03*
X45800Y726874D03*
X43841Y1248688D03*
X44833Y1656759D03*
X48269Y1672771D03*
X62020Y295952D03*
X62731Y305426D03*
X59322Y360702D03*
X51114Y360862D03*
X62812Y412708D03*
X53406Y402862D03*
X62813Y415750D03*
X49360Y428806D03*
X61171D03*
X47619Y418655D03*
X47618Y415613D03*
X48400Y586000D03*
X57595Y603476D03*
X59500Y738700D03*
X56777Y1314165D03*
X56799Y1520094D03*
Y1536094D03*
Y1540094D03*
Y1560094D03*
X59833Y1604359D03*
X54333Y1613359D03*
X50333D03*
X54478Y1663669D03*
X54535Y1658447D03*
X57833Y1671809D03*
X53333Y1671862D03*
X65000Y1681900D03*
X58325Y1679275D03*
X78269Y26474D03*
X74869D03*
X65937Y28403D03*
Y48720D03*
X77165Y278798D03*
Y295798D03*
Y286262D03*
Y303262D03*
X63429Y360702D03*
X67681D03*
X77220Y379022D03*
Y381522D03*
X68020Y395222D03*
X75516Y420319D03*
Y424319D03*
X64571Y428806D03*
X63540Y438802D03*
X72610Y441262D03*
Y444762D03*
X72981Y466385D03*
X77000Y485362D03*
X74550Y487812D03*
X80300Y641862D03*
X80241Y659011D03*
X80123Y664031D03*
X80135Y667933D03*
X74559Y667814D03*
X78080Y701832D03*
X63930Y739300D03*
X73759Y754726D03*
X68315Y765664D03*
X73759Y759246D03*
X72485Y1304152D03*
X75485D03*
X78485D03*
X72485Y1307152D03*
X75485D03*
X69485Y1304152D03*
Y1307152D03*
X65600Y1318588D03*
X65240Y1326068D03*
X75485Y1316152D03*
X72485Y1313152D03*
Y1310152D03*
X75485Y1313152D03*
Y1310152D03*
X69485D03*
X69809Y1333918D03*
Y1331418D03*
Y1336418D03*
X72809Y1333918D03*
Y1331418D03*
Y1336418D03*
X75809Y1333918D03*
Y1331418D03*
Y1336418D03*
X72909Y1339938D03*
X79009Y1340238D03*
X75909Y1339938D03*
X73027Y1347925D03*
X73059Y1345138D03*
X72987Y1342535D03*
X75909Y1342438D03*
X79009Y1342738D03*
Y1345238D03*
X78977Y1348025D03*
X75859Y1348138D03*
Y1345138D03*
X76369Y1507456D03*
X76680Y1530482D03*
X72774Y1546519D03*
X75922Y1558974D03*
Y1562374D03*
X77618Y1572504D03*
X74218D03*
X77040Y1601102D03*
X65120Y1609909D03*
X65520Y1615972D03*
X74100Y1613300D03*
X77833Y1678902D03*
X73833Y1674252D03*
X69833Y1678582D03*
X85374Y19538D03*
X81974D03*
X92442Y26474D03*
X89042D03*
X87620Y285321D03*
X87845Y278798D03*
Y295798D03*
X87820Y302821D03*
X87520Y395865D03*
Y391391D03*
Y382219D03*
X85826Y428319D03*
X84410Y438519D03*
X83320Y445212D03*
X94439Y450081D03*
X81505Y447377D03*
X79400Y482862D03*
X91027Y643276D03*
X89859Y628246D03*
X86459D03*
X82961Y657111D03*
X95725Y654540D03*
X95860Y659622D03*
X83165Y652564D03*
X91078Y649584D03*
X83208Y646436D03*
X83250Y665428D03*
X84470Y668702D03*
X86433Y688160D03*
X81285Y689804D03*
X84035Y697604D03*
X93547Y692260D03*
X83004Y705141D03*
X97295Y699786D03*
X85095Y722164D03*
X95849Y716358D03*
X91610Y721414D03*
X82357Y737803D03*
X84623Y741249D03*
X81966Y759246D03*
X85877Y759275D03*
X93485Y1304152D03*
X87485D03*
X90485D03*
X93485Y1307152D03*
X84485Y1304152D03*
X81485D03*
X93485Y1318152D03*
Y1315652D03*
Y1310152D03*
Y1313152D03*
X94209Y1337738D03*
X81809Y1340238D03*
X84809D03*
X87809D03*
X90809D03*
X94209D03*
X84809Y1345238D03*
X81809Y1342738D03*
X84809D03*
X81809Y1348238D03*
Y1345238D03*
X84809Y1348238D03*
X87809D03*
Y1345238D03*
Y1342738D03*
X94209D03*
Y1348238D03*
Y1345238D03*
X90809Y1348238D03*
Y1345238D03*
Y1342738D03*
X88520Y1484482D03*
Y1491482D03*
Y1487982D03*
Y1494982D03*
X89264Y1507611D03*
X92664D03*
X79769Y1507456D03*
X87500Y1567069D03*
X91500D03*
X90713Y1581852D03*
Y1597867D03*
X81008Y1589872D03*
X90788Y1615821D03*
Y1601867D03*
X81900Y1613300D03*
X85800D03*
X90698Y1630362D03*
X90788Y1619821D03*
X90698Y1642362D03*
X90407Y1656672D03*
X88333Y1661334D03*
X81833Y1674526D03*
X86245Y1694362D03*
X96420Y1693803D03*
X86030Y1683092D03*
X99547Y19538D03*
X110320D03*
X96147D03*
X106615Y26474D03*
X103215D03*
X113490Y216596D03*
X113400Y232128D03*
X110937Y285495D03*
Y302854D03*
X107200Y393562D03*
X107301Y388071D03*
X107419Y487807D03*
X104875Y490980D03*
X102384Y505374D03*
X112480Y507792D03*
X110689Y498271D03*
X110464Y505374D03*
X101983Y518100D03*
X99880Y526300D03*
X110060Y515279D03*
X99773Y515606D03*
X105587Y520727D03*
X106110Y633732D03*
X107489Y630917D03*
X110374Y630879D03*
X102269Y634466D03*
X107045Y661917D03*
X99021Y663732D03*
X103397Y667272D03*
X102120Y688650D03*
X102060Y692100D03*
X102420Y697262D03*
X96626Y736187D03*
X110527Y758869D03*
X108465Y1304292D03*
Y1307292D03*
X105475Y1304222D03*
Y1307222D03*
X102485Y1304152D03*
X99485D03*
X96485D03*
X102485Y1307152D03*
X99485D03*
X96485D03*
X108465Y1318292D03*
Y1310292D03*
Y1313292D03*
Y1315792D03*
X105475Y1318222D03*
Y1310222D03*
Y1313222D03*
Y1315722D03*
X99485Y1318152D03*
X96485D03*
Y1315652D03*
Y1310152D03*
Y1313152D03*
X99485Y1310152D03*
Y1313152D03*
Y1315652D03*
X102485Y1318152D03*
Y1310152D03*
Y1313152D03*
Y1315652D03*
X96809Y1340238D03*
Y1345238D03*
Y1348238D03*
Y1342738D03*
X112270Y1518907D03*
X99274Y1529169D03*
X96570Y1546187D03*
X99750Y1565378D03*
Y1561978D03*
X103902Y1584337D03*
X102251Y1576504D03*
X105651D03*
X104318Y1589352D03*
X100620Y1596367D03*
X101500Y1604400D03*
X100020Y1615821D03*
X98738Y1605867D03*
X104400Y1632385D03*
X104430Y1628012D03*
X104318Y1637862D03*
X99600Y1668332D03*
X99645Y1663217D03*
X99980Y1687921D03*
Y1698921D03*
X113720Y19538D03*
X127894D03*
X124494D03*
X120789Y26474D03*
X117389D03*
X115850Y186362D03*
X122000Y207362D03*
X116920Y207462D03*
X118920Y278875D03*
X119220Y306236D03*
X119920Y379362D03*
X119457Y392071D03*
Y388071D03*
X125070Y486736D03*
X125013Y491829D03*
X124124Y495883D03*
X116171Y485041D03*
X112483Y510637D03*
X116411Y497707D03*
X118652Y528860D03*
X129762Y531942D03*
X115793Y528188D03*
X112393D03*
X111920Y632922D03*
X114540Y633032D03*
X117750Y633232D03*
X120440Y633347D03*
X121400Y638062D03*
X125890Y644163D03*
X122329Y654660D03*
X122280Y651934D03*
X124431Y649570D03*
X122575Y671930D03*
X118019Y661371D03*
X124737Y735726D03*
X118737D03*
X121737D03*
Y738726D03*
X118737D03*
X124737D03*
X123220Y1324662D03*
X120220D03*
X112749Y1532594D03*
Y1528594D03*
Y1552594D03*
Y1556594D03*
X117707Y1553759D03*
X125033Y1589352D03*
X116798D03*
X123230Y1597350D03*
X119500Y1622380D03*
X124795Y1681846D03*
X128195Y1674362D03*
X114645Y1698862D03*
X117220Y1683437D03*
X127195Y1696362D03*
Y1700362D03*
Y1704362D03*
X125082Y1727092D03*
X123394Y1723472D03*
X117426Y1726622D03*
X125720Y1719262D03*
X141520Y181462D03*
X139720Y179162D03*
X143470Y184012D03*
X133590Y212382D03*
X129394Y278875D03*
X129375Y274800D03*
X129394Y306236D03*
X135220Y397071D03*
X132490Y420062D03*
X138042Y480238D03*
X132833D03*
X136982Y497090D03*
X131737Y496295D03*
X135006Y487753D03*
X131295Y487822D03*
X141325Y503806D03*
X141462Y507600D03*
X141329Y510487D03*
X141220Y498810D03*
X138878Y512550D03*
X138408Y507366D03*
X139153Y516453D03*
X133160Y532002D03*
X132600Y537072D03*
Y540472D03*
X133467Y634531D03*
X131740Y640103D03*
X131600Y646861D03*
X131330Y665740D03*
X142960Y690807D03*
X140460D03*
X142754Y698811D03*
X140254D03*
X142778Y706835D03*
X140278D03*
X140326Y721660D03*
X142826D03*
X140142Y1392545D03*
Y1396275D03*
X129627Y1556360D03*
X129586Y1553759D03*
X129813Y1604367D03*
X130533Y1622321D03*
X129533Y1637862D03*
X137420Y1708362D03*
X144520Y1717562D03*
X141642Y1717592D03*
X134557Y1722778D03*
X137852Y1726572D03*
X160360Y19538D03*
X156655Y26474D03*
X153255D03*
X147924Y28258D03*
X148784Y48720D03*
X145720Y186462D03*
Y202862D03*
Y206362D03*
X156670Y344542D03*
X159170D03*
X154220Y375682D03*
X158110Y376172D03*
X160090Y391170D03*
Y397470D03*
X152826Y439397D03*
Y434362D03*
X156306Y449045D03*
X153360Y449112D03*
X149557Y494353D03*
X150113Y488487D03*
X161267Y503143D03*
X149472Y506810D03*
X160000Y510052D03*
X152470Y495383D03*
X151378Y526924D03*
X149512Y514810D03*
X150800Y512021D03*
X153737Y514893D03*
X149504Y519881D03*
X154647Y521783D03*
X150877Y757969D03*
X151277Y1339183D03*
X153877D03*
X156477D03*
X156417Y1336343D03*
X151217Y1336393D03*
X153817D03*
X156417Y1333843D03*
X151217Y1333893D03*
X153817D03*
X151277Y1346883D03*
X153877D03*
X151277Y1349383D03*
X153877D03*
X156477Y1346883D03*
Y1349383D03*
Y1344383D03*
X151277D03*
X153877D03*
X156477Y1341883D03*
X151277D03*
X153877D03*
X147307Y1404745D03*
X149568Y1395145D03*
Y1397695D03*
X152684Y1403451D03*
X157490Y1421454D03*
X154990D03*
X159858Y1409361D03*
X155858Y1406669D03*
Y1409390D03*
X157530Y1432124D03*
X155030D03*
X157530Y1424124D03*
X155030D03*
X157530Y1429124D03*
X155030Y1426624D03*
Y1429124D03*
X157530Y1426624D03*
Y1435124D03*
X155030D03*
X157530Y1437754D03*
X155030D03*
X146390Y1504240D03*
X145538Y1517374D03*
X148938D03*
X153600Y1505600D03*
X147067Y1545985D03*
X157441Y1581932D03*
X146312Y1569525D03*
X149712D03*
X152026Y1614138D03*
X158335Y1614452D03*
X155180Y1619872D03*
X156070Y1695702D03*
X145745Y1712362D03*
X161310Y1708022D03*
X148145Y1701862D03*
X155145Y1713517D03*
X163760Y19538D03*
X174533D03*
X170828Y26474D03*
X167428D03*
X164830Y344542D03*
X161670D03*
X173275Y393497D03*
X164000Y415362D03*
X163926Y425383D03*
X164000Y420362D03*
X172507Y417205D03*
X163926Y430883D03*
Y443319D03*
Y439397D03*
Y435383D03*
X178546Y453806D03*
X172632Y454095D03*
X165176Y500782D03*
X176393Y575189D03*
X173793D03*
X176393Y572689D03*
X173793D03*
X171293D03*
Y575189D03*
X173793Y577790D03*
X171293D03*
X176393D03*
X176651Y596883D03*
Y594163D03*
X173878Y597027D03*
Y594307D03*
X176651Y599603D03*
X173878Y599747D03*
X161126Y721660D03*
X161078Y706835D03*
X163626Y721660D03*
X163578Y706835D03*
X170877Y1333783D03*
Y1336383D03*
X176077Y1333783D03*
X173477D03*
X176077Y1336383D03*
X173477D03*
X170907Y1339233D03*
X176107D03*
X173507D03*
X170877Y1341883D03*
X176077D03*
X173477D03*
Y1349383D03*
Y1346883D03*
Y1344383D03*
X176077D03*
Y1346883D03*
Y1349383D03*
X170877D03*
Y1346883D03*
Y1344383D03*
X176358Y1403669D03*
X176258Y1400669D03*
X173892Y1402749D03*
Y1405649D03*
X170922Y1399255D03*
X166262D03*
X173252Y1400005D03*
X168592D03*
X160490Y1421454D03*
X164000Y1408862D03*
X162257Y1406594D03*
X160530Y1432124D03*
Y1424124D03*
Y1429124D03*
Y1426624D03*
Y1435124D03*
Y1437754D03*
X165500Y1440362D03*
X173727Y1452134D03*
Y1448734D03*
X170570Y1509250D03*
X164710Y1518014D03*
X168110D03*
X173331Y1579399D03*
X167266Y1569968D03*
X170666D03*
X172099Y1588141D03*
X164920Y1712017D03*
X163060Y1717017D03*
X178226Y1726517D03*
X172962Y1721234D03*
X169777Y1726517D03*
X178142Y1720652D03*
X177933Y19538D03*
X186120Y24162D03*
X188620D03*
X190880Y383012D03*
Y387162D03*
Y391082D03*
X178375Y396571D03*
X181845Y401071D03*
X187371Y425383D03*
X187532Y421387D03*
X187371Y430883D03*
Y443383D03*
X180740Y437562D03*
X184550Y435712D03*
X187371Y440742D03*
X194440Y433895D03*
Y439565D03*
X187371Y447172D03*
X177871D03*
X181994Y453932D03*
X180640Y447172D03*
X185211Y453942D03*
X185191Y502439D03*
X186793Y575189D03*
X184193D03*
X186793Y572689D03*
X184193D03*
X181593Y575189D03*
X178993D03*
X181593Y572689D03*
X178993D03*
X189293Y575189D03*
X186793Y577790D03*
X184193D03*
X189293D03*
X181593D03*
X178993D03*
X181651Y596883D03*
X179151D03*
X186796Y594195D03*
Y596915D03*
X184151Y596883D03*
X179151Y594163D03*
X181651D03*
X184151D03*
X181651Y599603D03*
X179151D03*
X186796Y599635D03*
X184151Y599603D03*
X186720Y737862D03*
X180720D03*
X183720D03*
Y734862D03*
X180720D03*
X186720D03*
X185835Y757057D03*
X188978Y756855D03*
X191602Y756839D03*
X189377Y1333783D03*
X191977D03*
X189377Y1336383D03*
X191977D03*
X191947Y1339263D03*
X189347D03*
X189377Y1349383D03*
X191977D03*
X189377Y1346883D03*
X191977D03*
Y1344383D03*
X189377D03*
X191977Y1341883D03*
X189377D03*
X187711Y1395170D03*
Y1397670D03*
X190827Y1403451D03*
X180977Y1396173D03*
X178458Y1399269D03*
Y1402169D03*
Y1405069D03*
X188211Y1406691D03*
X186165Y1422589D03*
X183135Y1419784D03*
X180510Y1420258D03*
X177510D03*
X186135Y1419784D03*
X183165Y1422589D03*
X177510Y1423278D03*
X180510D03*
X183075Y1430424D03*
Y1425424D03*
Y1427924D03*
X186075Y1430424D03*
Y1425424D03*
Y1427924D03*
X183075Y1432924D03*
X186075D03*
X192600Y1557360D03*
X185895Y1557875D03*
X189600Y1566300D03*
X187400Y1568132D03*
X187542Y1729092D03*
X193293Y1722197D03*
X188794Y1725092D03*
X207894Y19538D03*
X204494D03*
X200789Y26474D03*
X197389D03*
X195050Y412055D03*
X199149Y425755D03*
Y420255D03*
Y414755D03*
X204699Y423242D03*
Y428742D03*
X195050Y417465D03*
X199149Y436755D03*
Y442255D03*
Y431255D03*
Y453255D03*
Y447755D03*
X197650Y455712D03*
X199149Y468255D03*
X208200Y493510D03*
X202338Y568746D03*
X201392Y574271D03*
X198336D03*
X204610Y571097D03*
X199164Y582481D03*
X200654Y578271D03*
X201622Y581009D03*
X208056Y591665D03*
X208806Y589335D03*
X208056Y587005D03*
X208806Y584675D03*
X202262Y592305D03*
X205162D03*
X202338Y602746D03*
X201392Y608271D03*
X198336D03*
X203892Y594471D03*
X202492Y596571D03*
X208292D03*
X206892Y594371D03*
X205392Y596571D03*
X204610Y605097D03*
X199164Y616481D03*
X200654Y612271D03*
X201622Y615009D03*
X208806Y618675D03*
X208056Y621005D03*
X208806Y623335D03*
X202338Y636746D03*
X208056Y625665D03*
X203892Y628471D03*
X202492Y630571D03*
X202262Y626305D03*
X208292Y630571D03*
X206892Y628371D03*
X205162Y626305D03*
X205392Y630571D03*
X204610Y639097D03*
X201392Y642271D03*
X199164Y650481D03*
X200654Y646271D03*
X201622Y649009D03*
X198336Y642271D03*
X208056Y655005D03*
X208806Y657335D03*
Y652675D03*
X207620Y671262D03*
X198420Y672662D03*
X198495Y669487D03*
X208056Y659665D03*
X205392Y664571D03*
X205162Y660305D03*
X206892Y662371D03*
X202262Y660305D03*
X202492Y664571D03*
X203892Y662471D03*
X208292Y664571D03*
X196049Y678195D03*
X194196Y687061D03*
X200018Y677492D03*
X193332Y678195D03*
X207129Y690027D03*
X203199Y690006D03*
X197086Y686326D03*
X203179Y693626D03*
X207140Y693636D03*
X195735Y696469D03*
X198235Y698969D03*
Y696469D03*
X200735Y698969D03*
Y696469D03*
X207140Y738462D03*
X205220Y736562D03*
X201220Y736662D03*
X203660Y731802D03*
X195602Y756839D03*
X203602Y756855D03*
X208977Y1336383D03*
Y1333783D03*
X194577D03*
Y1336383D03*
X209007Y1339263D03*
X194547D03*
X208977Y1341883D03*
X194577Y1349383D03*
Y1346883D03*
Y1344383D03*
X208977D03*
Y1346883D03*
Y1349383D03*
X194577Y1341883D03*
X206735Y1400005D03*
X209065Y1399255D03*
X204405D03*
X198001Y1409361D03*
X193941Y1407029D03*
X200797Y1409605D03*
X200492Y1406686D03*
X193941Y1409750D03*
X195966Y1542863D03*
X203120Y1624782D03*
X208115Y1624217D03*
X195590Y1714517D03*
X196010Y1709017D03*
X208295Y1703362D03*
X199050Y1726431D03*
X204600Y1733022D03*
X222067Y19538D03*
X218667D03*
X214962Y26474D03*
X211562D03*
X225407Y321831D03*
X209530Y426192D03*
X217770Y428262D03*
X224210Y431501D03*
X224305Y422977D03*
X219995Y426267D03*
X224210Y436619D03*
X218140Y440735D03*
X218010Y432735D03*
X223664Y443125D03*
X220000Y448735D03*
X212891Y566632D03*
X210391Y567981D03*
X212891Y601981D03*
X210391D03*
Y635981D03*
X212891D03*
X210320Y671262D03*
X224900Y713293D03*
X209720Y731862D03*
X220033Y756844D03*
X211602Y756855D03*
X216842Y756865D03*
X214177Y1336383D03*
X211577D03*
X214177Y1333783D03*
X211577D03*
X214207Y1339263D03*
X211607D03*
X214177Y1341883D03*
X211577D03*
X214177Y1349383D03*
Y1346883D03*
Y1344383D03*
X211577D03*
Y1346883D03*
Y1349383D03*
X211395Y1400005D03*
X214201Y1404169D03*
X212035Y1402899D03*
X214101Y1401169D03*
X216554Y1399264D03*
Y1402164D03*
Y1405064D03*
X212035Y1405799D03*
X219587Y1435402D03*
X217469Y1454725D03*
X219587Y1443402D03*
Y1439402D03*
X220869Y1454725D03*
X209820Y1631142D03*
X210593Y1714017D03*
X212120Y1703062D03*
X214120Y1713462D03*
X233339Y17662D03*
X235701Y21582D03*
X241310Y20322D03*
X229135Y26474D03*
X225735D03*
X238063Y26232D03*
X235701Y39570D03*
X229131Y50646D03*
X225731D03*
X239820Y54362D03*
X239720Y71862D03*
X239010Y78542D03*
X238297Y129703D03*
X234902Y174047D03*
X226800Y359464D03*
X230359Y461683D03*
X227430Y719772D03*
X238940Y716652D03*
X230864Y1254295D03*
X246510Y20362D03*
X242220Y39362D03*
X246220D03*
X250220D03*
X254050Y39422D03*
X246360Y26852D03*
X248820Y48962D03*
X252320D03*
X255820D03*
X257520Y51562D03*
X254020D03*
X250520D03*
X249885Y69623D03*
X245220Y67862D03*
X248097Y92143D03*
X247897Y100543D03*
X244822Y115543D03*
Y111543D03*
X253910Y115722D03*
X253878Y111771D03*
X243892Y140912D03*
X259933Y141122D03*
X257256Y156727D03*
X245490Y159702D03*
X252000Y395400D03*
X255810Y405582D03*
X252500Y415862D03*
X258066Y426735D03*
X256695Y461117D03*
X257750Y450842D03*
X254713Y518465D03*
X245700Y513262D03*
X250100Y521783D03*
X256885Y574805D03*
X254385D03*
X256855Y571995D03*
X251885Y574805D03*
X249800Y563262D03*
X254355Y589235D03*
X256855D03*
X251855D03*
X256855Y605995D03*
X251885Y608805D03*
X257643Y594220D03*
X255043D03*
Y596820D03*
X257643D03*
X256885Y608805D03*
X254385D03*
X256855Y603495D03*
X251855Y623265D03*
X254355D03*
X256855D03*
Y639995D03*
Y637495D03*
X257643Y628220D03*
X255043D03*
Y630820D03*
X257643D03*
X256885Y642805D03*
X254385D03*
X251855Y657265D03*
X251885Y642805D03*
X254355Y657265D03*
X256855D03*
X257643Y662220D03*
X255043D03*
Y664820D03*
X257643D03*
X253819Y675567D03*
X253849Y678077D03*
X256419Y675567D03*
X256449Y678077D03*
X251219Y675567D03*
X251249Y678077D03*
X248649D03*
X248989Y698827D03*
X249019Y693767D03*
X251589Y698827D03*
X251649Y696277D03*
X254189Y698827D03*
X251619Y693767D03*
X256849Y696277D03*
X256789Y698827D03*
X256819Y693767D03*
X254249Y696277D03*
X254219Y693767D03*
X248300Y703862D03*
X242460Y716652D03*
X253057Y755345D03*
X245487Y755435D03*
X259510Y757822D03*
X251187Y1255025D03*
X263240Y38122D03*
X266990Y41832D03*
X275120Y28562D03*
X275900Y48872D03*
X259320Y48962D03*
X261020Y51562D03*
X263520D03*
X261820Y48962D03*
X264740Y49182D03*
X266497Y69536D03*
Y72036D03*
X264720Y56362D03*
Y60362D03*
Y64362D03*
X266597Y77526D03*
Y80026D03*
X263320Y87662D03*
X261420Y100662D03*
X264920D03*
X268420D03*
X262920Y97962D03*
X266420D03*
X269920D03*
X273620Y96662D03*
X263550Y120922D03*
X269191Y121092D03*
X275797Y120245D03*
X265910Y125492D03*
X266975Y140107D03*
X260600Y151062D03*
X272800Y140162D03*
X264578Y151203D03*
X260100Y159562D03*
X265500Y227862D03*
X263000D03*
X260500Y227362D03*
Y224862D03*
X270240Y245332D03*
X271821Y251962D03*
X267759D03*
X259224Y419532D03*
X263430Y422235D03*
X259869Y431039D03*
X262963Y443735D03*
X272500Y447735D03*
X263040Y448752D03*
X272500Y452862D03*
X264055Y574505D03*
X264025Y571995D03*
X261555Y574505D03*
X261525Y571995D03*
X264055Y566935D03*
X263995Y569485D03*
X261495D03*
X261555Y566935D03*
X266555Y574505D03*
X266525Y571995D03*
X266495Y569485D03*
X266555Y566935D03*
X269055Y574505D03*
X269025Y571995D03*
X268995Y569485D03*
X269055Y566935D03*
X261465Y592115D03*
X261525Y589565D03*
X264025D03*
X263965Y592115D03*
X266525Y589565D03*
X266465Y592115D03*
X269025Y589565D03*
X268965Y592115D03*
X264025Y605995D03*
X261525D03*
X264055Y608505D03*
X261555D03*
X261435Y597175D03*
X261495Y594625D03*
X263995D03*
X263935Y597175D03*
X266525Y605995D03*
X266555Y608505D03*
X266435Y597175D03*
X266495Y594625D03*
X261525Y603495D03*
X264025D03*
X266525D03*
X269025Y605995D03*
X269055Y608505D03*
X268935Y597175D03*
X268995Y594625D03*
X269025Y603495D03*
X261495Y621055D03*
X263995D03*
X261525Y623565D03*
X264025D03*
X263995Y611055D03*
X261495D03*
X266495Y621055D03*
X266525Y623565D03*
X266495Y611055D03*
X268995Y621055D03*
X269025Y623565D03*
X268995Y611055D03*
X261525Y639995D03*
X264025D03*
X261525Y637495D03*
X266525Y639995D03*
X269025D03*
X264025Y637495D03*
X266525D03*
X269025D03*
X263965Y626115D03*
X261465D03*
X266465D03*
X268965D03*
X261495Y655055D03*
X263995D03*
X261525Y657565D03*
X264025D03*
X263995Y645055D03*
X264055Y642505D03*
X261495Y645055D03*
X261555Y642505D03*
X266495Y655055D03*
X266525Y657565D03*
X266495Y645055D03*
X266555Y642505D03*
X268995Y655055D03*
X269025Y657565D03*
X268995Y645055D03*
X269055Y642505D03*
X261465Y660115D03*
X263965D03*
X266465D03*
X268965D03*
X259049Y678077D03*
X259019Y675567D03*
X259419Y693767D03*
X259389Y698827D03*
X259449Y696277D03*
X269600Y715792D03*
X274247Y727165D03*
X268331Y738029D03*
X273046Y735662D03*
X270100Y727262D03*
X264000Y726262D03*
X266700Y730962D03*
X271570Y746422D03*
X265997Y747535D03*
X272208Y768516D03*
X271057Y765525D03*
Y762425D03*
X287000Y20862D03*
X284233Y26474D03*
X280833D03*
X290799Y28362D03*
X284230Y50646D03*
X280830D03*
X289400Y54222D03*
X285357Y105003D03*
X288557D03*
X280857Y107303D03*
X285857Y115603D03*
X282857D03*
X280857Y109903D03*
X275797Y129592D03*
X287000Y139862D03*
X283053Y139728D03*
X276825Y140462D03*
X290685Y165447D03*
X286481Y251962D03*
X281077D03*
X276491D03*
X289274Y290662D03*
X284515D03*
X276500Y444862D03*
X274850Y442562D03*
X279500Y455362D03*
X277578Y509039D03*
X284482Y566022D03*
X286582Y637809D03*
Y634283D03*
X284287Y716015D03*
X277046Y725709D03*
Y735442D03*
X284358Y732562D03*
X283350Y728483D03*
X289137Y735275D03*
X279507Y727025D03*
X285046Y737964D03*
X281046Y737938D03*
X275210Y738102D03*
X287607Y754962D03*
X277046Y746702D03*
X281046D03*
X285046D03*
X299500Y22862D03*
X295520Y12762D03*
X302610Y26362D03*
X292060Y24472D03*
X295520Y26362D03*
X300248Y28362D03*
X304927Y24654D03*
X304972Y28362D03*
X302720Y38182D03*
X292590Y53982D03*
X293161Y50522D03*
X306570Y50222D03*
X290720Y40017D03*
X294720D03*
X295524Y52092D03*
X301310Y52482D03*
X298550Y51602D03*
X303715Y50857D03*
X292942Y71499D03*
X305747Y64013D03*
Y61113D03*
X305247Y71567D03*
X301600Y82457D03*
X302310Y75673D03*
X295357Y88903D03*
X307820Y95724D03*
X301183Y107103D03*
Y110003D03*
Y112803D03*
X296478Y149203D03*
X296800Y139762D03*
X306000Y165662D03*
X295685Y165447D03*
X296478Y158703D03*
X306730Y173842D03*
X304651Y251962D03*
X291759D03*
X306736Y290662D03*
X302765D03*
X298184D03*
X293763D03*
X298587Y508074D03*
X300520Y552262D03*
X307987Y577658D03*
X293805Y569397D03*
Y565997D03*
X298000Y587890D03*
X308417Y585158D03*
X308447Y592255D03*
X306144Y602225D03*
X305612Y622530D03*
Y625030D03*
Y627530D03*
X296405Y630732D03*
Y634132D03*
X295962Y679374D03*
X294679Y688446D03*
Y685046D03*
X291600Y705162D03*
X298273Y715400D03*
X297087Y721249D03*
X304602Y727968D03*
X293027Y755985D03*
X303647Y1307981D03*
X303723Y1353316D03*
Y1355853D03*
X304051Y1365453D03*
X306667Y1361597D03*
X302805Y1379941D03*
Y1376541D03*
X296170Y1622852D03*
X310400Y50362D03*
X314657Y71803D03*
Y68903D03*
X323040Y73122D03*
X323117Y81168D03*
Y76938D03*
X322875Y84318D03*
X316364Y89212D03*
X310459Y75892D03*
X320430Y78002D03*
X313357Y89503D03*
X313457Y96803D03*
X311057Y107103D03*
Y110003D03*
Y112803D03*
X308175Y144202D03*
X308500Y165662D03*
X311200Y165562D03*
X309230Y173842D03*
X309756Y177449D03*
Y181449D03*
X310970Y195362D03*
X308790Y197622D03*
X320270Y200462D03*
X319370Y214492D03*
X316370D03*
X319370Y217492D03*
X316370D03*
X323314Y210645D03*
X306910Y228162D03*
X309910D03*
X306910Y225162D03*
X309910D03*
X322658Y229254D03*
X319718Y223750D03*
X317981Y237724D03*
X320940Y238372D03*
X317129Y251962D03*
X316463Y290662D03*
X316444Y559125D03*
X317860Y572322D03*
X319520Y577658D03*
X312007Y588675D03*
X319520Y582658D03*
X316127Y592785D03*
X318560Y587632D03*
X321276Y599298D03*
X317386Y623207D03*
X308605Y629525D03*
Y627025D03*
X319557Y736225D03*
X317967Y746985D03*
Y771875D03*
X320578Y1290197D03*
X323028Y1297967D03*
X320428D03*
Y1295467D03*
X323028D03*
Y1292967D03*
X320428D03*
X320245Y1357401D03*
X313841Y1365553D03*
X309841Y1364815D03*
X318051Y1367043D03*
X316579Y1364585D03*
X309841Y1367871D03*
X322575Y1358151D03*
X332500Y150738D03*
X326216Y138787D03*
X326900Y162287D03*
X323420Y207549D03*
X326168Y207580D03*
X334485Y216809D03*
X337000Y216862D03*
X335575Y214170D03*
X328588Y209677D03*
X334500Y219362D03*
X337000D03*
X328939Y229139D03*
X335385Y235309D03*
X335412Y222176D03*
X329648Y252202D03*
X341295Y290239D03*
X329002Y290662D03*
X330674Y365702D03*
X328167Y379073D03*
X336270Y402992D03*
X329050Y607402D03*
X331339Y709313D03*
X328120Y710862D03*
X335677Y715215D03*
X327107Y732665D03*
X335467Y725335D03*
X338097Y736235D03*
X335126Y728323D03*
X327096Y736005D03*
X336446Y746486D03*
X338667Y772452D03*
X341527Y778362D03*
X339148Y1269717D03*
X339088Y1272287D03*
X339028Y1274887D03*
X325688Y1290167D03*
X325718Y1287587D03*
X328078Y1288747D03*
X323178Y1290197D03*
X323208Y1287617D03*
X328168Y1280967D03*
X325748Y1284987D03*
X328108Y1286147D03*
X328138Y1283567D03*
X328018Y1291317D03*
X339035Y1280218D03*
X339040Y1277594D03*
X328065Y1299248D03*
X325538Y1297937D03*
Y1292937D03*
Y1295437D03*
X328058Y1293917D03*
X328070Y1296624D03*
X335679Y1330518D03*
X334973Y1333353D03*
X338795Y1338799D03*
X336179Y1342753D03*
X324905Y1357401D03*
X327235Y1358151D03*
X332475Y1357945D03*
X327875Y1363945D03*
Y1361045D03*
X330041Y1362315D03*
X329941Y1359315D03*
X332475Y1363345D03*
Y1360445D03*
X340440Y120552D03*
X343450Y131167D03*
X342700Y139662D03*
X355189Y144267D03*
X351100Y150412D03*
X348100Y185162D03*
X345600Y188162D03*
X356295Y219362D03*
X353145D03*
X342000Y252612D03*
X354672Y252693D03*
X354145Y290591D03*
X345411Y364702D03*
Y376923D03*
X343354Y391643D03*
X347340Y407462D03*
X348880Y703442D03*
X354100Y720743D03*
X352879Y728657D03*
X348037Y728735D03*
X348730Y735098D03*
Y731698D03*
X344264Y1272455D03*
X341754Y1272485D03*
X344252Y1269948D03*
X341742Y1269978D03*
X344258Y1267117D03*
X341748Y1267147D03*
X341754Y1274985D03*
X344264Y1274955D03*
X355036Y1272433D03*
Y1269933D03*
X355378Y1262027D03*
X355318Y1264597D03*
X355258Y1267197D03*
X355036Y1274933D03*
X341605Y1280248D03*
X344115Y1280218D03*
X344264Y1277455D03*
X341754Y1277485D03*
X355048Y1277440D03*
X355025Y1280248D03*
X352373Y1334603D03*
X354703Y1335353D03*
X345969Y1342755D03*
X341969Y1342017D03*
X350179Y1344245D03*
X348707Y1341787D03*
X341969Y1345073D03*
X354850Y1371908D03*
X351850D03*
X349260Y1373418D03*
X351850Y1375408D03*
X354850D03*
X351850Y1378408D03*
X354850D03*
X351850Y1381408D03*
X354850D03*
X349260Y1376918D03*
Y1379918D03*
X349636Y1399601D03*
X352713Y1399336D03*
X355513Y1402306D03*
X352513D03*
X349513D03*
X355325Y1405386D03*
X349463Y1405286D03*
X352463D03*
X355325Y1408386D03*
X346426Y1414401D03*
X352401Y1414432D03*
X355325Y1414386D03*
Y1417386D03*
X352401Y1411432D03*
X355325Y1411386D03*
X352401Y1408432D03*
X349123Y1411376D03*
X349323Y1408406D03*
X349073Y1414356D03*
X346256Y1417301D03*
X352231Y1417332D03*
X348903Y1417256D03*
X363625Y127662D03*
X361800Y122522D03*
X366060Y133912D03*
X363525Y158702D03*
X361190Y210762D03*
X357303Y213159D03*
X371551Y224862D03*
X367306Y252811D03*
X366498Y290264D03*
X357660Y318850D03*
X364014Y366391D03*
Y378649D03*
X364179Y392037D03*
X370200Y409582D03*
X373720Y431362D03*
X365720Y440562D03*
X365771Y449480D03*
X359669Y686744D03*
X359639Y690114D03*
X360470Y705965D03*
X363101Y697348D03*
Y693948D03*
X360990Y726862D03*
X358902Y736225D03*
X355946Y728800D03*
X359790Y729835D03*
X358902Y739755D03*
Y743035D03*
Y754945D03*
Y746405D03*
Y773352D03*
X371578Y1248967D03*
X371458Y1254137D03*
X371330Y1256687D03*
X371518Y1251537D03*
X371278Y1259257D03*
X360198Y1269777D03*
X357546Y1272403D03*
Y1269903D03*
X360138Y1272347D03*
X357828Y1264567D03*
X357888Y1261997D03*
X360378Y1264627D03*
X360438Y1262057D03*
X357768Y1267167D03*
X360318Y1267227D03*
X357546Y1274903D03*
X360128Y1274957D03*
X371218Y1261857D03*
X371225Y1267188D03*
X371230Y1264564D03*
X357558Y1277410D03*
X357535Y1280218D03*
X360120Y1277654D03*
X367694Y1317092D03*
X367807Y1319592D03*
X368391Y1328161D03*
X370923Y1325373D03*
X357033Y1334603D03*
X359363Y1335353D03*
X362147Y1336553D03*
X360003Y1338247D03*
X364269Y1338017D03*
X364073Y1334903D03*
X360003Y1341147D03*
X362147Y1339653D03*
X364347Y1340853D03*
X364647Y1371990D03*
X361647D03*
X358647D03*
X367647D03*
X370552Y1372073D03*
X364647Y1375490D03*
X361647D03*
X358647D03*
Y1378490D03*
X370552Y1375573D03*
X367647Y1375490D03*
X355713Y1399336D03*
X361703Y1399386D03*
X364703D03*
X367703D03*
X370703D03*
X358703Y1402386D03*
X361703D03*
X364703D03*
X367703D03*
X370703D03*
X358713Y1399336D03*
X358573Y1405336D03*
X361573D03*
X364573D03*
X367573D03*
X370573D03*
X358703Y1414606D03*
X361703D03*
X364703D03*
X361703Y1417386D03*
X358703D03*
X364703D03*
X367703D03*
Y1414606D03*
X358217Y1411405D03*
X370517Y1414615D03*
X370717Y1417405D03*
X357917Y1408205D03*
X367948Y1531529D03*
X371850Y1534062D03*
X368600Y1543200D03*
X367140Y1645390D03*
X366700Y1649000D03*
X370500Y1654362D03*
X370635Y1675820D03*
X369300Y1680400D03*
Y1682900D03*
X380930Y122022D03*
X383160Y124322D03*
X383060Y128491D03*
X372530Y122972D03*
X373200Y126052D03*
X379295Y131002D03*
X379860Y252162D03*
X379112Y290386D03*
X385720Y320902D03*
X376500Y366391D03*
Y378649D03*
X377136Y390307D03*
X390220Y392062D03*
X383060Y403542D03*
X379220Y436362D03*
X376220D03*
X382220D03*
X389920Y461362D03*
X379220Y470962D03*
X387500Y495362D03*
X389020Y522862D03*
X371970Y683892D03*
X381010Y734732D03*
X376638Y1248997D03*
X374088Y1248937D03*
X374028Y1251507D03*
X373823Y1256896D03*
X376333Y1256866D03*
X376518Y1254167D03*
X376578Y1251567D03*
X373968Y1254107D03*
X373835Y1259403D03*
X376345Y1259373D03*
X387478Y1248967D03*
X387358Y1254137D03*
X387117Y1256851D03*
X387418Y1251537D03*
X387117Y1259351D03*
X373835Y1261903D03*
Y1264403D03*
X376345Y1261873D03*
Y1264373D03*
X376285Y1267218D03*
X373735Y1267158D03*
X387117Y1261851D03*
X387129Y1264358D03*
X387125Y1267188D03*
X384501Y1321177D03*
X386831Y1321927D03*
X378097Y1329329D03*
X374097Y1328591D03*
X382307Y1330819D03*
X380835Y1328361D03*
X374097Y1331647D03*
X373552Y1372073D03*
X377025Y1371990D03*
X380025D03*
X373532Y1378598D03*
X373552Y1375573D03*
X380025Y1378490D03*
X377025D03*
X380025Y1375490D03*
X377025D03*
Y1381490D03*
X380025D03*
X376825Y1399386D03*
X379825D03*
X373703D03*
X379825Y1402386D03*
X376825D03*
X373703D03*
X376825Y1405386D03*
X379825D03*
X373573Y1405336D03*
X374027Y1411365D03*
X373703Y1414606D03*
X376825Y1414386D03*
X379825D03*
X376825Y1417386D03*
Y1411386D03*
X379825D03*
X373703Y1417386D03*
X376825Y1408386D03*
X379825D03*
X374307Y1408135D03*
X382489Y1428478D03*
X385667Y1433425D03*
X386827Y1429525D03*
X377830Y1534342D03*
X374900Y1534102D03*
X381120D03*
X377720Y1539862D03*
X374720D03*
X374800Y1546400D03*
X385100Y1539700D03*
X381800Y1539600D03*
X381000Y1546500D03*
X384000D03*
X378000Y1546400D03*
X387930Y1585155D03*
X384600Y1595100D03*
X382220Y1591870D03*
X374391Y1648476D03*
X385123Y1639732D03*
X378547D03*
X380170Y1660002D03*
X372640Y1662112D03*
X380077Y1654049D03*
X372009Y1682584D03*
X375430Y1676462D03*
X376610Y1688252D03*
X396380Y62742D03*
X402100Y62632D03*
X399240Y62722D03*
X404910Y62562D03*
X388735Y117322D03*
X395980Y148272D03*
X388965Y215067D03*
X388720Y218362D03*
X394720Y206362D03*
X402700Y234167D03*
X392616Y252162D03*
X396294Y281585D03*
X392083Y290954D03*
X404215Y291140D03*
X398720Y321202D03*
X398661Y323761D03*
X390876Y365640D03*
X390843Y378439D03*
X403875Y365640D03*
X404120Y378439D03*
X404291Y391433D03*
X391149Y404304D03*
X403720Y405552D03*
X388720Y430862D03*
X403220Y436362D03*
X395520Y448362D03*
X400080Y472652D03*
X402500Y495362D03*
X394500Y522862D03*
X400589Y575236D03*
X398796Y1161570D03*
Y1153070D03*
Y1170070D03*
X403738Y1249027D03*
X403618Y1254197D03*
X403498Y1256747D03*
X403678Y1251597D03*
X392538Y1248997D03*
X389928Y1251507D03*
X389988Y1248937D03*
X389868Y1254107D03*
X392298Y1256717D03*
X392418Y1254167D03*
X389627Y1256821D03*
X392478Y1251567D03*
X392238Y1259287D03*
X389627Y1259321D03*
X403438Y1259317D03*
X392220Y1264594D03*
X392228Y1261897D03*
X389627Y1261821D03*
X389639Y1264328D03*
X389635Y1267158D03*
X392185Y1267218D03*
X403385Y1267248D03*
X403378Y1261917D03*
X403390Y1264624D03*
X399935Y1317092D03*
Y1319592D03*
X389161Y1321177D03*
X391491Y1321927D03*
X392131Y1324821D03*
X396397Y1324591D03*
X394197Y1323091D03*
X396397Y1321691D03*
X400073Y1327653D03*
X403051Y1325373D03*
X394297Y1326091D03*
X392131Y1327721D03*
X396397Y1327491D03*
X400888Y1395508D03*
X392947Y1397827D03*
X390934Y1404085D03*
X401079Y1399208D03*
X400924Y1408227D03*
X400926Y1404707D03*
X392517Y1419015D03*
X400991Y1417264D03*
X390934Y1407605D03*
X390914Y1412991D03*
X403125Y1425008D03*
X390687Y1431713D03*
X390777Y1435152D03*
X394067Y1435323D03*
X401244Y1440773D03*
X396822Y1439340D03*
X396946Y1537632D03*
X396768Y1541810D03*
X404920Y1539362D03*
X396946Y1556810D03*
X391330Y1585155D03*
X404030Y1595390D03*
Y1591990D03*
X394360Y1616380D03*
X392550Y1618650D03*
X397406Y1633142D03*
X402590Y1618952D03*
X401740Y1648082D03*
X404240D03*
X404320Y1645452D03*
X401820D03*
X391563Y1640244D03*
X397406Y1636542D03*
X397400Y1641000D03*
X390180Y1668212D03*
X396824Y1673662D03*
X407970Y59612D03*
X407790Y62652D03*
X415800Y62665D03*
Y67465D03*
X419901Y117491D03*
X408284Y163662D03*
X420865Y215067D03*
X410996Y218834D03*
X420752Y239562D03*
X405139Y239908D03*
X417765Y252162D03*
X404985D03*
X417218Y291274D03*
X419920Y338162D03*
X416220Y364062D03*
X418704Y379201D03*
X416762Y367353D03*
X418540Y392163D03*
X416514Y407028D03*
X412720Y439362D03*
X417880Y461942D03*
X418520Y473562D03*
X419460Y1161570D03*
Y1153370D03*
Y1169597D03*
X406248Y1248997D03*
X408798Y1249057D03*
X408511Y1256866D03*
X406001Y1256896D03*
X406128Y1254167D03*
X408678Y1254227D03*
X406188Y1251567D03*
X419638Y1248967D03*
X419295Y1256851D03*
X419518Y1254137D03*
X419578Y1251537D03*
X419295Y1259351D03*
X408738Y1251627D03*
X408523Y1259373D03*
X406013Y1259403D03*
X419295Y1261851D03*
X419307Y1264358D03*
X419285Y1267188D03*
X408523Y1264373D03*
X406013Y1264403D03*
Y1261903D03*
X408523Y1261873D03*
X405895Y1267218D03*
X408445Y1267278D03*
X416629Y1321177D03*
X418959Y1321927D03*
X410225Y1329329D03*
X406225Y1328591D03*
X414435Y1330819D03*
X412963Y1328361D03*
X406225Y1331647D03*
X418320Y1383862D03*
X422320D03*
X414333Y1385292D03*
X410933Y1384648D03*
X414909Y1395658D03*
X408915Y1402606D03*
X411150Y1408163D03*
X410912Y1418177D03*
X408968Y1410427D03*
X411162Y1414126D03*
X416926Y1426471D03*
X412416Y1431645D03*
X419861Y1429718D03*
X419302Y1434700D03*
X422708Y1437560D03*
X410074Y1424993D03*
X416999Y1441908D03*
X413599D03*
X407625Y1552572D03*
X419820Y1555862D03*
X409140Y1566892D03*
X405000Y1566670D03*
X412600Y1601000D03*
X408600Y1607400D03*
X419780Y1602802D03*
X414406Y1624992D03*
Y1628392D03*
X405990Y1618952D03*
X416020Y1620862D03*
X412456Y1649838D03*
X417960Y1650072D03*
X410700Y1655310D03*
X409857Y1682767D03*
X421320Y1671699D03*
X410249Y1673082D03*
X427120Y59862D03*
X428500Y65016D03*
Y70016D03*
X435340Y122196D03*
X428889Y121515D03*
X428883Y131015D03*
X429780Y149373D03*
Y153477D03*
Y157466D03*
Y161466D03*
X433695Y209862D03*
X421200Y232562D03*
X423145Y227862D03*
X426490Y244262D03*
X429702Y290763D03*
X425720Y319492D03*
X432380Y346522D03*
X422420Y338162D03*
X431781Y379201D03*
X434006Y365203D03*
X433596Y391163D03*
X431920Y405288D03*
X428720Y439362D03*
X437720Y435362D03*
X431570Y435512D03*
X437520Y476337D03*
X431220Y496362D03*
X434343Y504233D03*
Y509733D03*
Y498733D03*
X431220Y507143D03*
Y512623D03*
Y501643D03*
X434343Y515233D03*
Y526233D03*
Y520733D03*
X431220Y518133D03*
Y523362D03*
X434620Y535762D03*
X434343Y542733D03*
X434320Y540153D03*
X434343Y547769D03*
Y552769D03*
X421960Y1161570D03*
Y1153370D03*
Y1169597D03*
X422148Y1248937D03*
X424698Y1248997D03*
X422088Y1251507D03*
X421805Y1256821D03*
X422028Y1254107D03*
X424458Y1256717D03*
X424578Y1254167D03*
X424638Y1251567D03*
X421805Y1259321D03*
X424398Y1259287D03*
X436068Y1248967D03*
X435828Y1256687D03*
X435948Y1254137D03*
X436008Y1251537D03*
X435768Y1259257D03*
X421805Y1261821D03*
X421817Y1264328D03*
X421795Y1267158D03*
X424345Y1267218D03*
X424380Y1264594D03*
X424388Y1261897D03*
X435715Y1267188D03*
X435720Y1264564D03*
X435708Y1261857D03*
X432063Y1317092D03*
Y1319592D03*
X421289Y1321177D03*
X423619Y1321927D03*
X428525Y1321691D03*
X426325Y1323091D03*
X424259Y1324821D03*
X428525Y1324591D03*
X432628Y1327845D03*
X435179Y1325373D03*
X424259Y1327721D03*
X426425Y1326091D03*
X428525Y1327491D03*
X426320Y1383862D03*
X430320D03*
X439030Y1383692D03*
X436780Y1387387D03*
X436467Y1391687D03*
X438458Y1402169D03*
X438645Y1426890D03*
X437299Y1436774D03*
X433539Y1430613D03*
X425030Y1434292D03*
X433897Y1434670D03*
X427546Y1443411D03*
X433954Y1439029D03*
X424146Y1443411D03*
X435396Y1551810D03*
X424820Y1552605D03*
X431620Y1541362D03*
X434430Y1567562D03*
X424570Y1579466D03*
X433350Y1579509D03*
X424800Y1616600D03*
X432200Y1607060D03*
X423180Y1602802D03*
X432500Y1613822D03*
X430015Y1626608D03*
X433670Y1639562D03*
X426728Y1636495D03*
X451418Y78782D03*
X446640Y104552D03*
X446746Y152662D03*
X453028Y154864D03*
X452500Y213362D03*
Y222362D03*
X452071Y254862D03*
X442265Y290939D03*
X439120Y314562D03*
X442220Y323362D03*
X448220Y323582D03*
Y319862D03*
X446000Y339362D03*
X455000Y340362D03*
X450500Y358862D03*
X443770Y371042D03*
X451062Y397262D03*
X447490Y409052D03*
X443300Y410962D03*
X447750Y414112D03*
X453020Y414262D03*
X449420Y424162D03*
X451520Y475837D03*
X442520Y476337D03*
X453680Y515072D03*
X451320Y533562D03*
X448276Y1161570D03*
X445776D03*
X443276D03*
X445776Y1153370D03*
X448276D03*
X443276D03*
X448276Y1170069D03*
X445776D03*
X443276D03*
X441128Y1248997D03*
X438578Y1248937D03*
X438518Y1251507D03*
X440858Y1256866D03*
X438348Y1256896D03*
X441008Y1254167D03*
X438458Y1254107D03*
X441068Y1251567D03*
X440870Y1259373D03*
X438360Y1259403D03*
X451642Y1256851D03*
X451878Y1254107D03*
X451642Y1259351D03*
X451938Y1251507D03*
X451998Y1248937D03*
X438360Y1261903D03*
X440870Y1261873D03*
Y1264373D03*
X438360Y1264403D03*
X438225Y1267158D03*
X440775Y1267218D03*
X451642Y1261851D03*
X451654Y1264358D03*
X451645Y1267158D03*
X448757Y1321177D03*
X451087Y1321927D03*
X442353Y1329329D03*
X438353Y1328591D03*
X446563Y1330819D03*
X445091Y1328361D03*
X438353Y1331647D03*
X443842Y1389106D03*
X448020Y1391862D03*
X443424Y1397869D03*
X439391Y1398266D03*
X441369Y1394260D03*
X451048Y1404914D03*
X447110Y1403812D03*
X448114Y1396812D03*
X445339Y1415731D03*
X446230Y1407722D03*
X445230Y1411719D03*
X445723Y1419730D03*
X443850Y1423404D03*
X451080Y1433740D03*
X440164Y1433982D03*
X445294Y1430415D03*
X443715Y1436052D03*
X452520Y1564862D03*
X448328Y1582476D03*
X446020Y1570412D03*
X452020Y1580412D03*
X448740Y1574862D03*
X444458Y1602654D03*
X437383Y1602629D03*
X454661Y1609235D03*
X442974Y1615615D03*
X448181Y1614401D03*
X443800Y1610712D03*
X449940Y1647412D03*
X447090Y1647472D03*
X444940Y1641842D03*
X438340Y1652266D03*
X441740D03*
X462620Y120948D03*
X462320Y115948D03*
X453346Y149864D03*
X461900Y215244D03*
X466300Y217803D03*
X461900Y222921D03*
X466300Y225480D03*
X468323Y254562D03*
X465236Y296973D03*
X461736Y301098D03*
Y306098D03*
X463198Y311587D03*
X465000Y340362D03*
X456660Y359172D03*
X460800Y358962D03*
X467211Y371902D03*
X459220Y393762D03*
X463500Y383562D03*
X455720Y404762D03*
X458600Y414262D03*
X465421Y428078D03*
X456520Y476337D03*
X461520D03*
X453727Y518036D03*
X457456Y522516D03*
X470880Y572692D03*
X467130Y600122D03*
X456818Y1256687D03*
X454388Y1254077D03*
X454152Y1256821D03*
X456998Y1251537D03*
X456758Y1259257D03*
X454152Y1259321D03*
X468258Y1249107D03*
X468018Y1256827D03*
X468138Y1254277D03*
X468198Y1251677D03*
X467958Y1259397D03*
X457058Y1248967D03*
X454508Y1248907D03*
X454448Y1251477D03*
X456938Y1254137D03*
X456705Y1267188D03*
X454155Y1267128D03*
X456748Y1261867D03*
X456740Y1264564D03*
X454152Y1261821D03*
X454164Y1264328D03*
X467905Y1267328D03*
X467910Y1264704D03*
X467898Y1261997D03*
X464191Y1317092D03*
Y1319592D03*
X453417Y1321177D03*
X455747Y1321927D03*
X458453Y1323091D03*
X460653Y1321691D03*
Y1324591D03*
X456387Y1324821D03*
X464191Y1327793D03*
X467307Y1325373D03*
X458553Y1326091D03*
X460653Y1327491D03*
X456387Y1327721D03*
X459550Y1401348D03*
X465947Y1398355D03*
X459321Y1393009D03*
Y1396409D03*
X458441Y1414893D03*
X468880Y1418400D03*
X456619Y1431189D03*
X463140Y1451562D03*
X463207Y1547543D03*
X453595Y1551470D03*
X459520Y1546962D03*
X466905Y1567847D03*
X467400Y1556700D03*
X460020Y1580412D03*
X457220Y1584020D03*
X466520Y1574862D03*
X457220Y1603562D03*
X460200Y1589900D03*
X456510Y1614472D03*
X469488Y1607362D03*
X460910Y1629172D03*
Y1625772D03*
X455681Y1622492D03*
X458978Y1634481D03*
X463344Y1637622D03*
X469580Y1640272D03*
X468040Y1651657D03*
X466460Y1672332D03*
X466180Y1678392D03*
X481880Y147069D03*
X481246Y161364D03*
X476220Y158772D03*
X470900Y234787D03*
X486800Y259162D03*
X478500Y258862D03*
X474736Y302098D03*
X478995Y293787D03*
X479736Y303598D03*
Y308598D03*
X486720Y360862D03*
X482720D03*
X475508Y359266D03*
X476585Y370727D03*
X472720Y391362D03*
X485020Y414162D03*
X471920Y416687D03*
X474169Y476196D03*
X479169D03*
X474044Y503725D03*
X478510Y602942D03*
X472960Y602152D03*
X482780Y607012D03*
X473698Y1161570D03*
X471198D03*
X473698Y1153370D03*
X471198D03*
X473698Y1170070D03*
X471198D03*
X473318Y1249137D03*
X470768Y1249077D03*
X473035Y1256866D03*
X470525Y1256896D03*
X473198Y1254307D03*
X470648Y1254247D03*
X473258Y1251707D03*
X470708Y1251647D03*
X473047Y1259373D03*
X470537Y1259403D03*
X484098Y1248997D03*
X483819Y1256851D03*
X483978Y1254167D03*
X484038Y1251567D03*
X483819Y1259351D03*
X472965Y1267358D03*
X470415Y1267298D03*
X470537Y1261903D03*
X473047Y1261873D03*
Y1264373D03*
X470537Y1264403D03*
X483819Y1261851D03*
X483831Y1264358D03*
X483745Y1267218D03*
X480885Y1321177D03*
X485545D03*
X483215Y1321927D03*
X474481Y1329329D03*
X470481Y1328591D03*
X478691Y1330819D03*
X477219Y1328361D03*
X470481Y1331647D03*
X483560Y1401712D03*
X474983Y1400385D03*
X485141Y1405430D03*
X481997Y1409955D03*
X470987Y1409965D03*
X484921Y1413246D03*
X470890Y1435838D03*
X478449Y1448158D03*
X482633Y1449091D03*
Y1446091D03*
X470111Y1548269D03*
X483348Y1548062D03*
X475110Y1548112D03*
X477968Y1548122D03*
X480848Y1548120D03*
X486210Y1547960D03*
X482400Y1558320D03*
X472220Y1626732D03*
X472210Y1622735D03*
X477905Y1663242D03*
Y1659242D03*
X475150Y1654302D03*
X477835Y1677462D03*
X488748Y72264D03*
X499580Y78442D03*
X489730Y76132D03*
X498330Y96112D03*
X498730Y128592D03*
X498700Y212685D03*
Y220362D03*
X503100Y215244D03*
X500925Y231262D03*
X503100Y222921D03*
X496028Y258590D03*
X499096Y252462D03*
X489091Y293787D03*
X498636Y296273D03*
X495136Y300398D03*
Y305398D03*
X486861D03*
X495036Y310398D03*
X486710Y313582D03*
X492150Y336810D03*
X498720Y360862D03*
X490720D03*
Y368862D03*
X489520Y411862D03*
X494020Y414262D03*
X492970Y409252D03*
X502070Y427937D03*
X488169Y475696D03*
X493169Y476196D03*
X498169D03*
X486500Y556212D03*
X491043Y550447D03*
X486608Y1248967D03*
X489158Y1249027D03*
X486329Y1256821D03*
X486488Y1254137D03*
X488918Y1256747D03*
X489038Y1254197D03*
X486548Y1251537D03*
X489098Y1251597D03*
X486329Y1259321D03*
X488858Y1259317D03*
X500228Y1259237D03*
X486329Y1261821D03*
X486341Y1264328D03*
X488840Y1264624D03*
X488848Y1261927D03*
X488805Y1267248D03*
X486255Y1267188D03*
X500138Y1269637D03*
X500150Y1272344D03*
X500198Y1267037D03*
Y1264467D03*
X500168Y1261807D03*
X500150Y1275224D03*
Y1278104D03*
X487875Y1321927D03*
X492878Y1322618D03*
X490678Y1324018D03*
X496319Y1330493D03*
Y1333043D03*
X499435Y1338799D03*
X488539Y1325772D03*
X492878Y1325518D03*
X488539Y1328672D03*
X490778Y1327018D03*
X492878Y1328418D03*
X496319Y1341264D03*
X491089Y1446091D03*
Y1449091D03*
X499489D03*
Y1446091D03*
X489230Y1643592D03*
X516236Y92948D03*
X513586Y92799D03*
X510600Y92782D03*
X517290Y104252D03*
X513700Y117862D03*
X510900Y111962D03*
X503270Y128592D03*
X507320D03*
X515690Y147852D03*
X519010Y147912D03*
X518186Y139821D03*
X519236Y202404D03*
X518670Y219192D03*
X512500Y209862D03*
Y223362D03*
X508500Y232862D03*
X508000Y241862D03*
X508502Y298813D03*
X503040Y287928D03*
X508500Y303362D03*
X508136Y309398D03*
X502239Y315404D03*
X507160Y332452D03*
X510720Y360862D03*
X514720D03*
X502720D03*
X506720Y368862D03*
X509720Y390362D03*
X513720D03*
X505720Y398362D03*
X502260Y397742D03*
X511320Y437962D03*
X513444Y457522D03*
X516970Y592942D03*
X504135Y615612D03*
X505398Y1259377D03*
X502858Y1259257D03*
X502718Y1271417D03*
X505218Y1271447D03*
X505290Y1267254D03*
X505338Y1261947D03*
X505278Y1264547D03*
X502750Y1267134D03*
X502798Y1261827D03*
X502738Y1264427D03*
X502718Y1274114D03*
X505218Y1274144D03*
X515898Y1271447D03*
X515950Y1274144D03*
X505220Y1280054D03*
X502718Y1276994D03*
X505218Y1277024D03*
X502680Y1280054D03*
X515960D03*
X515950Y1277024D03*
X513013Y1334603D03*
X517673D03*
X515343Y1335353D03*
X506609Y1342755D03*
X502609Y1342017D03*
X510819Y1344245D03*
X509347Y1341787D03*
X502609Y1345073D03*
X509246Y1420002D03*
X505777Y1425579D03*
X507964Y1448979D03*
Y1445979D03*
X529720Y30792D03*
Y43054D03*
X534720Y42922D03*
X533915Y59822D03*
X523978Y59074D03*
X529078Y59282D03*
X527520Y69633D03*
X528590Y72922D03*
X518450Y101602D03*
X527310Y98147D03*
Y94747D03*
X527160Y129243D03*
X523220Y170362D03*
X534765Y161067D03*
X526920Y161362D03*
X529507Y202448D03*
X522337Y202404D03*
X531298Y284280D03*
X536420Y309422D03*
X523682Y307541D03*
Y304541D03*
X526980Y322582D03*
X521820Y336762D03*
X531720Y360862D03*
X527720D03*
X523670Y368892D03*
X525720Y390362D03*
X529720D03*
X521720Y398362D03*
X532650Y446396D03*
Y442376D03*
X521885Y452442D03*
X532650Y450330D03*
Y454270D03*
X533410Y475932D03*
X525820Y473662D03*
X524425Y489112D03*
Y495112D03*
X519520Y484027D03*
X522805Y482155D03*
X531258Y505473D03*
X521561Y505969D03*
Y500469D03*
Y511469D03*
X524220Y505862D03*
Y500362D03*
Y511362D03*
X521561Y516969D03*
Y522469D03*
X536000Y520362D03*
X524220Y516862D03*
X524720Y525293D03*
Y519743D03*
X521561Y527969D03*
Y539819D03*
X524920D03*
X524820Y545319D03*
X523699Y571545D03*
X528500Y566722D03*
X523890Y592387D03*
X531472Y579750D03*
X521118Y1273097D03*
X518488Y1271477D03*
X521058Y1275667D03*
X518490Y1274144D03*
X521058Y1278277D03*
X521020Y1280974D03*
X518500Y1280054D03*
X518490Y1277024D03*
X530398Y1288557D03*
X530548Y1283377D03*
X530428Y1285947D03*
X530410Y1291254D03*
X532558Y1289967D03*
X532618Y1287367D03*
X532678Y1284797D03*
X530450Y1297014D03*
Y1294134D03*
X532570Y1295554D03*
Y1298434D03*
Y1292674D03*
X525008Y1336287D03*
X520643Y1338247D03*
X522809Y1339517D03*
X522783Y1334882D03*
X520643Y1341147D03*
X520003Y1335353D03*
X528447Y1353316D03*
Y1355816D03*
X524892Y1341462D03*
X522818Y1342930D03*
X528929Y1364212D03*
X531563Y1361597D03*
X539720Y30792D03*
X534720D03*
X542050Y47452D03*
X539720Y42862D03*
X550971Y42902D03*
X544720Y42892D03*
X548609Y48082D03*
X537315Y59822D03*
X541002Y71436D03*
X544402D03*
X548070Y79372D03*
X542460Y99172D03*
X539475Y118772D03*
X547395Y147302D03*
X543083Y146338D03*
X540460Y200392D03*
X544390Y236512D03*
X550390Y231742D03*
X548390Y236512D03*
X546390Y231742D03*
X542050Y231722D03*
X539639Y271972D03*
X539830Y274912D03*
X537720Y278212D03*
X547420Y306862D03*
X544920D03*
X549220Y339687D03*
X535720Y360862D03*
X546758Y360502D03*
X547810Y414472D03*
X549670Y419892D03*
X542870Y438320D03*
X548464Y456534D03*
X548780Y475932D03*
X548550Y480382D03*
X546210Y519642D03*
X541820Y575130D03*
X541722Y568054D03*
X537730Y577440D03*
X547020Y590332D03*
X550320Y583362D03*
X536626Y590500D03*
X537560Y598102D03*
X537648Y1290037D03*
X535058Y1290007D03*
X535148Y1287397D03*
X543660Y1302934D03*
X541100D03*
X538560D03*
X535110Y1292704D03*
Y1295584D03*
Y1298464D03*
X537650Y1292704D03*
X540210D03*
X537650Y1298464D03*
Y1295584D03*
X540210Y1298464D03*
Y1295584D03*
X536020Y1302904D03*
X545141Y1357401D03*
X549801D03*
X538737Y1365553D03*
X534737Y1364815D03*
X542947Y1367043D03*
X541475Y1364585D03*
X534737Y1367871D03*
X547471Y1358151D03*
X563482Y40826D03*
X554720Y32862D03*
X565184Y47982D03*
X558058Y46352D03*
X554983Y45312D03*
X553650Y48842D03*
X555175Y71436D03*
X558575D03*
X551470Y79372D03*
X567865Y92656D03*
X559000Y102862D03*
X561000Y98862D03*
X552395Y134340D03*
X566500Y125097D03*
X551231Y122671D03*
X564890Y142173D03*
X555220Y164787D03*
X555545Y156462D03*
X555195Y184862D03*
Y171862D03*
X554872Y196635D03*
X559400Y201162D03*
X557248Y198909D03*
X564600Y202662D03*
X552489Y212022D03*
X553402Y231292D03*
X552089Y253202D03*
Y257202D03*
X562461Y272161D03*
X561324Y301149D03*
X566730Y300992D03*
X555520Y309827D03*
X563790Y331846D03*
X561290D03*
X558790D03*
X562200Y419412D03*
X559300Y414112D03*
X559730Y434772D03*
X557829Y454479D03*
X558220Y459362D03*
X563281Y543113D03*
X563700Y538477D03*
X560640Y540613D03*
X566140Y554972D03*
Y551472D03*
X559927Y548457D03*
X556820Y570462D03*
X557430Y583572D03*
X566510Y1352217D03*
X554837Y1359315D03*
X557037Y1363715D03*
Y1357915D03*
Y1360815D03*
X554937Y1362315D03*
X552771Y1361045D03*
Y1363945D03*
X552131Y1358151D03*
X555057Y1449395D03*
X572500Y32862D03*
X568500D03*
X581500Y41862D03*
X573190Y42912D03*
X567507Y45869D03*
X575330Y47672D03*
X570208Y47982D03*
X579930Y72052D03*
X577300Y66682D03*
X577880Y75442D03*
X570150Y102862D03*
X579080Y119402D03*
X573360Y140532D03*
X573115Y161232D03*
X569470Y171702D03*
X581120Y155062D03*
X568245Y167112D03*
X579481Y198378D03*
X579170Y190092D03*
X579481Y194378D03*
Y206378D03*
X578450Y218562D03*
X579245Y221362D03*
X567730Y225362D03*
X578390D03*
X567730Y221362D03*
X581755Y236978D03*
X575359Y265132D03*
X582510Y296657D03*
X577676Y300268D03*
X577480Y303822D03*
X582510Y304052D03*
Y311571D03*
X570440Y331930D03*
X567630Y331958D03*
X574800Y322462D03*
X571830Y348772D03*
X572360Y351962D03*
X571720Y381862D03*
X575050Y383602D03*
X577720Y381862D03*
X574491Y376549D03*
X580370Y383670D03*
X581090Y426970D03*
X571930Y421232D03*
X571110Y442656D03*
X569490Y437600D03*
X571110Y446706D03*
X567320Y454962D03*
Y459962D03*
Y457462D03*
X577220Y449462D03*
X578920Y466462D03*
X583045Y488212D03*
X583220Y493212D03*
X568840Y501046D03*
X584173Y498422D03*
X568520Y504162D03*
Y506662D03*
X577470Y505592D03*
X578925Y516846D03*
X571627Y548124D03*
X569050Y578292D03*
X572057Y577242D03*
X571555Y1352487D03*
X570645Y1361358D03*
X576220Y1423862D03*
X571620Y1424492D03*
X584950Y54842D03*
X586260Y52222D03*
X599800Y43152D03*
X597955Y48047D03*
X593369Y45682D03*
X586600Y60602D03*
X590680Y83591D03*
X592307Y94262D03*
X597287D03*
X594720Y97220D03*
X588245Y132142D03*
X598410Y124102D03*
X598390Y126802D03*
X589690Y161732D03*
X592220Y173862D03*
X596795Y179287D03*
X590281Y180698D03*
X599720Y184887D03*
X593220D03*
X584795Y233362D03*
X591310Y219582D03*
X592220Y249362D03*
X595415Y246515D03*
X591727Y285862D03*
X593763Y293999D03*
X588850Y291622D03*
X599620Y314762D03*
X595520Y314862D03*
X583820Y314662D03*
X590820Y330962D03*
X590720Y327862D03*
Y324582D03*
X590470Y319192D03*
X593120Y342782D03*
X583685Y363271D03*
X586185D03*
X586070Y352302D03*
X591839Y426112D03*
X595380Y416660D03*
X591720Y433937D03*
X595520Y439762D03*
X597220Y458688D03*
X599080Y448062D03*
X584100Y477952D03*
X592520Y467662D03*
X590210Y484132D03*
X599645Y479862D03*
X598661Y486922D03*
X587100Y493842D03*
X592400Y479162D03*
X591070Y504900D03*
X594090Y501957D03*
X587100Y496342D03*
X591425Y522337D03*
X591500Y516862D03*
X596880Y534812D03*
X592340Y744624D03*
X598693Y742072D03*
X611810Y34400D03*
X612822Y43232D03*
X606880Y44682D03*
X614400Y46012D03*
X603063Y48023D03*
X606020Y84562D03*
X615220Y76862D03*
X615170Y73812D03*
X601220Y73862D03*
Y76862D03*
X603720Y98362D03*
X608620Y94162D03*
X617585Y97257D03*
X613020Y94162D03*
X617409D03*
X603880Y93902D03*
X600220Y96862D03*
X614384Y119342D03*
X606040Y153432D03*
X606190Y144002D03*
X602580Y151052D03*
X603019Y146399D03*
X615573Y179484D03*
X615572Y176442D03*
X611381Y200378D03*
X613970Y188752D03*
X611381Y209878D03*
X614200Y265792D03*
X605350Y293092D03*
X605870Y298172D03*
X605560Y303372D03*
X607590Y314732D03*
X609040Y317282D03*
X615635Y317637D03*
X614130Y328762D03*
X605305Y331162D03*
X615180Y336812D03*
X605898Y372984D03*
X609690Y402812D03*
X605220Y416362D03*
X610720Y436362D03*
X600800Y430900D03*
X614220Y436362D03*
X610720Y442862D03*
X614220D03*
Y447862D03*
X602910Y461862D03*
X610720Y457862D03*
X614220D03*
X610720Y452862D03*
X604360Y452120D03*
X614220Y467862D03*
Y472862D03*
Y477862D03*
X605469Y467562D03*
X610720Y462862D03*
X614220D03*
X601220Y486922D03*
X600645Y504362D03*
X606200Y510862D03*
X611870Y512560D03*
X606220Y517762D03*
X607328Y537481D03*
X610797Y537528D03*
X607720Y550862D03*
X610720D03*
X613220Y654662D03*
X603276Y741375D03*
X600460Y744912D03*
X613047Y741492D03*
X602768Y758385D03*
X616675Y31777D03*
X624633Y49193D03*
X629820Y42562D03*
Y45062D03*
X619562Y49193D03*
X624140Y46672D03*
X622271Y44782D03*
X629000Y67362D03*
X628590Y58622D03*
X622271Y57952D03*
X623300Y95762D03*
X620540Y100112D03*
X632300Y104472D03*
X626699Y119182D03*
X630951D03*
X631290Y153702D03*
X615970Y161522D03*
X628195Y175914D03*
X628194Y172872D03*
X617370Y188752D03*
X630040D03*
X626640D03*
X628730Y216472D03*
X631730D03*
X628730Y220472D03*
Y224472D03*
X631730Y220472D03*
Y224472D03*
X622730Y230362D03*
X630795Y236862D03*
X618470Y265732D03*
X629564Y253127D03*
X621060Y271066D03*
X633150Y301457D03*
X627950Y298897D03*
X627600Y309134D03*
X632143Y306575D03*
X630220Y314362D03*
X623365Y316742D03*
X631146Y317768D03*
X619474Y331162D03*
X619100Y374638D03*
X621720Y373362D03*
X622490Y402162D03*
X628500Y402362D03*
X624220Y411362D03*
X629220D03*
X623220Y426362D03*
X625500Y421362D03*
X629220D03*
Y426362D03*
X628900Y431050D03*
X625620Y447862D03*
X625900Y431050D03*
X625620Y442862D03*
X629220D03*
X622220D03*
X617220Y436362D03*
X622220Y452862D03*
Y447862D03*
X629220Y457862D03*
X626400Y462812D03*
X625620Y457862D03*
X622220D03*
X629220Y452862D03*
X625620D03*
X629220Y447862D03*
X626390Y467882D03*
X626210Y478002D03*
X626310Y472902D03*
X629220Y462862D03*
X622220D03*
X622520Y467862D03*
X629220Y487310D03*
X622860D03*
X626720Y482880D03*
X623670Y507862D03*
X629480Y508862D03*
X633000Y508700D03*
X629920Y516652D03*
X623000Y546900D03*
X629220Y643462D03*
X626720D03*
X617252Y739354D03*
X623497Y748235D03*
X626017Y745083D03*
X620870Y762072D03*
X617940Y763552D03*
X630417Y757135D03*
X628970Y1670880D03*
X637220Y31462D03*
X643880Y42142D03*
X647447Y46322D03*
X641200Y46762D03*
X638500Y57362D03*
X635000D03*
X637000Y68142D03*
X634500Y73422D03*
X645330Y77132D03*
Y72972D03*
X640220Y85542D03*
X634690D03*
X647220Y96929D03*
X639901Y103462D03*
X640000Y108542D03*
X639970Y113892D03*
X640130Y166362D03*
X643170Y171362D03*
X649870Y181942D03*
X645263Y235689D03*
X640295Y234237D03*
X645109Y249202D03*
Y260202D03*
X643800Y294327D03*
Y298297D03*
Y306547D03*
Y302247D03*
X645990Y314482D03*
X643800Y310962D03*
X633350Y314362D03*
X647100Y357372D03*
X636075Y389862D03*
X649075Y389937D03*
X632620Y389862D03*
X645925Y389937D03*
X638700Y400962D03*
X647700Y399162D03*
X643500Y400962D03*
X643940Y411482D03*
X637220Y411362D03*
X644220Y426362D03*
X640720Y418862D03*
X644220Y421362D03*
X637220Y416362D03*
Y426362D03*
X637195Y421362D03*
X647420Y434162D03*
X640720Y431362D03*
X644000Y438862D03*
X644220Y431362D03*
X638250Y439250D03*
X637220Y431362D03*
X644220Y452862D03*
X640820Y457902D03*
X637220Y452862D03*
X640720D03*
X640920Y447862D03*
X644220D03*
X637195Y457862D03*
X637220Y467862D03*
Y472862D03*
Y477862D03*
X644220D03*
Y462862D03*
X641235Y477377D03*
X640798Y472934D03*
X637220Y462862D03*
X640820Y467862D03*
X640620Y483422D03*
X642580Y508172D03*
X645220Y504362D03*
X646815Y517974D03*
X648296Y528255D03*
X637020Y522362D03*
X642630Y517870D03*
X640130D03*
X633147Y758595D03*
X647725Y1643719D03*
X643725Y1643467D03*
X648225Y1658482D03*
X642725Y1658562D03*
X635410Y1664220D03*
X637540Y1669480D03*
X636702Y1677610D03*
X645725Y1691182D03*
X640725Y1691452D03*
X650725Y1690682D03*
X646225Y1708169D03*
X642225Y1708457D03*
X648220Y1716912D03*
X636160Y1710662D03*
X639745Y1722362D03*
Y1718362D03*
X648220Y1722921D03*
X651943Y33535D03*
X656439Y47264D03*
X659839D03*
X663543Y43328D03*
X656950Y59012D03*
X651680Y73812D03*
X656500Y69662D03*
X661587D03*
X661600Y75562D03*
X657165Y79131D03*
X656426Y75431D03*
X652320Y123362D03*
X662498Y124960D03*
X650790Y149871D03*
Y140699D03*
X662880Y149912D03*
Y146912D03*
X651730Y177212D03*
X662560Y214152D03*
X662780Y210362D03*
Y205362D03*
Y207862D03*
X659880Y210762D03*
Y205762D03*
Y208262D03*
X650705Y270947D03*
X662891Y357442D03*
X662680Y354362D03*
X651520Y378662D03*
X658720Y399862D03*
X652000Y402362D03*
X653100Y407862D03*
X655820Y452662D03*
X655800Y461432D03*
X652195Y457862D03*
X655820Y467662D03*
X663000Y489500D03*
X663014Y493860D03*
X655220Y486862D03*
X661865Y505334D03*
X663720Y523806D03*
X665990Y517131D03*
X661220Y526862D03*
X650794Y515039D03*
X652577Y1000775D03*
X653690Y1392362D03*
X653761Y1396300D03*
X663187Y1395170D03*
Y1397720D03*
X666303Y1403476D03*
X663687Y1407279D03*
X654540Y1427605D03*
Y1424205D03*
X661100Y1451012D03*
X662660Y1548120D03*
X663410Y1553982D03*
X664590Y1631620D03*
X663097Y1642667D03*
X651725Y1643397D03*
X656725Y1660769D03*
X663118Y1655557D03*
X663043Y1651557D03*
X663145Y1672862D03*
Y1668862D03*
X653420Y1698662D03*
X663645Y1722862D03*
X680200Y39062D03*
X677560Y40572D03*
X672250Y40812D03*
X666943Y43328D03*
X682290Y46822D03*
X670612Y47264D03*
X674012D03*
X674035Y74522D03*
X678050Y58157D03*
X673987Y87662D03*
X677820Y89462D03*
X680578Y75992D03*
X674540Y80652D03*
X670800Y85932D03*
X667940Y80142D03*
X671320Y91192D03*
X677790Y104880D03*
X673720Y110362D03*
X674145Y113487D03*
X677978Y119668D03*
Y115668D03*
X675560Y117120D03*
X668300Y132400D03*
X665650Y147692D03*
X673713Y237725D03*
X674731Y359924D03*
X680600Y364282D03*
X683100Y369550D03*
X673220Y388362D03*
X675295Y399862D03*
X670720D03*
X668695Y408362D03*
Y404262D03*
X665870Y433942D03*
X675220Y508862D03*
X680220Y495887D03*
X670220Y503837D03*
X680220Y508862D03*
X675220Y521862D03*
X670720D03*
Y516862D03*
X680220Y530362D03*
X673340Y530922D03*
X673617Y744735D03*
X669700Y746626D03*
X677887Y742121D03*
X669778Y759929D03*
X670037Y1336396D03*
X664987D03*
X667487D03*
X664987Y1338896D03*
X667487D03*
X670037D03*
Y1333896D03*
X664987D03*
X667487D03*
X664987Y1348896D03*
X667487D03*
X664987Y1346396D03*
X667487D03*
X664987Y1343896D03*
Y1341396D03*
X667487D03*
Y1343896D03*
X670037Y1341396D03*
Y1343896D03*
Y1346396D03*
Y1348896D03*
X679881Y1399280D03*
X673477Y1409386D03*
X669477Y1406694D03*
X677619Y1408887D03*
X675876Y1406619D03*
X669477Y1409415D03*
X674149Y1434149D03*
X671149D03*
X668649D03*
X674149Y1426149D03*
Y1431149D03*
Y1428649D03*
X671149Y1426149D03*
X668649D03*
X671149Y1431149D03*
X668649Y1428649D03*
Y1431149D03*
X671149Y1428649D03*
X677319Y1428359D03*
Y1433359D03*
Y1430859D03*
X682160Y1548040D03*
X665410Y1548180D03*
X679207Y1560482D03*
X678877Y1566798D03*
X678621Y1571072D03*
X678610Y1582154D03*
X666560Y1581000D03*
X678619Y1579070D03*
X666600Y1584900D03*
X678900Y1595400D03*
X678771Y1585945D03*
X666700Y1595500D03*
X678900Y1589800D03*
X666700Y1591900D03*
X678900Y1592600D03*
X666700Y1588500D03*
X679640Y1617520D03*
Y1614000D03*
X679270Y1604040D03*
X675710Y1620320D03*
X673420Y1650057D03*
X671290Y1646320D03*
X668695Y1662235D03*
X671610Y1673792D03*
X671620Y1668303D03*
X677940Y1670110D03*
X678490Y1695660D03*
X674195Y1712362D03*
X675120Y1716242D03*
X674195Y1728362D03*
X672270Y1721612D03*
X687120Y39632D03*
X692289Y40633D03*
X689940Y38952D03*
X696800Y42108D03*
X696838Y47940D03*
X683440Y42832D03*
X687344Y46940D03*
X692389Y46439D03*
X694751Y70212D03*
X690027Y70142D03*
X685780Y70022D03*
X699475Y69982D03*
X685968Y58157D03*
X694400D03*
X681980D03*
X690510Y59132D03*
X696700Y72462D03*
X692389Y72692D03*
X687664Y73202D03*
X696370Y78512D03*
X696727Y81552D03*
Y84052D03*
X681053Y104668D03*
X695720Y102162D03*
X694220Y104862D03*
X688019Y109845D03*
X687030Y113090D03*
X687034Y115896D03*
X697615Y123697D03*
X687238Y171071D03*
X685600Y364282D03*
X690600D03*
X695600D03*
X683500Y381200D03*
X685210Y388852D03*
X694920Y388797D03*
X687500Y399402D03*
X692330Y388751D03*
X685220Y391652D03*
X692402Y391250D03*
X695220Y399862D03*
X685270Y408362D03*
Y404262D03*
X692400Y404682D03*
X683320Y490662D03*
X685220Y495887D03*
X690580Y482992D03*
X694510Y482942D03*
X686120Y481862D03*
X695220Y495887D03*
X690220D03*
X695220Y508862D03*
X685220D03*
X690220Y506362D03*
X685220Y503837D03*
X690220Y508882D03*
X690330Y503530D03*
X695257Y503847D03*
X695220Y516852D03*
X685220D03*
X690220Y519662D03*
X695220D03*
X689720Y530862D03*
X695220Y530662D03*
X683457Y745175D03*
X696810Y1300162D03*
X692280Y1302532D03*
X684555Y1338896D03*
X689605Y1336396D03*
Y1338896D03*
X687105Y1336396D03*
X684555D03*
X687105Y1338896D03*
X689605Y1333896D03*
X687105D03*
X684555D03*
X689605Y1348896D03*
X687105D03*
X689605Y1346396D03*
X687105D03*
X684555Y1341396D03*
Y1343896D03*
Y1346396D03*
Y1348896D03*
X689605Y1341396D03*
Y1343896D03*
X687105Y1341396D03*
Y1343896D03*
X684541Y1399280D03*
X682211Y1400030D03*
X686871D03*
X691777Y1405594D03*
Y1399794D03*
X689577Y1401194D03*
X687511Y1402924D03*
X691777Y1402694D03*
X689677Y1404194D03*
X687511Y1405824D03*
X694596Y1396198D03*
X694129Y1420283D03*
X696754Y1419809D03*
X691129Y1420283D03*
X681899Y1434049D03*
Y1426049D03*
Y1431049D03*
Y1428549D03*
X694129Y1423303D03*
X691129D03*
X696694Y1427949D03*
Y1425449D03*
Y1430449D03*
X696784Y1422614D03*
X683930Y1552562D03*
Y1555062D03*
Y1557562D03*
X692100Y1567190D03*
X692026Y1580490D03*
X697197Y1640667D03*
X697122Y1636667D03*
X689200Y1648843D03*
X686220Y1640667D03*
X697595Y1666862D03*
X687045Y1673362D03*
X706370Y46782D03*
X701838Y42202D03*
Y47940D03*
X703900Y72112D03*
X701400D03*
X713000Y69662D03*
X697720Y58162D03*
X710200Y69662D03*
X706867Y58197D03*
X703100Y58157D03*
X712500Y79862D03*
X710486Y77695D03*
X700500Y74862D03*
X698710Y86035D03*
X705390Y85792D03*
X703000Y84862D03*
X706720Y100462D03*
X699220Y102162D03*
X702720D03*
X701220Y104862D03*
X697720D03*
X712733Y117488D03*
Y114588D03*
X712290Y106722D03*
X712340Y128093D03*
X700600Y125309D03*
X707008Y125804D03*
X705800Y167788D03*
Y171188D03*
X704770Y182999D03*
Y179599D03*
Y194810D03*
Y191410D03*
Y218432D03*
Y206621D03*
Y215032D03*
Y203221D03*
X700600Y364282D03*
X705600D03*
X710600D03*
X709000Y354000D03*
X715600Y363900D03*
X705700Y361400D03*
X709400Y378200D03*
X713220Y378362D03*
X711200Y396500D03*
X707220Y399362D03*
X709160Y386730D03*
X713220Y388362D03*
X707400Y396200D03*
X713220Y399862D03*
X705195Y408362D03*
Y404262D03*
X705780Y411022D03*
X712770Y406822D03*
X705720Y488862D03*
X703220Y490362D03*
X705720Y484862D03*
X711220Y503842D03*
X705220D03*
Y508862D03*
X711220Y508882D03*
X710720Y521362D03*
X705220D03*
X701757Y521324D03*
X705220Y530362D03*
X710940Y591172D03*
X698602Y580536D03*
X705240Y594020D03*
X702740D03*
X712060Y638542D03*
X708680Y638812D03*
X708310Y646032D03*
X704320Y645262D03*
X704000Y740862D03*
X700500Y745862D03*
X703545Y745907D03*
X711720Y1286162D03*
X707720Y1290162D03*
X705720Y1286662D03*
X704795Y1294559D03*
X707320Y1301162D03*
X708137Y1336396D03*
Y1338896D03*
X703087Y1336396D03*
X705587D03*
Y1338896D03*
X703087D03*
X708137Y1333896D03*
X705587D03*
X703087D03*
Y1346396D03*
X705587D03*
X703087Y1348896D03*
X705587D03*
X708137Y1341396D03*
Y1343896D03*
X705587Y1341396D03*
X703087D03*
Y1343896D03*
X705587D03*
X708137Y1348896D03*
Y1346396D03*
X701330Y1395195D03*
Y1397695D03*
X704446Y1403476D03*
X701830Y1407326D03*
X711620Y1409386D03*
X707620Y1406694D03*
Y1409660D03*
X699754Y1419809D03*
X699694Y1427949D03*
Y1425449D03*
Y1430449D03*
X699784Y1422614D03*
X712222Y1570703D03*
X702112Y1571683D03*
Y1575683D03*
Y1579683D03*
X711102Y1575683D03*
X714162Y1574333D03*
X713052Y1579683D03*
X712582Y1584843D03*
X704497Y1598927D03*
X702112Y1587683D03*
Y1591683D03*
X713102Y1601307D03*
X715775Y1599024D03*
X714380Y1589960D03*
X702112Y1595683D03*
X712512Y1596338D03*
X711350Y1590720D03*
X711780Y1614590D03*
X704370Y1604580D03*
X706103Y1617107D03*
X708857Y1613462D03*
X710570Y1629890D03*
X708830Y1623115D03*
X705516Y1620296D03*
X710540Y1636070D03*
X708999Y1646762D03*
X703719Y1646768D03*
X697595Y1662862D03*
X700460Y1660918D03*
X709678Y1658485D03*
X697730Y1677460D03*
X704759Y1677001D03*
X723041Y-13200D03*
Y-9800D03*
X724620Y40062D03*
X728720Y43562D03*
X719820Y45862D03*
X717320Y44062D03*
X729293Y58062D03*
X724644Y58362D03*
X719949Y58862D03*
X715990Y69662D03*
X725740Y69580D03*
X721990Y69762D03*
X718900Y69662D03*
X727700Y60562D03*
X728591Y71960D03*
X722415Y77862D03*
X718425Y77882D03*
X728090Y75132D03*
X719100Y85262D03*
X727518Y90984D03*
X715933Y117488D03*
Y114588D03*
X729933Y108388D03*
X728733Y132088D03*
Y129288D03*
X720433Y135088D03*
X717433D03*
X728733Y126388D03*
X719933Y124488D03*
X723133D03*
X715940Y157362D03*
X718213Y159241D03*
X720633Y160788D03*
X716698Y185687D03*
Y173687D03*
Y177087D03*
Y197187D03*
Y200587D03*
Y189087D03*
Y209021D03*
Y212421D03*
X717020Y220862D03*
X719720Y220142D03*
X722500Y365500D03*
X724897Y353887D03*
X721989Y351234D03*
X727000Y365500D03*
X731400D03*
X722500Y374100D03*
X727000D03*
X731400Y375000D03*
X718720Y381892D03*
X728220Y388362D03*
X723195Y408362D03*
Y404262D03*
X725220Y399862D03*
X723220Y508882D03*
X717220D03*
X729220D03*
Y503842D03*
X723220D03*
X717220D03*
X714000Y496132D03*
X723120Y525362D03*
X728220Y521362D03*
X717220D03*
X717296Y525407D03*
X723220Y516852D03*
X729220D03*
X717220D03*
X729212Y531700D03*
X729328Y583076D03*
X729295Y586113D03*
X725207Y579371D03*
X722707D03*
X715860Y585540D03*
X714320Y597462D03*
X723450Y597072D03*
X720240Y598292D03*
X715420Y639162D03*
X719190Y646642D03*
X717720Y643262D03*
X715220D03*
X723340Y642922D03*
X714087Y745865D03*
X720697Y765862D03*
X723460Y1245632D03*
X714720Y1286162D03*
X723054Y1333896D03*
X725604D03*
X728104D03*
X725604Y1338896D03*
X723054Y1336396D03*
X725604D03*
X728104Y1338896D03*
Y1336396D03*
X723054Y1338896D03*
X725604Y1346396D03*
X728104D03*
X725604Y1348896D03*
X728104D03*
X725604Y1343896D03*
Y1341396D03*
X728104Y1343896D03*
Y1341396D03*
X723054Y1348896D03*
Y1346396D03*
Y1343896D03*
Y1341396D03*
X725654Y1405824D03*
Y1402924D03*
X727720Y1401194D03*
X727820Y1404194D03*
X718024Y1399280D03*
X722684D03*
X720354Y1400030D03*
X725014D03*
X715762Y1408887D03*
X714019Y1406619D03*
X717300Y1547370D03*
X715792Y1567461D03*
X720370Y1566910D03*
X723520Y1561604D03*
X724712Y1566820D03*
X716612Y1584635D03*
X717152Y1570093D03*
X728977Y1574453D03*
X717402Y1574433D03*
X724465Y1580092D03*
X722465Y1582092D03*
X726465D03*
X723942Y1574123D03*
X724465Y1590950D03*
X722465Y1588950D03*
X726465D03*
X729052Y1602518D03*
X726092Y1598483D03*
X720987Y1599568D03*
X723542Y1612702D03*
X721488Y1610945D03*
X725910Y1611900D03*
X716688Y1610055D03*
X719168Y1612016D03*
X718195Y1647300D03*
X714203Y1642926D03*
X729150Y1641690D03*
X726810Y1652430D03*
X714071Y1663842D03*
X722630Y1655740D03*
X724500Y1680400D03*
X718758Y1673800D03*
X745900Y40362D03*
X733314Y40862D03*
X740100Y41162D03*
X746100Y46262D03*
X736620Y45262D03*
X745474Y57932D03*
X733642Y58062D03*
X741377Y57932D03*
X737595D03*
X732793Y71436D03*
X736193D03*
X742620Y71762D03*
X735880Y60662D03*
X740819Y82362D03*
X736720Y101662D03*
X745035Y94632D03*
X735770Y94988D03*
X739823Y91052D03*
X741308Y108742D03*
X738600Y136600D03*
X736060Y145532D03*
X740220Y145362D03*
X745725Y167537D03*
X732720Y231362D03*
X734220Y238362D03*
X744247Y312598D03*
X741800Y363200D03*
X742090Y356082D03*
X735600Y351400D03*
X735800Y365500D03*
X732700Y351500D03*
X740200Y375100D03*
X736220Y380787D03*
X742720Y380262D03*
X735800Y375000D03*
X738220Y388362D03*
X742160Y396452D03*
X738220Y383862D03*
X745720Y399862D03*
X735220Y410842D03*
X735745Y408362D03*
Y404262D03*
X733720Y399862D03*
X743980Y443482D03*
X740740Y473822D03*
X741420Y494162D03*
X747600Y506592D03*
X735220Y508862D03*
X745220Y503842D03*
X735220D03*
X735430Y516862D03*
X745220Y522362D03*
Y516852D03*
X730220Y523362D03*
X740840Y521982D03*
X735173Y521362D03*
X736480Y531722D03*
X738980D03*
X733922Y531712D03*
X733117Y580071D03*
Y582571D03*
X733134Y585672D03*
X736710Y603842D03*
Y607242D03*
X735620Y613862D03*
X730690Y655532D03*
X744538Y746524D03*
X737609Y744282D03*
X730889Y746834D03*
X740820Y741762D03*
X729920Y1405594D03*
X732226Y1396212D03*
X729920Y1399794D03*
Y1402694D03*
X733336Y1568341D03*
Y1565341D03*
Y1559341D03*
Y1562341D03*
X730336Y1559341D03*
Y1562341D03*
X745336D03*
Y1559341D03*
Y1565341D03*
Y1568341D03*
X742336Y1562341D03*
Y1559341D03*
Y1565341D03*
Y1568341D03*
X739336Y1562341D03*
Y1559341D03*
Y1565341D03*
Y1568341D03*
X736336D03*
Y1565341D03*
Y1559341D03*
Y1562341D03*
X733336Y1574341D03*
Y1571341D03*
X745336Y1574341D03*
Y1571341D03*
X742336Y1574341D03*
Y1571341D03*
X739336Y1574341D03*
Y1571341D03*
X736336D03*
Y1574341D03*
X730282Y1580391D03*
X741382Y1585251D03*
Y1580121D03*
X735882Y1580391D03*
X730282Y1590651D03*
Y1585521D03*
X735882Y1590651D03*
X741382Y1590691D03*
X732504Y1600321D03*
Y1597321D03*
X744504D03*
Y1600321D03*
X741504Y1597321D03*
Y1600321D03*
X735504Y1597321D03*
Y1600321D03*
X738504Y1597321D03*
Y1600321D03*
X744504Y1609521D03*
Y1612521D03*
X741504Y1609521D03*
X738504D03*
X735504D03*
X741504Y1612521D03*
X738504D03*
X735504D03*
X732504Y1603321D03*
Y1606321D03*
X744504Y1603321D03*
Y1606321D03*
X741504Y1603321D03*
Y1606321D03*
X738504Y1603321D03*
X735504D03*
X738504Y1606321D03*
X735504D03*
X735300Y1648760D03*
X737080Y1655820D03*
X735080Y1662980D03*
X740840Y1655590D03*
X732705Y1669450D03*
X754620Y51602D03*
X758620D03*
X749477Y57932D03*
X755700Y59942D03*
Y62442D03*
X758200Y59942D03*
Y62442D03*
X760700Y59942D03*
Y62442D03*
X747487Y71429D03*
X757693Y100653D03*
Y96423D03*
X750700Y106642D03*
X754800Y97082D03*
X750033Y92888D03*
Y89988D03*
X757340Y92562D03*
X748033Y116288D03*
X747230Y108572D03*
X760390Y111810D03*
X751220Y137864D03*
X747200Y251500D03*
X757150Y280592D03*
X758720Y283262D03*
X759920Y280562D03*
X758412Y298790D03*
X755305Y298847D03*
X748820Y284562D03*
X758390Y295450D03*
X748498Y309640D03*
X759637Y311585D03*
X757936Y303908D03*
X760670Y317432D03*
X747554Y384962D03*
X757430Y408212D03*
X760469Y442647D03*
X750290Y462162D03*
X757365Y459862D03*
X752500Y495762D03*
X757238Y483862D03*
X756642Y496522D03*
Y501744D03*
X751220Y522362D03*
Y516852D03*
X759790Y525522D03*
X755940Y516862D03*
X756650Y526072D03*
X761710Y517651D03*
X757020Y530462D03*
X759820D03*
X754220D03*
X762345Y1284542D03*
Y1287542D03*
Y1290542D03*
X762205Y1293272D03*
X757720Y1375462D03*
Y1384062D03*
X758020Y1397862D03*
X758420Y1406862D03*
X758120Y1414762D03*
X755420Y1426262D03*
Y1422862D03*
X748336Y1562341D03*
Y1559341D03*
Y1565341D03*
Y1568341D03*
X751336D03*
Y1565341D03*
Y1559341D03*
Y1562341D03*
X748336Y1574341D03*
Y1571341D03*
X760112Y1579183D03*
X749612Y1579023D03*
X749652Y1586407D03*
X760152Y1583183D03*
X749612Y1583023D03*
X760112Y1592183D03*
Y1587183D03*
X747504Y1600321D03*
X749662Y1590733D03*
X749612Y1594683D03*
X758360Y1589661D03*
X747504Y1609521D03*
Y1612521D03*
X750504D03*
Y1609521D03*
X747504Y1603321D03*
Y1606321D03*
X761716Y1661194D03*
X751620Y1674312D03*
X759859Y1686090D03*
X759359Y1729520D03*
X752875Y1726670D03*
X774059Y68912D03*
X773420Y143462D03*
X772328Y153728D03*
X771426Y158026D03*
X766320Y264892D03*
X763320D03*
X771630Y258102D03*
X762420Y280562D03*
X777420Y277962D03*
X769789Y296231D03*
X777467Y296315D03*
X769860Y302462D03*
X771377Y314139D03*
X771490Y354942D03*
X768490D03*
X777420Y354962D03*
X774490Y354942D03*
X765000Y354862D03*
X771960Y375162D03*
X767960Y369662D03*
X776000D03*
X764000D03*
X766195Y393212D03*
X773245Y398212D03*
X766195Y403212D03*
Y413212D03*
X773245Y403212D03*
Y408212D03*
X768910Y403260D03*
X771050Y416940D03*
X766195Y423212D03*
Y428212D03*
X768701Y418662D03*
X774982Y446908D03*
X772365Y454862D03*
X768720Y459862D03*
X765315Y454862D03*
Y459862D03*
X772365D03*
X765360Y475412D03*
X765335Y469552D03*
X772364Y475062D03*
X772365Y469862D03*
X765315Y479862D03*
X772365Y488862D03*
X776170Y493422D03*
X766510Y493452D03*
X765386Y483572D03*
X773530Y507062D03*
X765810Y506342D03*
X769745Y502600D03*
X775378Y502502D03*
X765521Y525364D03*
X769220Y530362D03*
X765720D03*
X777020D03*
X772020Y746562D03*
X774384Y744088D03*
X762562Y746444D03*
X769921Y742095D03*
X767421D03*
X764921D03*
X769337Y760775D03*
X762617Y758885D03*
X765345Y1284542D03*
X768335Y1284612D03*
X765345Y1287542D03*
Y1290542D03*
X768335Y1287612D03*
Y1290612D03*
X765205Y1293272D03*
X768195Y1293342D03*
X778005Y1294092D03*
X768520Y1384062D03*
Y1375462D03*
X768620Y1397262D03*
X775375Y1403561D03*
X767820Y1414762D03*
X763152Y1581893D03*
Y1577893D03*
Y1573793D03*
X773952Y1580493D03*
X768714Y1571203D03*
X769452Y1584393D03*
X770252Y1587268D03*
X763152Y1590893D03*
Y1594893D03*
X774052Y1590293D03*
X776922Y1590444D03*
X776052Y1611893D03*
X764920Y1695347D03*
X766880Y1689020D03*
X766603Y1721797D03*
X785180Y120947D03*
X792680D03*
X790180D03*
X787680D03*
X783940Y118637D03*
X786440D03*
X788940D03*
X781440D03*
X782553Y150031D03*
Y152531D03*
X779893Y147521D03*
Y150021D03*
X780820Y278262D03*
X785135Y274822D03*
X785200Y271400D03*
X794057Y301569D03*
X794220Y296062D03*
X785220Y284762D03*
X792943Y312642D03*
X784415Y313734D03*
X793896Y309026D03*
X793820Y304962D03*
X779120Y303410D03*
Y308755D03*
X785000Y355000D03*
X779920Y354962D03*
X782420D03*
X790120Y354862D03*
X792620D03*
X787600Y354900D03*
X795520Y393462D03*
X791075Y388000D03*
X781195Y393212D03*
X781320Y398212D03*
X787720Y408362D03*
X781195Y413212D03*
Y423212D03*
X785560Y417902D03*
X788120Y422942D03*
X791040Y422892D03*
X793660Y422842D03*
X785720Y427862D03*
X789230Y414942D03*
X780020Y441437D03*
Y445287D03*
X784730Y432682D03*
X787320Y444862D03*
Y439862D03*
X791582Y435352D03*
X781205Y454402D03*
X780315Y459862D03*
X787320Y454862D03*
Y449862D03*
Y459862D03*
X787360Y469862D03*
X786220Y464862D03*
X796315Y469290D03*
X780315Y464862D03*
X783340Y474802D03*
X782690Y488862D03*
X793220Y493362D03*
X781170Y493422D03*
X785800Y482762D03*
X793875Y483262D03*
X778670Y493422D03*
X783600Y502462D03*
X783450Y522462D03*
X783400Y511902D03*
X789720Y589862D03*
X785220Y581362D03*
X789720Y587362D03*
X791720Y593862D03*
X793720Y595862D03*
X791969Y618384D03*
X794720Y617862D03*
X783507Y761875D03*
X794157Y761295D03*
X782515Y766702D03*
X791140Y761693D03*
X792045Y1284542D03*
Y1290542D03*
Y1287542D03*
X791905Y1293272D03*
X791260Y1388662D03*
X790380Y1432132D03*
X784352Y1568293D03*
Y1565293D03*
Y1559293D03*
Y1562293D03*
X781352Y1568293D03*
Y1565293D03*
Y1559293D03*
Y1562293D03*
X793352D03*
Y1559293D03*
Y1565293D03*
Y1568293D03*
X790352Y1562293D03*
Y1559293D03*
Y1565293D03*
Y1568293D03*
X787352D03*
Y1565293D03*
Y1559293D03*
Y1562293D03*
X784352Y1574293D03*
Y1571293D03*
X781352Y1574293D03*
Y1571293D03*
X793352Y1574293D03*
Y1571293D03*
X790352Y1574293D03*
Y1571293D03*
X787352D03*
Y1574293D03*
X788079Y1580393D03*
X782479D03*
X793579D03*
X788079Y1590653D03*
X782479D03*
Y1585523D03*
X793579Y1590653D03*
Y1585523D03*
X785052Y1600693D03*
Y1597693D03*
X782052D03*
Y1600693D03*
X794052D03*
X788052D03*
X791052D03*
X794052Y1597693D03*
X788052D03*
X791052D03*
X785052Y1607793D03*
X782052D03*
X779052D03*
X785052Y1611893D03*
X782052D03*
X779052D03*
X794052Y1607793D03*
X791052D03*
X788052D03*
X797052Y1611893D03*
X794052D03*
X788052D03*
X791052D03*
X785052Y1603693D03*
X782052D03*
X794052D03*
X788052D03*
X791052D03*
X808800Y267900D03*
X810920Y280062D03*
X798204Y279146D03*
X797924Y298358D03*
X806450Y310362D03*
X803620Y302962D03*
X805870Y304812D03*
X799720Y300462D03*
X795920Y312662D03*
X803280Y354982D03*
X800646Y354921D03*
X795220Y354862D03*
X806000Y360600D03*
X798400D03*
X805910Y355012D03*
X797900Y354800D03*
X795520Y398212D03*
X800352Y408389D03*
X803120Y428762D03*
X797720Y428412D03*
X798370Y439932D03*
X802010Y439940D03*
X802790Y433832D03*
X795320Y439862D03*
X805720Y432902D03*
X801750Y444330D03*
X795320Y444862D03*
X810860Y454862D03*
X802810D03*
X795320D03*
Y449862D03*
X802810Y464862D03*
Y449862D03*
X810860Y459862D03*
X802810D03*
X795320D03*
X810860Y449862D03*
X798990Y474862D03*
X802865D03*
X795320Y464862D03*
X810815Y474862D03*
X810860Y464862D03*
X810815Y469862D03*
X807220Y493362D03*
X801940Y485932D03*
X804510Y486122D03*
X809510D03*
X799230Y485922D03*
X812510Y486422D03*
X802790Y495652D03*
X805470Y510522D03*
X807640Y506672D03*
X808100Y509900D03*
X797420Y512503D03*
X805445Y587582D03*
X810720Y586862D03*
X811143Y605265D03*
X807945Y594362D03*
X803220D03*
X797200Y599883D03*
X795720Y614862D03*
X796702Y761195D03*
X810850Y770272D03*
X799577Y760985D03*
X807000Y757562D03*
X798035Y1284612D03*
X795045Y1284542D03*
X798035Y1290612D03*
Y1287612D03*
X795045Y1290542D03*
Y1287542D03*
X797895Y1293342D03*
X794905Y1293272D03*
X806323Y1343076D03*
X812130Y1343022D03*
X809210Y1343062D03*
X804100Y1435010D03*
X800000Y1431100D03*
X799352Y1562293D03*
Y1559293D03*
Y1565293D03*
Y1568293D03*
X796352Y1562293D03*
Y1559293D03*
Y1565293D03*
Y1568293D03*
X799352Y1574293D03*
Y1571293D03*
X796352Y1574293D03*
Y1571293D03*
X804652Y1581793D03*
Y1573793D03*
X812652Y1577793D03*
X801652Y1584539D03*
X812698Y1587047D03*
X804652Y1597793D03*
Y1585993D03*
X799152Y1586507D03*
X804652Y1589793D03*
X797052Y1607793D03*
X804652Y1609793D03*
X827114Y115223D03*
X823114D03*
X814570Y145952D03*
X814531Y139851D03*
X820900Y147112D03*
X815060Y280072D03*
X813490Y273862D03*
X816220Y277162D03*
X813293Y287062D03*
X826300Y311962D03*
X823800D03*
X818000Y378800D03*
X813210Y374292D03*
X815710D03*
X825003Y389012D03*
Y397276D03*
X819220Y397664D03*
X824980Y413260D03*
X819220Y412264D03*
X823600Y421194D03*
X815310Y440100D03*
X816810Y464862D03*
X825100Y468900D03*
X824860Y464862D03*
X816400Y472900D03*
X820720Y493862D03*
X822415Y479600D03*
X821720Y511082D03*
X814305Y499503D03*
X819320Y502347D03*
X821720Y527082D03*
X815650Y516807D03*
X821720Y515082D03*
Y523082D03*
X820220Y586862D03*
X814220Y582530D03*
X823720Y594862D03*
X820470Y595112D03*
X815120Y593582D03*
X820613Y744641D03*
X823589Y746924D03*
X822374Y757039D03*
X814770Y763874D03*
X815789Y1008845D03*
X826090Y1334362D03*
Y1339362D03*
Y1329362D03*
Y1344362D03*
X820920Y1344342D03*
X818420D03*
X823352Y1565293D03*
Y1562293D03*
Y1559293D03*
Y1568293D03*
X826352Y1565293D03*
Y1562293D03*
Y1559293D03*
Y1568293D03*
X823352Y1571293D03*
Y1574293D03*
X826352Y1571293D03*
Y1574293D03*
X824479Y1580393D03*
X815652Y1582570D03*
Y1573793D03*
X813352Y1590893D03*
X812652Y1593793D03*
X824479Y1590653D03*
Y1585523D03*
X824052Y1597693D03*
Y1600693D03*
X827052D03*
Y1597693D03*
X815551Y1593793D03*
X818652Y1590444D03*
X812652Y1605793D03*
X824052Y1611893D03*
Y1607793D03*
Y1603693D03*
X827052Y1611893D03*
Y1607793D03*
Y1603693D03*
X821052Y1611893D03*
Y1607793D03*
X818052Y1611893D03*
X812652Y1601793D03*
X840001Y20200D03*
Y16800D03*
X836779Y68008D03*
X828600Y61752D03*
X839898Y87248D03*
X841584Y94181D03*
X837250Y93221D03*
X839360Y114862D03*
X835114Y115223D03*
X845220Y135862D03*
Y129362D03*
X829114Y147123D03*
X828145Y160362D03*
X838220Y163862D03*
X835220D03*
X837320Y175112D03*
X842720Y181360D03*
X837160Y218212D03*
Y213207D03*
X844526Y204968D03*
X838820Y206872D03*
X837500Y229642D03*
X840063Y285022D03*
X839450Y272662D03*
X835400Y268800D03*
X829620Y280345D03*
X829820Y275045D03*
X840850Y278948D03*
X829720Y292762D03*
X839860Y294702D03*
X827620Y302962D03*
X830417Y311865D03*
X836300Y418800D03*
X832400Y427100D03*
X840400Y418900D03*
X831720Y457700D03*
X839640Y449612D03*
X832700Y446800D03*
X830600Y449200D03*
X838220Y459562D03*
X841200Y456500D03*
X832720Y494862D03*
X829720D03*
X838645Y492862D03*
X830870Y480010D03*
X832590Y512888D03*
X829745Y502082D03*
X832370Y525849D03*
X843287Y527817D03*
X841461Y525849D03*
X840990Y529786D03*
X828009Y587913D03*
X831705Y593877D03*
X829230Y582772D03*
X831530Y651932D03*
X830587Y741205D03*
X833120Y743392D03*
X838587Y766825D03*
X841827Y766795D03*
X837127Y758976D03*
X829420Y758422D03*
X841997Y773085D03*
X838020Y1232432D03*
X832090Y1326862D03*
Y1331862D03*
Y1336862D03*
Y1341862D03*
X829352Y1565293D03*
Y1562293D03*
Y1559293D03*
Y1568293D03*
X832352D03*
Y1565293D03*
Y1559293D03*
Y1562293D03*
X835352Y1568293D03*
Y1565293D03*
Y1559293D03*
Y1562293D03*
X838352Y1568293D03*
Y1565293D03*
Y1559293D03*
Y1562293D03*
X841352Y1568293D03*
Y1565293D03*
Y1559293D03*
Y1562293D03*
X829352Y1574293D03*
Y1571293D03*
X832352D03*
Y1574293D03*
X835352Y1571293D03*
Y1574293D03*
X838352Y1571293D03*
Y1574293D03*
X841352Y1571293D03*
Y1574293D03*
X830079Y1580393D03*
X835579D03*
X843652Y1584539D03*
X833052Y1597693D03*
X836052D03*
X830079Y1590653D03*
X835579D03*
X833052Y1600693D03*
X836052D03*
X835579Y1585523D03*
X830052Y1600693D03*
Y1597693D03*
X841152Y1586507D03*
X833052Y1603693D03*
X836052D03*
X839052Y1611893D03*
X833052Y1607793D03*
Y1611893D03*
X836052Y1607793D03*
Y1611893D03*
X830052D03*
Y1607793D03*
Y1603693D03*
X839052Y1607793D03*
X858629Y60293D03*
X850015Y87341D03*
X843855Y87711D03*
X847472Y94754D03*
X847660Y113962D03*
X853100Y113762D03*
X854100Y132972D03*
X854220Y135862D03*
Y129362D03*
X854200Y138562D03*
X848745Y160187D03*
X848709Y156752D03*
X848360Y182872D03*
X845720Y181362D03*
X855858Y212425D03*
X855933Y215375D03*
X860050Y215310D03*
X847580Y232222D03*
X853828Y269043D03*
X850133Y271049D03*
X861865Y273730D03*
X850093Y286625D03*
X855480Y299692D03*
X856243Y286447D03*
X859920Y308852D03*
X859740Y399081D03*
X846040Y399210D03*
X846490Y422131D03*
X850610Y444352D03*
X851606Y447927D03*
X844210Y455902D03*
X846700Y476900D03*
X855200D03*
X857620Y492862D03*
X858600Y511130D03*
X848620Y509752D03*
X853070Y515447D03*
X857195Y522162D03*
X859888Y593970D03*
X859054Y583752D03*
X845523Y582126D03*
X856520Y751262D03*
X859450Y750462D03*
X844957Y763065D03*
X854620Y1242125D03*
X854237Y1250358D03*
X846652Y1581793D03*
Y1573793D03*
X854652Y1577793D03*
X857652Y1582570D03*
Y1573793D03*
X854777Y1586968D03*
X846652Y1597793D03*
X855352Y1590893D03*
X854652Y1593793D03*
X846652Y1585993D03*
X857551Y1593793D03*
X846652Y1589793D03*
X854652Y1605793D03*
Y1601793D03*
X846652Y1609793D03*
X862930Y70072D03*
X866330D03*
X862452Y151590D03*
X867620Y154362D03*
X871145Y163862D03*
X871580Y183370D03*
X875169Y185113D03*
X864859Y187110D03*
X873200Y194262D03*
X871890Y196740D03*
X877971Y196652D03*
X867528Y231788D03*
X875543Y266447D03*
X867700Y268262D03*
X875543Y269347D03*
X863747Y280870D03*
X867237Y273325D03*
X868552Y285537D03*
X874243Y287047D03*
X877322Y296051D03*
X872320Y304936D03*
X869820D03*
X867320D03*
X864820D03*
X860531Y375826D03*
X870700Y386476D03*
Y398620D03*
Y402581D03*
X868113Y409372D03*
X870513Y414276D03*
X862320Y431462D03*
X863415Y445829D03*
X860574Y445404D03*
X861080Y459742D03*
X870360Y493042D03*
X862620Y507162D03*
X868110Y499142D03*
X865290Y499032D03*
X865810Y521862D03*
X866820Y736562D03*
X863925Y737697D03*
X864680Y751582D03*
X874155Y756993D03*
X864700Y778300D03*
X868352Y1568293D03*
Y1565293D03*
Y1559293D03*
Y1562293D03*
X865352Y1568293D03*
Y1565293D03*
Y1559293D03*
Y1562293D03*
X874352D03*
Y1559293D03*
Y1565293D03*
Y1568293D03*
X871352D03*
Y1565293D03*
Y1559293D03*
Y1562293D03*
X868352Y1574293D03*
Y1571293D03*
X865352Y1574293D03*
Y1571293D03*
X874352Y1574293D03*
Y1571293D03*
X871352D03*
Y1574293D03*
X866479Y1580393D03*
X872079D03*
X866052Y1597693D03*
X869052D03*
X866479Y1590653D03*
X869052Y1600693D03*
X866052D03*
X872052Y1597693D03*
X872079Y1590653D03*
X872052Y1600693D03*
X866479Y1585523D03*
X875052Y1597693D03*
Y1600693D03*
X860652Y1590444D03*
X869052Y1603693D03*
X866052D03*
X872052D03*
X869052Y1607793D03*
Y1611893D03*
X866052Y1607793D03*
X863052Y1611893D03*
X866052D03*
X872052Y1607793D03*
Y1611893D03*
X875052Y1603693D03*
Y1607793D03*
Y1611893D03*
X863052Y1607793D03*
X860052Y1611893D03*
X878327Y183169D03*
X876695Y171362D03*
Y176862D03*
X887520Y171362D03*
Y176862D03*
X877724Y200837D03*
X878220Y187449D03*
X888929Y209223D03*
X891620Y209662D03*
X888929Y206723D03*
X891620Y207162D03*
X884003Y278712D03*
X883870Y275802D03*
X883909Y281862D03*
X879587Y270004D03*
X883870Y272652D03*
X887338Y296760D03*
X882520Y327562D03*
X885020D03*
X887520D03*
X890422Y333879D03*
X893440Y336232D03*
X890820Y389362D03*
X890920Y386352D03*
X889453Y458926D03*
X887590Y471552D03*
X889439Y489599D03*
Y492999D03*
X881680Y504742D03*
Y508142D03*
X884512Y523800D03*
X882410Y526132D03*
X888130Y532612D03*
X891530D03*
X887810Y582442D03*
X889000Y737562D03*
X885310Y736442D03*
X886720Y741902D03*
X878192Y879910D03*
X884747Y871745D03*
X879100Y912608D03*
X884619Y916477D03*
X892317Y915872D03*
X880102Y923235D03*
X891560Y1435510D03*
X883352Y1562293D03*
Y1559293D03*
Y1565293D03*
Y1568293D03*
X880352Y1562293D03*
Y1559293D03*
Y1565293D03*
Y1568293D03*
X877352Y1562293D03*
Y1559293D03*
Y1565293D03*
Y1568293D03*
X883352Y1574293D03*
Y1571293D03*
X880352Y1574293D03*
Y1571293D03*
X877352Y1574293D03*
Y1571293D03*
X888652Y1581793D03*
Y1573793D03*
X877579Y1580393D03*
X885652Y1584539D03*
X888652Y1597793D03*
Y1585993D03*
X877579Y1585523D03*
X878052Y1597693D03*
Y1600693D03*
X877579Y1590653D03*
X883152Y1586507D03*
X888652Y1589793D03*
X878052Y1603693D03*
Y1607793D03*
X881052Y1611893D03*
X878052D03*
X881052Y1607793D03*
X888652Y1609793D03*
X908620Y188899D03*
X896620Y209662D03*
X894120D03*
Y207162D03*
X896620D03*
X902350Y208294D03*
X907470Y211980D03*
X902350Y204894D03*
X907470Y215380D03*
X902350Y219068D03*
X907470Y226154D03*
X902350Y222468D03*
X907470Y229554D03*
X906120Y261252D03*
X894770Y283062D03*
X896540Y341132D03*
X902260Y473153D03*
Y475653D03*
X903124Y470797D03*
X900020Y470672D03*
X896060Y481222D03*
Y484622D03*
X907678Y488177D03*
X895340Y497882D03*
Y501282D03*
X901829Y512730D03*
Y516130D03*
X893450Y516862D03*
X901230Y531612D03*
X904630D03*
X894897Y871745D03*
X894965Y917422D03*
X899830Y971484D03*
Y974884D03*
X907770Y1045242D03*
X894830Y1435970D03*
X907352Y1568293D03*
Y1565293D03*
Y1559293D03*
Y1562293D03*
Y1574293D03*
Y1571293D03*
X908479Y1580393D03*
X896652Y1577793D03*
X899652Y1582570D03*
Y1573793D03*
X896672Y1587073D03*
X897352Y1590893D03*
X896652Y1593793D03*
X908479Y1590653D03*
Y1585523D03*
X908052Y1600693D03*
Y1597693D03*
X899551Y1593793D03*
X902652Y1590444D03*
X896652Y1605793D03*
X908052Y1611893D03*
X905052D03*
X902052D03*
X908052Y1607793D03*
X905052D03*
X908052Y1603693D03*
X896652Y1601793D03*
X922726Y176302D03*
X922100Y181791D03*
X917386Y184114D03*
X924920Y196199D03*
X923836Y193563D03*
X923897Y445545D03*
X927034Y445594D03*
X912984Y458135D03*
X909584D03*
X924447Y463012D03*
X921047D03*
X909190Y473392D03*
X912288Y472430D03*
X918532Y492445D03*
X927154Y492103D03*
X924623Y492097D03*
X918078Y495177D03*
X921189Y492086D03*
X918212Y497677D03*
X918131Y503330D03*
X921060Y506086D03*
X923783Y506076D03*
X918212Y500777D03*
X909984Y496330D03*
X926173Y512391D03*
X913394Y521662D03*
X916794D03*
X909600Y521162D03*
X922879Y531976D03*
Y528576D03*
X918420Y804062D03*
X909720Y798861D03*
Y794862D03*
X913720Y799362D03*
X914152Y803294D03*
X921757Y962082D03*
X916974Y962108D03*
X923930Y976652D03*
X917980Y974952D03*
X924440Y996852D03*
X914838Y985989D03*
X918720Y1009937D03*
X910352Y1568293D03*
Y1565293D03*
Y1559293D03*
Y1562293D03*
X922352D03*
Y1559293D03*
Y1565293D03*
Y1568293D03*
X919352Y1562293D03*
Y1559293D03*
Y1565293D03*
Y1568293D03*
X916352Y1562293D03*
Y1559293D03*
Y1565293D03*
Y1568293D03*
X913352D03*
Y1565293D03*
Y1559293D03*
Y1562293D03*
X910352Y1574293D03*
Y1571293D03*
X922352Y1574293D03*
Y1571293D03*
X919352Y1574293D03*
Y1571293D03*
X916352Y1574293D03*
Y1571293D03*
X913352D03*
Y1574293D03*
X919579Y1580393D03*
X914079D03*
X919579Y1590653D03*
X914079D03*
X919579Y1585523D03*
X917052Y1600693D03*
Y1597693D03*
X914052Y1600693D03*
Y1597693D03*
X911052Y1600693D03*
Y1597693D03*
X920052Y1600693D03*
Y1597693D03*
X917052Y1611893D03*
X914052D03*
X911052D03*
X917052Y1607793D03*
X914052D03*
X911052D03*
X920052Y1611893D03*
X923052D03*
Y1607793D03*
X920052D03*
X917052Y1603693D03*
X914052D03*
X911052D03*
X920052D03*
X919488Y1660733D03*
X918020Y1672860D03*
X914500Y1671400D03*
X938160Y173389D03*
X935550Y173329D03*
X940720Y173389D03*
X938160Y176389D03*
X935550Y176329D03*
X940720Y176389D03*
X940424Y184190D03*
X936424D03*
X935770Y191419D03*
X939270D03*
X940410Y188852D03*
X930472Y246093D03*
X938603Y240063D03*
X933122Y246115D03*
X933686Y242922D03*
X935454Y241154D03*
X933217Y380693D03*
Y384693D03*
X941059Y427911D03*
Y424511D03*
X937447Y457862D03*
X934047D03*
X928394Y472201D03*
Y474701D03*
X932373Y495175D03*
X932089Y492691D03*
X929654Y492103D03*
X932218Y499314D03*
X939872Y495813D03*
X932089Y505986D03*
X932289Y502986D03*
X926637Y506069D03*
X929281Y506086D03*
X931720Y524862D03*
X940550Y517400D03*
X940140Y514925D03*
X933773Y530479D03*
X930731D03*
X941050Y532252D03*
Y528852D03*
X938742Y803831D03*
X931573Y816109D03*
X927470Y815112D03*
X935052Y812630D03*
X934260Y808312D03*
X938371Y809311D03*
X930786Y811785D03*
X925220Y817862D03*
X928237Y824844D03*
X926469Y826612D03*
X926823Y962082D03*
X940170Y962842D03*
X939740Y987762D03*
X936998Y985750D03*
X932310Y996812D03*
X927220Y1012362D03*
X931220D03*
X925352Y1562293D03*
Y1559293D03*
Y1565293D03*
Y1568293D03*
Y1574293D03*
Y1571293D03*
X938652Y1581393D03*
X928152Y1584539D03*
X938652Y1593393D03*
Y1585393D03*
X925152Y1586507D03*
X938652Y1589393D03*
X933979Y1661327D03*
X929979Y1661352D03*
X942100Y1671100D03*
X945720Y173389D03*
X943220D03*
X945720Y176389D03*
X943220D03*
X948400Y176499D03*
X949120Y184912D03*
X944250Y194489D03*
Y197889D03*
X957020Y193299D03*
X949550Y192819D03*
X957020Y264862D03*
X953046Y390103D03*
X951181Y391916D03*
X950660Y399472D03*
X956487Y394831D03*
X949920Y404602D03*
X944032Y437631D03*
Y434231D03*
X945447Y463012D03*
X942047D03*
X946727Y507952D03*
Y504552D03*
X954420Y511252D03*
Y500552D03*
Y497152D03*
Y514652D03*
X954390Y527596D03*
X945524Y515483D03*
X944261Y517871D03*
X941740Y512922D03*
X942610Y515350D03*
X945100Y534464D03*
X955123Y533642D03*
X948415Y534313D03*
X956518Y531567D03*
X957220Y582862D03*
X953594Y787477D03*
X954447Y791735D03*
X951043Y796140D03*
X950190Y791382D03*
X944272Y803410D03*
X943366Y798707D03*
X946786Y795287D03*
X947921Y799761D03*
X944170Y962842D03*
X949560Y981392D03*
X951560Y997422D03*
X956980Y1536260D03*
X953980D03*
X950980D03*
X947980D03*
X944980D03*
Y1551260D03*
X947980D03*
X950980D03*
X953980D03*
X956980D03*
X944980Y1548260D03*
X947980D03*
X950980D03*
X953980D03*
X956980D03*
X944980Y1545260D03*
X947980D03*
X950980D03*
X953980D03*
X956980D03*
X944980Y1542260D03*
X947980D03*
X950980D03*
X953980D03*
X956980D03*
Y1539260D03*
X953980D03*
X950980D03*
X947980D03*
X944980D03*
Y1554260D03*
X947980D03*
X950980D03*
X953980D03*
X956980D03*
X956800Y1663725D03*
X956600Y1666875D03*
X962604Y165313D03*
X962458Y162398D03*
X965150Y193412D03*
X966720Y198099D03*
X970720D03*
X961120Y193299D03*
X968384Y242051D03*
X965884D03*
X960020Y264862D03*
X963020D03*
X962570Y282812D03*
X962882Y314512D03*
X967239Y320073D03*
X963854Y320113D03*
X963300Y347962D03*
X962623Y350642D03*
X970730Y377872D03*
X972220Y386251D03*
Y390239D03*
X975670Y392063D03*
X963856Y398302D03*
X965890Y405967D03*
X963720Y439862D03*
X961320Y476242D03*
X968286Y483941D03*
Y480541D03*
X964347Y509462D03*
X970788Y501230D03*
X964347Y501262D03*
X969351Y512416D03*
X957790Y527596D03*
X963930Y533362D03*
X967330D03*
X959351Y533566D03*
X960920Y644762D03*
Y649762D03*
Y654762D03*
X963720Y647262D03*
Y657262D03*
Y652262D03*
X960820Y665062D03*
X960920Y659762D03*
X963720Y662262D03*
X967750Y1376460D03*
X969000Y1536262D03*
X971700D03*
X969000Y1548262D03*
X971700D03*
X969000Y1545262D03*
X971700D03*
X969000Y1551262D03*
X971700D03*
Y1542262D03*
X969000D03*
X971700Y1539262D03*
X969000D03*
X965904Y1554364D03*
X960904D03*
X969000Y1554262D03*
X971700D03*
X965622Y1579240D03*
Y1576240D03*
Y1573240D03*
X966852Y1585920D03*
X969852D03*
X960852D03*
X963852D03*
X957852D03*
X965086Y1603984D03*
X962086D03*
X980899Y-13200D03*
Y-9800D03*
Y20200D03*
Y16800D03*
X990501Y152397D03*
X986369Y155358D03*
X975690Y157220D03*
X983811Y156694D03*
X985499Y168753D03*
X985431Y181058D03*
X990115Y173039D03*
X987320Y194599D03*
Y198099D03*
Y201599D03*
X977220Y201399D03*
X986020Y191099D03*
X981795Y216623D03*
X978012Y276436D03*
X975512Y282096D03*
X978012D03*
X975512Y279266D03*
X978012D03*
X981470Y268532D03*
X979940Y292262D03*
Y289762D03*
X975512Y294996D03*
X978012D03*
X979940Y284762D03*
Y287262D03*
X988818Y346372D03*
X978000Y362462D03*
X988723Y369650D03*
X991934Y368443D03*
X988908Y373392D03*
X986400Y383123D03*
X983770Y373962D03*
X979766Y377507D03*
X977949Y384205D03*
X980916Y384286D03*
X980856Y392502D03*
X986955Y391939D03*
X983629Y397628D03*
X979559Y399362D03*
X983970Y392562D03*
X991369Y408252D03*
X979240Y425212D03*
X984254Y418379D03*
X987440Y431193D03*
X980720Y512362D03*
X986400Y503200D03*
X986273Y532996D03*
X980535Y532643D03*
X986418Y530019D03*
X975900Y1265062D03*
X987920Y1290662D03*
X985320Y1288762D03*
X992306Y1295049D03*
X979373Y1342724D03*
X974700Y1536262D03*
X980400D03*
X977700D03*
X974700Y1548262D03*
Y1545262D03*
Y1551262D03*
X980400Y1548262D03*
X977700D03*
X980400Y1545262D03*
X977700D03*
X980400Y1551262D03*
X977700D03*
Y1542262D03*
X980400D03*
X974700D03*
X977700Y1539262D03*
X980400D03*
X974700D03*
X984270Y1554364D03*
X974700Y1554262D03*
X980400D03*
X977700D03*
X989270Y1554364D03*
X988988Y1579240D03*
Y1573240D03*
Y1576240D03*
X995000Y150883D03*
X1001500D03*
X995180Y153689D03*
X1006220Y160799D03*
X1002720D03*
X1001101Y165510D03*
X999220Y185299D03*
X1002720D03*
X1006220D03*
X996415Y172579D03*
X1002920Y174799D03*
X990220Y195699D03*
Y199199D03*
X1008120Y198293D03*
X990195Y216823D03*
X990220Y202699D03*
X1000610Y211039D03*
X1005640Y210969D03*
X1001195Y219898D03*
X1005120Y230399D03*
X994743Y289843D03*
X1006232Y343983D03*
X1001440Y359702D03*
X994689Y379348D03*
X1006201Y370004D03*
X999440Y371782D03*
X996922Y367764D03*
X994322Y404090D03*
X1005123Y414662D03*
X997617Y412383D03*
X997394Y415578D03*
X993012Y421570D03*
X997225Y419162D03*
X990840Y431193D03*
X1005720Y498862D03*
X1003220Y512862D03*
X1005520Y510932D03*
X991237Y533043D03*
X1008560Y589682D03*
X1005960Y594682D03*
X1005373Y748826D03*
X995120Y773122D03*
X994942Y777055D03*
X996320Y1280683D03*
Y1284062D03*
X997920Y1278762D03*
X994574Y1297318D03*
X995066Y1536262D03*
X992466D03*
X1001066D03*
X1003766D03*
X998066D03*
X995066Y1551262D03*
X992466D03*
X995066Y1545262D03*
X992466D03*
X995066Y1548262D03*
X992466D03*
X1001066Y1551262D03*
X1003766D03*
X1001066Y1545262D03*
X1003766D03*
X1001066Y1548262D03*
X1003766D03*
X998066Y1551262D03*
Y1545262D03*
Y1548262D03*
Y1542262D03*
X1003766D03*
X1001066D03*
X992466D03*
X995066D03*
X998066Y1539262D03*
X1003766D03*
X1001066D03*
X992466D03*
X995066D03*
X1007636Y1554364D03*
X995066Y1554262D03*
X992466D03*
X1001066D03*
X1003766D03*
X998066D03*
X1002782Y1585920D03*
X999782D03*
X996782D03*
X990782D03*
X993782D03*
X996698Y1604000D03*
X993698D03*
X1008129Y150948D03*
X1009720Y160799D03*
X1013220D03*
X1012791Y157596D03*
X1012000Y185299D03*
X1014900D03*
X1017800D03*
X1017200Y175699D03*
X1014300D03*
X1019900Y175799D03*
X1020645Y190499D03*
X1011320Y202169D03*
X1019355Y218423D03*
X1019802Y214099D03*
X1010005Y208424D03*
X1011720Y229699D03*
X1019355Y222423D03*
X1019530Y226423D03*
X1007820Y229999D03*
X1021118Y294290D03*
X1020720Y310937D03*
X1015520Y302862D03*
X1009800Y343800D03*
X1021695Y364518D03*
X1006710Y372931D03*
X1015096Y373758D03*
X1017163Y367963D03*
X1009883Y367955D03*
X1010420Y416062D03*
X1015420Y410862D03*
X1009009Y419948D03*
X1021239Y416974D03*
X1016261Y432888D03*
X1012861D03*
X1024200Y510362D03*
X1018092Y520212D03*
X1020392Y521826D03*
X1016360Y594682D03*
X1016220Y590862D03*
X1019000Y601042D03*
X1021654Y606302D03*
X1011160Y594682D03*
X1007873Y748826D03*
X1007600Y1298250D03*
X1007610Y1295040D03*
X1021612Y1536262D03*
X1016012D03*
X1018612D03*
Y1551262D03*
X1016012D03*
X1018612Y1545262D03*
X1016012D03*
X1018612Y1548262D03*
X1016012D03*
X1021612Y1551262D03*
Y1545262D03*
Y1548262D03*
X1018612Y1542262D03*
X1016012D03*
X1021612D03*
Y1539262D03*
X1016012D03*
X1018612D03*
Y1554262D03*
X1016012D03*
X1021612D03*
X1012636Y1554364D03*
X1012354Y1579240D03*
Y1573240D03*
Y1576240D03*
X1021942Y1586090D03*
X1026620Y125662D03*
X1034229Y128953D03*
X1032894Y155185D03*
X1022800Y175799D03*
X1037618Y261200D03*
X1031702Y264130D03*
X1025862Y291727D03*
X1032317Y291284D03*
X1036278Y303993D03*
Y307393D03*
X1033285Y353627D03*
X1029395Y375844D03*
X1025004Y374662D03*
X1031950Y383771D03*
Y387171D03*
X1031153Y390152D03*
X1026820Y394362D03*
X1038320Y407062D03*
Y404462D03*
X1026548Y400571D03*
X1035920Y420062D03*
Y417462D03*
X1026370Y503562D03*
X1032155Y509737D03*
X1025530Y519627D03*
X1033040Y519852D03*
X1038130Y518417D03*
X1040720Y591862D03*
X1024154Y601152D03*
X1029630Y601252D03*
X1026654Y596152D03*
X1035760Y592952D03*
X1033260Y601272D03*
X1038260D03*
X1033817Y735612D03*
X1036954Y734669D03*
X1030660Y735082D03*
X1027212Y1536262D03*
X1024612D03*
Y1551262D03*
X1027212D03*
X1024612Y1545262D03*
X1027212D03*
X1024612Y1548262D03*
X1027212D03*
X1024612Y1542262D03*
X1027212D03*
Y1539262D03*
X1024612D03*
X1031002Y1554364D03*
X1024612Y1554262D03*
X1027212D03*
X1036002Y1554364D03*
X1035720Y1579240D03*
Y1573240D03*
Y1576240D03*
X1030942Y1586090D03*
X1033942D03*
X1024942D03*
X1027942D03*
X1028298Y1604000D03*
X1025298D03*
X1040970Y128332D03*
X1043720Y363462D03*
X1054820Y370162D03*
X1044120Y366362D03*
X1040120Y393962D03*
X1042720D03*
X1041420Y443962D03*
X1043920D03*
X1050470Y447062D03*
X1041444Y506504D03*
X1053690Y520760D03*
X1045720Y591672D03*
X1043260Y601272D03*
X1045760Y596272D03*
X1048260Y601272D03*
X1051680Y614772D03*
X1053745Y742341D03*
X1053354Y1286714D03*
Y1291714D03*
X1039510Y1296655D03*
X1049510D03*
X1044510D03*
X1039510Y1293155D03*
X1049510D03*
X1044510D03*
X1053354Y1296714D03*
X1041798Y1536262D03*
X1047798D03*
X1050498D03*
X1044798D03*
X1039298D03*
X1041798Y1551262D03*
X1039298D03*
X1041798Y1545262D03*
X1039298D03*
X1041798Y1548262D03*
X1039298D03*
X1047798Y1551262D03*
X1050498D03*
X1047798Y1545262D03*
X1050498D03*
X1047798Y1548262D03*
X1050498D03*
X1044798Y1551262D03*
Y1545262D03*
Y1548262D03*
X1039298Y1542262D03*
X1044798D03*
X1050498D03*
X1047798D03*
X1041798D03*
X1044798Y1539262D03*
X1050498D03*
X1047798D03*
X1039298D03*
X1041798D03*
X1054368Y1554364D03*
X1041798Y1554262D03*
X1039298D03*
X1047798D03*
X1050498D03*
X1044798D03*
X1053612Y1586010D03*
X1056898Y1604000D03*
X1067220Y145362D03*
Y142862D03*
Y148362D03*
X1059943Y435314D03*
X1062120Y477462D03*
X1056190Y520760D03*
X1058220Y585862D03*
X1061470D03*
X1056220Y605052D03*
X1055205Y744853D03*
X1063354Y1286714D03*
X1058354D03*
X1063354Y1291714D03*
X1058354D03*
X1063354Y1296714D03*
X1058290Y1296302D03*
X1071179Y1294669D03*
X1066462Y1520088D03*
X1065164Y1536262D03*
X1062464D03*
X1071164D03*
X1068164D03*
X1065164Y1551262D03*
X1062464D03*
X1065164Y1545262D03*
X1062464D03*
X1065164Y1548262D03*
X1062464D03*
X1071164Y1551262D03*
Y1545262D03*
Y1548262D03*
X1068164Y1551262D03*
Y1545262D03*
Y1548262D03*
Y1542262D03*
X1071164D03*
X1062464D03*
X1065164D03*
X1068164Y1539262D03*
X1071164D03*
X1062464D03*
X1065164D03*
Y1554262D03*
X1062464D03*
X1071164D03*
X1068164D03*
X1059368Y1554364D03*
X1059086Y1579240D03*
Y1573240D03*
Y1576240D03*
X1062612Y1586010D03*
X1065612D03*
X1056612D03*
X1059612D03*
X1059898Y1604000D03*
X1071920Y53862D03*
X1079114Y75775D03*
X1080168Y90721D03*
X1081282Y180937D03*
X1086756Y187540D03*
X1077973Y246362D03*
X1083973D03*
X1080973D03*
X1077883Y260842D03*
X1076823Y265438D03*
X1083823D03*
X1083883Y260842D03*
X1080883D03*
X1080323Y265438D03*
X1082853Y269492D03*
X1079853D03*
X1075400Y273762D03*
X1078400D03*
X1081400D03*
X1084400D03*
X1087400D03*
X1076018Y289400D03*
X1079018D03*
X1082018D03*
X1085018D03*
X1084130Y298342D03*
X1086630D03*
X1076353Y363966D03*
X1078853D03*
X1087330Y369061D03*
Y374131D03*
Y379251D03*
X1075462Y386723D03*
X1078151Y413911D03*
X1078120Y411262D03*
X1084245Y435437D03*
X1078545Y435637D03*
X1081045D03*
X1087280Y435437D03*
X1076598Y477087D03*
X1081930Y477132D03*
X1079320Y473892D03*
X1076820D03*
X1073589Y506461D03*
X1082220Y522362D03*
X1085720Y522422D03*
X1073250Y582332D03*
X1084637Y744635D03*
X1083714Y1285144D03*
Y1288144D03*
Y1291144D03*
X1077634Y1294869D03*
X1074387Y1294652D03*
X1074010Y1510650D03*
X1073864Y1536262D03*
X1085830D03*
X1073864Y1551262D03*
Y1545262D03*
Y1548262D03*
X1085830Y1551262D03*
Y1545262D03*
Y1548262D03*
Y1542262D03*
X1073864D03*
X1085830Y1539262D03*
X1073864D03*
X1077734Y1554364D03*
X1073864Y1554262D03*
X1085830D03*
X1082734Y1554364D03*
X1084000Y1647110D03*
X1094644Y67992D03*
X1090279Y126524D03*
X1105580Y132822D03*
X1100630Y130376D03*
X1099030Y245140D03*
X1088018Y289400D03*
X1089130Y298342D03*
X1091630D03*
X1094130D03*
X1089660Y408560D03*
X1095820Y420762D03*
X1090245Y435437D03*
X1093497Y744655D03*
X1089714Y1285144D03*
X1105480Y1517982D03*
X1088530Y1536262D03*
X1091530D03*
X1088530Y1551262D03*
Y1545262D03*
Y1548262D03*
X1094530Y1551262D03*
X1097230D03*
X1094530Y1545262D03*
X1097230D03*
X1094530Y1548262D03*
X1097230D03*
X1091530Y1551262D03*
Y1545262D03*
Y1548262D03*
Y1542262D03*
X1097230D03*
X1094530D03*
X1088530D03*
X1091530Y1539262D03*
X1094530D03*
X1088530D03*
X1101600Y1554364D03*
X1104750Y1549346D03*
X1088530Y1554262D03*
X1094530D03*
X1097230D03*
X1091530D03*
X1092302Y1585650D03*
X1089302D03*
X1098302D03*
X1095302D03*
X1095436Y1603944D03*
X1092436D03*
X1088790Y1641830D03*
X1094225Y1671710D03*
X1091880Y1673720D03*
X1110977Y55505D03*
X1110754Y60028D03*
X1113594Y69862D03*
X1109020Y80592D03*
X1118309Y111687D03*
X1115860Y113883D03*
X1118486Y208942D03*
X1111918Y234718D03*
X1109088Y234668D03*
X1111918Y237718D03*
Y240718D03*
X1109088Y237668D03*
Y240668D03*
X1120190Y255652D03*
X1117820Y456132D03*
X1113207Y744455D03*
X1115853Y1426342D03*
Y1435532D03*
X1114400Y1518237D03*
X1110725Y1518046D03*
X1113725Y1530935D03*
X1115802Y1615010D03*
X1117407Y1628495D03*
X1113990Y1631370D03*
X1113325Y1627975D03*
X1117182Y1625460D03*
X1106480Y1641275D03*
X1113110Y1666460D03*
X1108320Y1680200D03*
X1112130Y1711600D03*
X1112252Y1706170D03*
X1112200Y1709000D03*
X1114150Y1715726D03*
X1110663Y1719189D03*
X1119200Y1730300D03*
Y1727200D03*
X1114300Y1722700D03*
X1119300Y1724100D03*
X1132547Y64864D03*
X1129997Y69864D03*
X1122278Y107549D03*
X1120420Y109829D03*
X1124858Y197309D03*
X1128485Y198159D03*
X1133041Y194137D03*
X1124360Y259712D03*
X1125409Y305797D03*
X1122059Y305673D03*
X1124985Y302578D03*
X1127402Y456174D03*
X1136051Y503324D03*
X1124120Y643762D03*
X1136720Y641362D03*
X1133720Y642862D03*
X1129420Y644062D03*
X1122980Y741312D03*
X1127972Y747250D03*
X1135750Y1255672D03*
X1127179Y1372700D03*
X1124679D03*
Y1370200D03*
X1127179D03*
X1129729Y1372700D03*
Y1370200D03*
Y1375200D03*
X1127179D03*
X1124679D03*
X1129729Y1377700D03*
Y1380200D03*
Y1385200D03*
Y1382700D03*
X1127179D03*
X1124679D03*
X1127179Y1380200D03*
Y1377700D03*
X1124679D03*
Y1380200D03*
Y1385200D03*
X1127179D03*
X1122879Y1431474D03*
Y1434024D03*
X1125995Y1439780D03*
X1123379Y1443583D03*
X1133169Y1445690D03*
X1129169Y1442998D03*
X1135568Y1442923D03*
X1129169Y1445719D03*
X1130841Y1462953D03*
X1128341Y1465453D03*
Y1462953D03*
X1130841Y1465453D03*
X1133841Y1462953D03*
Y1465453D03*
X1128341Y1468453D03*
X1130841D03*
X1133841D03*
X1128341Y1460453D03*
X1130841D03*
X1133841D03*
Y1471453D03*
X1130841D03*
X1128341D03*
X1132187Y1582738D03*
X1135187D03*
X1132187Y1590738D03*
X1135187D03*
X1124862Y1615010D03*
X1140242Y101135D03*
X1152720Y180862D03*
X1148795Y213731D03*
X1141957Y227277D03*
X1144457D03*
X1139457D03*
X1146670Y230110D03*
X1147700Y362731D03*
X1137315Y379592D03*
X1147700Y368041D03*
X1138551Y503324D03*
X1144720Y501362D03*
Y498662D03*
X1142967Y592097D03*
X1138500Y586362D03*
X1142127Y586452D03*
X1140697Y608762D03*
X1150140Y610362D03*
X1144810Y613762D03*
X1142674Y1287608D03*
X1144247Y1372700D03*
Y1370200D03*
X1146797Y1372700D03*
X1149297D03*
X1146797Y1370200D03*
X1149297D03*
X1144247Y1375200D03*
X1146797D03*
X1149297D03*
X1144247Y1377700D03*
Y1380200D03*
Y1385200D03*
Y1382700D03*
X1146797D03*
X1149297D03*
X1146797Y1380200D03*
Y1377700D03*
X1149297Y1380200D03*
Y1377700D03*
Y1385200D03*
X1146797D03*
X1146563Y1436334D03*
X1141903D03*
X1144233Y1435584D03*
X1139573D03*
X1149469Y1437098D03*
X1151669Y1435698D03*
Y1438598D03*
X1137311Y1445191D03*
X1147203Y1441968D03*
X1149569Y1440098D03*
X1151669Y1441498D03*
X1147203Y1439068D03*
X1141591Y1462853D03*
Y1465353D03*
Y1468353D03*
Y1471353D03*
Y1460353D03*
X1150821Y1459607D03*
Y1456587D03*
X1138430Y1524150D03*
X1151497Y1524187D03*
X1153465Y1550301D03*
X1149528D03*
X1145410Y1540640D03*
X1143060Y1538380D03*
X1141654Y1550301D03*
X1137717Y1558020D03*
X1141690Y1552920D03*
X1152187Y1574738D03*
X1142187D03*
X1145187D03*
X1142187Y1582738D03*
X1145187D03*
X1152187D03*
X1141525Y1597630D03*
X1152187Y1590738D03*
X1142187D03*
X1145187D03*
X1140750Y1604330D03*
X1150380Y1602590D03*
X1146960Y1618960D03*
X1152257Y1628910D03*
X1155703Y73679D03*
X1165440Y176450D03*
X1168710Y176590D03*
X1159460Y194090D03*
X1160630Y213870D03*
X1159753Y361281D03*
X1159460Y366025D03*
X1156790Y363231D03*
X1161690Y374110D03*
X1164320Y451062D03*
X1156100Y456342D03*
X1167190Y526922D03*
X1158300Y585862D03*
X1170740Y602132D03*
X1155962Y746193D03*
X1156609Y1286685D03*
X1165279Y1372700D03*
X1162779D03*
X1167829D03*
X1162779Y1370200D03*
X1165279D03*
X1167829D03*
X1162779Y1375200D03*
X1165279D03*
X1167829D03*
Y1377700D03*
Y1380200D03*
Y1385200D03*
Y1382700D03*
X1165279D03*
X1162779D03*
X1165279Y1380200D03*
X1162779D03*
Y1377700D03*
X1165279D03*
X1162779Y1385200D03*
X1165279D03*
X1161022Y1431499D03*
Y1433999D03*
X1164138Y1439780D03*
X1154288Y1432502D03*
X1161522Y1443630D03*
X1167312Y1442998D03*
Y1445964D03*
X1159386Y1464253D03*
Y1466753D03*
X1156386Y1464253D03*
Y1466753D03*
X1159386Y1469253D03*
X1156386D03*
X1153821Y1459607D03*
Y1456587D03*
X1159386Y1461753D03*
X1159476Y1458918D03*
X1156386Y1461753D03*
X1156476Y1458918D03*
X1159446Y1456113D03*
X1156446D03*
X1167245Y1524187D03*
X1159371D03*
X1163308D03*
X1155433D03*
X1165276Y1550301D03*
X1169213D03*
X1157402D03*
X1161339D03*
X1161595Y1574738D03*
X1164595D03*
X1155187D03*
X1161595Y1582738D03*
X1164595D03*
X1155187D03*
X1163079Y1601479D03*
X1161595Y1590738D03*
X1164595D03*
X1155187D03*
X1169460Y1606630D03*
Y1616630D03*
Y1611630D03*
X1158030Y1619250D03*
X1164830Y1628830D03*
X1163970Y1620600D03*
X1169325Y1642600D03*
X1158325D03*
X1162383Y1652505D03*
X1164830Y1654632D03*
X1159930D03*
X1161076Y1680624D03*
X1157700Y1681100D03*
X1174120Y57111D03*
X1175926Y69151D03*
X1180676Y106858D03*
X1187413Y143132D03*
X1181420Y157962D03*
X1181700Y186962D03*
X1173314Y176452D03*
X1170595Y170056D03*
X1181476Y172247D03*
X1184510Y188962D03*
X1173100Y186962D03*
X1172925Y202174D03*
X1181369Y199234D03*
X1183460Y205342D03*
X1181470Y208802D03*
X1172835Y218174D03*
X1181500Y211962D03*
Y218462D03*
Y215962D03*
Y222162D03*
X1186653Y302242D03*
X1181450Y306052D03*
X1174120Y355362D03*
X1169690Y526922D03*
X1172310Y584562D03*
X1181300Y584762D03*
X1177570Y602052D03*
X1175217Y595762D03*
X1173020Y745972D03*
X1175573Y1286765D03*
X1172573D03*
X1182747Y1372700D03*
X1185297D03*
X1182747Y1370200D03*
X1185297D03*
X1182747Y1375200D03*
X1185297D03*
X1182747Y1380200D03*
Y1377700D03*
Y1385200D03*
Y1382700D03*
X1185297D03*
Y1377700D03*
Y1380200D03*
Y1385200D03*
X1184706Y1436334D03*
X1180046D03*
X1182376Y1435584D03*
X1177716D03*
X1171342Y1445650D03*
X1175454Y1445191D03*
X1173711Y1442923D03*
X1171182Y1524187D03*
X1184330Y1573260D03*
X1184290Y1570080D03*
X1171595Y1574738D03*
X1174595D03*
X1171595Y1582738D03*
X1174595D03*
X1183410Y1594450D03*
X1183440Y1591640D03*
X1171595Y1590738D03*
X1174595D03*
X1178140Y1601100D03*
X1184200Y1599900D03*
X1183320Y1597080D03*
X1169968Y1602370D03*
X1174550Y1615630D03*
X1178250Y1609100D03*
X1184200Y1602700D03*
X1185030Y1624660D03*
X1180325Y1642600D03*
X1173383Y1652505D03*
X1184383D03*
X1181930Y1654632D03*
X1175830D03*
X1170930D03*
X1183076Y1680624D03*
X1172076D03*
X1194478Y56986D03*
X1197520Y56962D03*
X1201158Y57130D03*
X1189393Y60183D03*
X1188700Y100700D03*
X1185400Y104000D03*
X1193532Y132644D03*
X1194800Y143112D03*
X1197414Y161592D03*
X1191020Y170862D03*
X1185420Y153762D03*
X1200720Y184862D03*
X1188300Y189062D03*
X1200720Y187862D03*
X1200963Y212648D03*
X1200830Y206002D03*
X1186340Y204492D03*
X1187300Y217862D03*
X1188500Y205772D03*
X1188600Y225962D03*
X1187013Y238972D03*
X1194840Y236592D03*
X1199720Y252362D03*
X1196720D03*
X1188810Y296088D03*
X1186280Y298972D03*
X1193198Y586172D03*
X1195698D03*
X1198198D03*
X1200698D03*
X1185687Y744475D03*
X1187797Y1372700D03*
Y1370200D03*
Y1375200D03*
Y1382700D03*
Y1377700D03*
Y1380200D03*
Y1385200D03*
X1187412Y1437498D03*
X1189612Y1436098D03*
X1191918Y1432516D03*
X1185346Y1442128D03*
X1187512Y1440498D03*
X1189612Y1441898D03*
X1185346Y1439228D03*
X1189612Y1438998D03*
X1187720Y1517688D03*
X1187830Y1522188D03*
X1198546Y1520188D03*
X1187830Y1526688D03*
X1198546Y1524688D03*
X1187720Y1536362D03*
X1198485Y1534313D03*
X1198436Y1529362D03*
X1187720Y1531862D03*
Y1553692D03*
X1198497Y1539667D03*
X1187720Y1548772D03*
X1198436Y1546492D03*
X1187720Y1544292D03*
X1198436Y1551192D03*
Y1556192D03*
Y1561062D03*
X1187720Y1558682D03*
Y1563182D03*
X1194510Y1563076D03*
X1187600Y1622064D03*
X1201600Y1633790D03*
X1199400Y1627800D03*
X1190895Y1642910D03*
X1186000Y1640000D03*
X1197400Y1654942D03*
X1192500D03*
X1186830Y1654632D03*
X1193646Y1680934D03*
X1201106Y1677873D03*
X1190735Y1688390D03*
X1194793Y1698295D03*
X1201505Y1688435D03*
X1192340Y1700422D03*
X1197240D03*
X1193174Y1726414D03*
X1216176Y56742D03*
X1202860Y120392D03*
X1215763Y114363D03*
X1215800Y111300D03*
X1201700Y110000D03*
X1202920Y117162D03*
X1210910Y129502D03*
X1206114Y132962D03*
X1206434Y129492D03*
X1206694Y139512D03*
X1214415Y153962D03*
X1206664Y158952D03*
X1214091Y164962D03*
X1214534Y157462D03*
X1214054Y186092D03*
X1214693Y174962D03*
X1214134Y180972D03*
X1213720Y200309D03*
Y189362D03*
X1204220D03*
X1213720Y195362D03*
X1215720Y204862D03*
X1203200Y202514D03*
X1219060Y213312D03*
X1206660Y224742D03*
X1213540Y224792D03*
X1207220Y243998D03*
X1210900Y265300D03*
X1204475Y350684D03*
X1205165Y380962D03*
X1218870Y418082D03*
X1214000Y599262D03*
X1208980Y598462D03*
X1207100Y600882D03*
X1211277Y744265D03*
X1206757Y744455D03*
X1210288Y754081D03*
X1202300Y753962D03*
X1207607Y754095D03*
X1215896Y756942D03*
X1206432Y758995D03*
X1202307Y757082D03*
X1205820Y1652910D03*
X1210830Y1676500D03*
X1217210Y1684520D03*
X1212305Y1688700D03*
X1216363Y1698605D03*
X1205563Y1698340D03*
X1207180Y1685680D03*
X1208010Y1700467D03*
X1213910Y1700732D03*
X1203110Y1700467D03*
X1203939Y1726459D03*
X1214834Y1726724D03*
X1228425Y91500D03*
X1222100Y91600D03*
X1225100Y91500D03*
X1225700Y108962D03*
X1232182Y110659D03*
X1224614Y116962D03*
X1219534Y116492D03*
X1223500Y111162D03*
X1226400Y125200D03*
X1226093Y134262D03*
X1229500Y125100D03*
X1223100Y130700D03*
X1234093Y144962D03*
X1226093Y140962D03*
X1222593D03*
X1222920Y144909D03*
Y148909D03*
X1222593Y168962D03*
X1222890Y157002D03*
X1226093Y156962D03*
X1222594Y154242D03*
X1226093Y168162D03*
X1225874Y163462D03*
X1222720Y163362D03*
X1226093Y177962D03*
X1222724Y176102D03*
X1226093Y172962D03*
X1223134Y190802D03*
X1225574Y188662D03*
X1228520Y202162D03*
X1229720Y197302D03*
X1226093Y193462D03*
X1225320Y200162D03*
X1233282Y201875D03*
X1223180Y210552D03*
X1233780Y214572D03*
X1231720Y217862D03*
Y209862D03*
X1219220Y243862D03*
Y247148D03*
X1230720Y380362D03*
X1221220D03*
X1232720Y377862D03*
X1224300Y380400D03*
X1223650Y520672D03*
X1230650D03*
X1227150D03*
X1219060Y757272D03*
X1223327Y757615D03*
X1228320Y758598D03*
X1218810Y1700732D03*
X1236620Y58862D03*
X1241010Y110782D03*
X1250010Y117121D03*
X1244200Y112862D03*
X1249362Y111600D03*
X1241035Y114399D03*
X1234746Y136040D03*
X1240728Y136198D03*
X1240904Y151592D03*
X1238604Y150062D03*
X1241100Y145842D03*
X1244120Y167462D03*
X1246272Y164889D03*
X1243100Y160181D03*
X1243184Y182422D03*
X1239874Y182322D03*
X1236410Y201462D03*
X1236220Y189362D03*
X1236593Y197462D03*
X1236584Y205762D03*
X1245486Y203000D03*
X1245593Y211762D03*
X1236620Y221562D03*
X1244720Y230362D03*
X1245514Y224302D03*
X1245593Y219662D03*
X1239045Y224062D03*
X1246878Y248615D03*
X1240500Y248332D03*
Y244332D03*
X1236720Y257362D03*
X1243589Y379595D03*
X1236720Y377862D03*
X1234720Y380362D03*
X1248150Y520672D03*
X1244650D03*
X1241150D03*
X1237650D03*
X1234150D03*
X1242260Y757602D03*
X1261227Y52061D03*
X1258727D03*
X1263454Y83060D03*
X1266464Y83090D03*
X1264098Y88787D03*
X1262320Y96012D03*
X1258539Y100900D03*
X1252520Y92022D03*
X1258539Y109263D03*
X1260641Y114399D03*
X1264220Y110462D03*
X1250424Y108943D03*
X1257581Y114579D03*
X1256093Y149462D03*
X1264663Y158946D03*
X1254994Y157382D03*
X1265010Y162222D03*
X1261899Y174648D03*
X1253624Y201362D03*
X1267315Y220701D03*
X1264874Y217462D03*
X1256504D03*
X1255613Y209568D03*
X1265207Y208442D03*
X1259703Y209808D03*
X1253440Y230552D03*
X1253860Y235622D03*
X1256070Y229512D03*
X1264584Y226592D03*
X1256593Y221462D03*
Y233972D03*
Y225972D03*
X1253950Y246692D03*
X1266715Y244692D03*
X1254370Y241302D03*
X1265065Y249982D03*
X1256494Y243177D03*
X1256574Y238662D03*
X1266518Y237042D03*
X1256584Y248002D03*
X1256454Y252122D03*
X1264854Y253996D03*
Y256496D03*
X1258883Y280558D03*
X1258250Y292986D03*
X1263150Y294726D03*
X1255150Y306211D03*
X1256220Y434362D03*
X1261220Y454362D03*
X1253220Y451362D03*
X1267220D03*
X1260220Y477362D03*
X1255920Y511362D03*
X1251650Y520672D03*
X1255150D03*
X1258667Y751405D03*
X1255520Y747362D03*
X1263486Y739949D03*
X1257672Y1351008D03*
X1276820Y58142D03*
X1282360Y58132D03*
X1279580D03*
X1279390Y87697D03*
X1275820Y87962D03*
X1270329Y101011D03*
X1266722Y101005D03*
X1278456Y96187D03*
X1279415Y90847D03*
X1281704Y95402D03*
X1282824Y108872D03*
X1271284Y108971D03*
X1282764Y135398D03*
X1277820Y140682D03*
X1281093Y144516D03*
X1271954Y159143D03*
X1271593Y165962D03*
X1278093Y184462D03*
X1278993Y193262D03*
X1273093Y200038D03*
X1278183Y201262D03*
X1275493Y193962D03*
X1267289Y192167D03*
X1269904Y192692D03*
X1272893Y191262D03*
X1271315Y220701D03*
X1267773Y208373D03*
X1273093Y213962D03*
X1275727Y209597D03*
X1267618Y225382D03*
X1277661Y225685D03*
X1267593Y229462D03*
X1278783Y221386D03*
X1282176Y221436D03*
X1282654Y226309D03*
X1278320Y239292D03*
X1279493Y248662D03*
X1282645Y255671D03*
Y252271D03*
X1277771Y255173D03*
X1273754Y256504D03*
X1276800Y276562D03*
X1269960Y294536D03*
X1271150Y305792D03*
X1272530Y429362D03*
X1284220D03*
X1280270Y434362D03*
X1272220D03*
X1278380Y463362D03*
X1276220Y477362D03*
X1283220D03*
X1269220D03*
X1274420Y463362D03*
X1275576Y730879D03*
X1266727Y752955D03*
X1279788Y1304042D03*
X1279812Y1353552D03*
X1279334Y1356089D03*
X1275856Y1358098D03*
X1271990Y1358079D03*
X1276891Y1362891D03*
X1282928Y1361833D03*
X1269012Y1371693D03*
Y1368293D03*
X1285201Y58121D03*
X1293454Y81232D03*
X1289210D03*
X1298640Y93062D03*
X1292880Y93162D03*
X1292899Y98519D03*
X1294354Y103166D03*
X1291704Y109427D03*
X1288093Y125962D03*
X1291478Y137745D03*
X1286150Y131092D03*
X1297605Y145824D03*
X1285710Y249182D03*
X1290293Y247562D03*
X1288637Y240448D03*
X1292630Y240462D03*
X1291071Y275543D03*
Y278543D03*
X1290005Y293768D03*
Y290268D03*
X1294500Y299692D03*
X1291100D03*
X1291500Y312862D03*
Y315362D03*
X1291420Y320662D03*
Y318162D03*
X1295540Y440902D03*
X1301310Y440862D03*
X1291220Y463362D03*
X1294440Y477267D03*
X1296630Y463462D03*
X1300220Y477362D03*
X1284220Y463362D03*
X1289936Y732539D03*
X1290520Y746562D03*
X1292572Y785575D03*
X1297298Y790982D03*
X1296719Y1290197D03*
X1299169Y1295467D03*
Y1297967D03*
X1296569D03*
Y1295467D03*
Y1292967D03*
X1299169D03*
X1296581Y1300474D03*
X1299181D03*
X1296576Y1303298D03*
X1299176D03*
X1290102Y1365789D03*
X1286102Y1365051D03*
X1294312Y1367279D03*
X1292840Y1364821D03*
X1286102Y1368107D03*
X1298836Y1358387D03*
X1296506Y1357637D03*
X1301820Y58672D03*
X1311424Y68652D03*
X1308174D03*
X1311960Y58152D03*
X1311260Y83032D03*
X1310857Y78542D03*
X1307120Y78562D03*
X1310906Y97807D03*
X1314406Y97756D03*
X1308274Y104162D03*
X1314059Y93877D03*
X1307244Y118452D03*
X1306836Y108242D03*
X1302080Y117032D03*
X1302060Y113852D03*
X1300990Y121812D03*
X1315156Y130656D03*
X1314920Y135361D03*
X1313117Y250605D03*
X1314685Y248651D03*
X1307431Y256099D03*
X1309283Y254162D03*
X1311275Y252297D03*
X1305552Y257974D03*
X1308736Y284948D03*
X1312136D03*
X1307042Y292636D03*
X1303642D03*
X1307442Y306998D03*
X1304042D03*
X1317100Y553900D03*
X1308600Y653500D03*
X1303576Y659671D03*
X1311420Y738262D03*
X1305187Y735630D03*
X1315020Y739862D03*
X1307469Y787772D03*
X1301034Y784165D03*
X1304260Y788265D03*
X1309930Y789852D03*
X1306701Y794779D03*
X1305117Y797125D03*
X1309210Y792802D03*
X1315169Y1274887D03*
X1315289Y1269717D03*
X1315229Y1272287D03*
X1304149Y1291317D03*
X1301889Y1284987D03*
X1301829Y1290167D03*
X1301859Y1287587D03*
X1304299Y1280967D03*
X1304269Y1283567D03*
X1304239Y1286147D03*
X1304209Y1288747D03*
X1315176Y1280218D03*
X1315181Y1277594D03*
X1299319Y1290197D03*
X1299349Y1287617D03*
X1301686Y1303268D03*
X1304196Y1299248D03*
X1304189Y1293917D03*
X1304201Y1296624D03*
X1301679Y1292937D03*
Y1295437D03*
Y1297937D03*
X1301691Y1300444D03*
X1311820Y1330518D03*
Y1333018D03*
X1314936Y1338799D03*
X1312650Y1342572D03*
X1308616Y1363345D03*
Y1360445D03*
X1306082Y1359315D03*
X1306182Y1362315D03*
X1304016Y1363945D03*
Y1361045D03*
X1308616Y1357945D03*
X1303496Y1358387D03*
X1301166Y1357637D03*
X1316459Y58697D03*
X1322248Y68487D03*
X1321279Y58767D03*
X1317831Y68652D03*
X1322415Y75480D03*
X1322906Y94212D03*
X1319968Y98266D03*
X1329891Y99455D03*
X1329646Y104954D03*
X1322906Y109733D03*
X1323912Y245111D03*
X1320387Y258901D03*
X1325769Y259001D03*
X1325414Y293556D03*
X1328814D03*
X1319903Y299176D03*
X1323303D03*
X1330101Y540049D03*
X1328530Y747702D03*
X1325210Y744322D03*
X1331519Y1262027D03*
X1331459Y1264597D03*
X1331399Y1267197D03*
X1317889Y1267147D03*
X1320399Y1267117D03*
X1317883Y1269978D03*
X1317895Y1272485D03*
X1320393Y1269948D03*
X1320405Y1272455D03*
X1331177Y1269933D03*
Y1272433D03*
X1317895Y1274985D03*
X1320405Y1274955D03*
X1331177Y1274933D03*
X1331166Y1280248D03*
X1317746D03*
X1320256Y1280218D03*
X1317895Y1277485D03*
X1320405Y1277455D03*
X1331189Y1277440D03*
X1328514Y1334603D03*
X1330844Y1335353D03*
X1322110Y1342755D03*
X1318110Y1342017D03*
X1326320Y1344245D03*
X1324848Y1341787D03*
X1318110Y1345073D03*
X1331288Y1372440D03*
X1327491Y1372358D03*
X1324491Y1372658D03*
X1327491Y1375858D03*
X1331288Y1375940D03*
X1324491Y1375858D03*
X1327491Y1381478D03*
Y1378478D03*
X1331288Y1378560D03*
X1324491Y1381478D03*
Y1378478D03*
X1331304Y1401986D03*
Y1404986D03*
X1327926D03*
X1322228Y1419890D03*
X1322186Y1411326D03*
Y1414326D03*
Y1417326D03*
X1322270Y1422454D03*
X1325084Y1420066D03*
X1325042Y1408502D03*
Y1411502D03*
Y1417502D03*
Y1414502D03*
X1331344Y1414456D03*
X1330804Y1411536D03*
Y1408536D03*
X1331386Y1420020D03*
X1328008D03*
X1331344Y1417456D03*
X1327966Y1408456D03*
Y1411456D03*
Y1417456D03*
Y1414456D03*
X1331428Y1422584D03*
X1328050D03*
X1322312Y1425018D03*
X1325126Y1422630D03*
X1325168Y1425194D03*
X1328092Y1425148D03*
X1331470D03*
X1333190Y58825D03*
X1347640Y101950D03*
X1345583Y91307D03*
X1336549Y105970D03*
X1344631Y127244D03*
X1332497Y133931D03*
X1343034Y141698D03*
X1344684Y280259D03*
X1336761Y293404D03*
X1340161D03*
X1344720Y423162D03*
X1337220D03*
X1342220D03*
X1339720D03*
X1333143Y540049D03*
X1340420Y538422D03*
Y541822D03*
X1347419Y1259257D03*
X1347379Y1256687D03*
X1336269Y1274957D03*
X1333969Y1264567D03*
X1334029Y1261997D03*
X1333909Y1267167D03*
X1336339Y1269777D03*
X1336279Y1272347D03*
X1347359Y1261857D03*
X1347371Y1264564D03*
X1336519Y1264627D03*
X1336579Y1262057D03*
X1347366Y1267188D03*
X1336459Y1267227D03*
X1333687Y1269903D03*
Y1272403D03*
Y1274903D03*
X1333676Y1280218D03*
X1336261Y1277654D03*
X1333699Y1277410D03*
X1343948Y1317092D03*
Y1319592D03*
X1344532Y1328161D03*
X1347397Y1325320D03*
X1336144Y1341147D03*
X1338288Y1339653D03*
X1340488Y1340853D03*
X1336144Y1338247D03*
X1340214Y1334853D03*
X1340410Y1338017D03*
X1338288Y1336553D03*
X1333174Y1334603D03*
X1335504Y1335353D03*
X1334288Y1372440D03*
X1340288D03*
X1346193Y1372523D03*
X1343193D03*
X1337288Y1372440D03*
Y1375940D03*
X1334288D03*
X1343193Y1376023D03*
X1346193D03*
X1340288Y1375940D03*
X1346304Y1401986D03*
X1343304D03*
X1340304D03*
X1337304D03*
X1334304D03*
Y1404986D03*
X1346304D03*
X1343304D03*
X1340304D03*
X1337304D03*
X1337344Y1414456D03*
X1346344D03*
X1343344D03*
X1340344D03*
X1346534Y1411496D03*
Y1408496D03*
X1334344Y1414456D03*
X1346344Y1417456D03*
X1340344D03*
X1337344D03*
X1334386Y1420020D03*
X1334344Y1417456D03*
X1346386Y1420020D03*
X1343386D03*
X1340386D03*
X1337386D03*
X1343344Y1417456D03*
X1337428Y1422584D03*
X1340428D03*
X1343428D03*
X1334428D03*
X1337328Y1425164D03*
X1340328D03*
X1343328D03*
X1346178Y1425254D03*
X1346278Y1422674D03*
X1334470Y1425148D03*
X1348610Y84712D03*
X1349480Y77072D03*
X1366369Y83820D03*
X1349570Y104147D03*
X1353394Y131812D03*
X1348620Y136162D03*
X1349220Y140362D03*
X1348084Y280259D03*
X1358624Y284644D03*
X1355224D03*
X1356220Y581862D03*
X1356047Y680000D03*
X1358907Y681262D03*
X1361727Y680665D03*
X1352474Y1256866D03*
X1349964Y1256896D03*
X1352486Y1259373D03*
X1349976Y1259403D03*
X1363258Y1256851D03*
Y1259351D03*
X1349876Y1267158D03*
X1352426Y1267218D03*
X1363266Y1267188D03*
X1349976Y1261903D03*
X1352486Y1261873D03*
Y1264373D03*
X1349976Y1264403D03*
X1363258Y1261851D03*
X1363270Y1264358D03*
X1360593Y1321872D03*
X1363098Y1320951D03*
X1354238Y1329329D03*
X1350238Y1328591D03*
X1358448Y1330819D03*
X1356976Y1328361D03*
X1350238Y1331647D03*
X1352666Y1378560D03*
X1349666D03*
X1352666Y1381560D03*
X1349666D03*
X1352666Y1375940D03*
X1349666D03*
X1352126Y1401986D03*
X1349426D03*
X1352126Y1404986D03*
X1349426D03*
X1349508Y1420020D03*
X1352166Y1420456D03*
Y1414456D03*
Y1411456D03*
Y1408456D03*
Y1417456D03*
X1349466Y1411456D03*
Y1408456D03*
Y1417456D03*
Y1414456D03*
X1349278Y1422674D03*
X1364860Y1455172D03*
X1362410Y1445272D03*
X1378839Y87626D03*
X1366369Y92450D03*
X1366714Y109506D03*
X1376991Y176430D03*
X1373591D03*
X1375619Y236261D03*
X1375257Y229756D03*
X1373493Y227762D03*
X1380522Y260236D03*
Y263636D03*
X1368524Y282744D03*
X1365124D03*
X1378306Y657608D03*
X1374668Y659708D03*
X1378306Y669608D03*
X1374668Y671708D03*
X1370207Y682245D03*
X1374668Y683708D03*
X1378306Y681608D03*
X1374668Y695708D03*
X1378306Y693608D03*
Y705608D03*
X1374668Y707708D03*
Y719708D03*
X1378306Y717608D03*
X1374938Y1161569D03*
Y1170069D03*
X1379579Y1259317D03*
X1368379Y1259287D03*
X1379639Y1256747D03*
X1368439Y1256717D03*
X1365768Y1256821D03*
Y1259321D03*
X1365776Y1267158D03*
X1368326Y1267218D03*
X1379519Y1261917D03*
X1379531Y1264624D03*
X1379526Y1267248D03*
X1368361Y1264594D03*
X1368369Y1261897D03*
X1365768Y1261821D03*
X1365780Y1264328D03*
X1376076Y1317092D03*
Y1319592D03*
X1379192Y1325373D03*
X1368272Y1324821D03*
X1372538Y1324591D03*
X1370338Y1323091D03*
X1372538Y1321691D03*
X1365376Y1321938D03*
X1367635Y1320904D03*
X1377214Y1327653D03*
X1368272Y1327721D03*
X1370438Y1326091D03*
X1372538Y1327491D03*
X1377054Y1394028D03*
X1367316Y1399053D03*
Y1403458D03*
X1370577Y1421899D03*
X1367436Y1414778D03*
X1370891Y1410306D03*
X1378417Y1415292D03*
X1367316Y1407458D03*
X1367889Y1419235D03*
X1377075Y1425014D03*
X1365235Y1428637D03*
X1370250Y1433715D03*
X1367620Y1431472D03*
X1367170Y1453142D03*
X1368842Y1449261D03*
X1364800Y1449231D03*
X1368980Y1457122D03*
X1370041Y1460374D03*
X1393250Y93802D03*
X1386684Y145017D03*
X1386404Y149008D03*
X1394182Y171470D03*
X1398182D03*
X1384002Y197668D03*
X1389256D03*
X1380602D03*
X1392656D03*
X1395960Y226422D03*
X1393460D03*
X1386868Y222937D03*
X1384017Y223697D03*
X1386138Y225411D03*
X1384895Y221346D03*
X1381951Y221420D03*
X1380638Y245694D03*
X1386630Y238651D03*
X1380638Y249094D03*
X1386630Y242051D03*
X1381235Y236020D03*
X1390600Y248262D03*
X1388754Y253803D03*
Y257203D03*
X1386273Y268670D03*
Y272070D03*
X1392685Y498992D03*
X1387550Y502922D03*
X1387600Y499182D03*
X1391260Y507082D03*
X1393206Y664708D03*
X1389568Y662608D03*
X1393206Y679208D03*
X1389568Y677108D03*
X1393206Y693708D03*
X1389568Y691608D03*
Y706108D03*
X1393206Y708208D03*
X1393199Y722708D03*
X1389561Y720608D03*
X1385338Y735098D03*
X1388976Y737198D03*
X1396081Y1161569D03*
Y1153369D03*
Y1170069D03*
X1384652Y1256866D03*
X1382142Y1256896D03*
X1384664Y1259373D03*
X1382154Y1259403D03*
X1395436Y1256851D03*
Y1259351D03*
X1384586Y1267278D03*
X1395426Y1267188D03*
X1382036Y1267218D03*
X1382154Y1261903D03*
X1384664Y1261873D03*
Y1264373D03*
X1382154Y1264403D03*
X1395436Y1261851D03*
X1395448Y1264358D03*
X1392770Y1321177D03*
X1395100Y1321927D03*
X1386366Y1329329D03*
X1382366Y1328591D03*
X1390576Y1330819D03*
X1389104Y1328361D03*
X1382366Y1331647D03*
X1396311Y1385712D03*
X1398680Y1380582D03*
X1390474Y1385142D03*
X1387074Y1384272D03*
X1390513Y1395452D03*
X1387066Y1401734D03*
X1387291Y1408163D03*
X1387470Y1418302D03*
X1385109Y1410427D03*
X1390170Y1423942D03*
X1387068Y1413991D03*
X1381066Y1425008D03*
X1393630Y1426562D03*
X1388557Y1431645D03*
X1395907Y1430227D03*
X1395443Y1434700D03*
X1398569Y1437860D03*
X1383429Y1427652D03*
X1392620Y1446708D03*
X1389220D03*
X1382600Y1563480D03*
X1391655Y1570037D03*
X1391055Y1565037D03*
X1384840Y1565640D03*
X1386790Y1563610D03*
X1396600Y1590200D03*
Y1586400D03*
X1393000Y1590300D03*
X1395325Y1606862D03*
X1386200Y1645700D03*
X1386600Y1641400D03*
X1407029Y152732D03*
X1410370Y138742D03*
X1406970D03*
X1407029Y156132D03*
X1401341Y177159D03*
X1404829Y184263D03*
X1404741Y177159D03*
X1408229Y184263D03*
X1407178Y171684D03*
X1403778D03*
X1398006Y197668D03*
X1406786D03*
X1401406D03*
X1410186D03*
X1413900Y225212D03*
X1396900Y228932D03*
X1398831Y1161569D03*
Y1153369D03*
Y1170069D03*
X1411909Y1259257D03*
X1400599Y1256717D03*
X1411969Y1256687D03*
X1397946Y1256821D03*
Y1259321D03*
X1400539Y1259287D03*
X1400521Y1264594D03*
X1400529Y1261897D03*
X1397936Y1267158D03*
X1400486Y1267218D03*
X1411849Y1261857D03*
X1411861Y1264564D03*
X1411856Y1267188D03*
X1397946Y1261821D03*
X1397958Y1264328D03*
X1408204Y1317092D03*
Y1319592D03*
X1411320Y1325373D03*
X1400400Y1324821D03*
X1404666Y1324591D03*
X1402466Y1323091D03*
X1404666Y1321691D03*
X1397430Y1321177D03*
X1399760Y1321927D03*
X1408969Y1327645D03*
X1402566Y1326091D03*
X1400400Y1327721D03*
X1404666Y1327491D03*
X1401655Y1384676D03*
X1406461Y1383862D03*
X1415171Y1383692D03*
X1412961Y1387387D03*
X1412608Y1391687D03*
X1414362Y1402191D03*
X1414786Y1426890D03*
X1413440Y1436774D03*
X1409680Y1430613D03*
X1401371Y1434592D03*
X1410477Y1440117D03*
X1410038Y1434670D03*
X1403687Y1444711D03*
X1400287D03*
X1400220Y1518862D03*
X1409248Y1528862D03*
X1400160Y1543342D03*
X1404433Y1565037D03*
X1400695Y1570037D03*
X1400715Y1565037D03*
X1407440Y1557552D03*
X1404433Y1570037D03*
X1402536Y1576097D03*
X1402680Y1597700D03*
X1401300Y1619917D03*
X1410900Y1624800D03*
X1400000Y1626362D03*
Y1634362D03*
Y1638362D03*
X1410500Y1638862D03*
X1396900Y1642100D03*
X1413950Y184263D03*
X1423110D03*
X1417350D03*
X1426510D03*
X1428336Y232762D03*
X1415340Y231812D03*
X1418630Y220018D03*
X1422030D03*
X1413847Y239528D03*
X1426020Y261501D03*
X1431430Y256383D03*
Y264060D03*
X1426647Y329050D03*
X1417022Y621419D03*
X1424119Y1161520D03*
X1426619D03*
X1424119Y1153369D03*
X1426619D03*
Y1169570D03*
X1424119D03*
X1416999Y1256866D03*
X1414489Y1256896D03*
X1417011Y1259373D03*
X1414501Y1259403D03*
X1427783Y1256851D03*
Y1259351D03*
X1414366Y1267158D03*
X1416916Y1267218D03*
X1427786Y1267158D03*
X1414501Y1261903D03*
X1417011Y1261873D03*
Y1264373D03*
X1414501Y1264403D03*
X1427783Y1261851D03*
X1427795Y1264358D03*
X1424898Y1321177D03*
X1427228Y1321927D03*
X1418494Y1329329D03*
X1414494Y1328591D03*
X1422704Y1330819D03*
X1421232Y1328361D03*
X1414494Y1331647D03*
X1418990Y1387452D03*
X1422594Y1383301D03*
X1419995Y1397492D03*
X1415620Y1396652D03*
X1419055Y1392497D03*
X1426872Y1405811D03*
X1423256Y1403728D03*
X1424255Y1396612D03*
X1421480Y1415731D03*
X1422371Y1407722D03*
X1421371Y1411719D03*
X1421864Y1419730D03*
X1419991Y1423404D03*
X1424930Y1433850D03*
X1416272Y1433949D03*
X1421435Y1430415D03*
X1419746Y1435932D03*
X1414350Y1516435D03*
X1426020Y1521535D03*
X1414590Y1532255D03*
X1414350Y1521335D03*
X1427120Y1537355D03*
X1414590Y1537155D03*
X1414740Y1543475D03*
Y1548375D03*
X1427320Y1548575D03*
X1425620Y1556662D03*
X1416060Y1574922D03*
X1422680Y1582100D03*
X1419450Y1596150D03*
X1423700Y1600400D03*
X1434600Y59262D03*
X1444275Y57262D03*
X1432220Y61862D03*
X1440800Y66862D03*
X1447340Y157402D03*
X1442434Y210757D03*
X1430120Y225182D03*
X1436060Y220018D03*
X1432660D03*
X1431636Y230448D03*
X1444570Y238372D03*
X1431933Y238125D03*
X1431431Y267378D03*
X1436120Y315772D03*
X1436270Y312592D03*
X1436335Y309407D03*
X1436320Y305862D03*
Y303362D03*
X1436050Y321352D03*
X1436120Y318272D03*
X1436232Y344176D03*
X1433418Y729104D03*
X1444099Y1259397D03*
X1432899Y1259257D03*
X1444159Y1256827D03*
X1432959Y1256687D03*
X1430293Y1256821D03*
Y1259321D03*
X1444051Y1264704D03*
X1444039Y1261997D03*
X1444046Y1267328D03*
X1432889Y1261867D03*
X1432881Y1264564D03*
X1432846Y1267188D03*
X1430296Y1267128D03*
X1430293Y1261821D03*
X1430305Y1264328D03*
X1440332Y1317092D03*
Y1319592D03*
X1443448Y1325373D03*
X1432528Y1324821D03*
X1436794Y1324591D03*
X1434594Y1323091D03*
X1436794Y1321691D03*
X1429558Y1321177D03*
X1431888Y1321927D03*
X1441332Y1327793D03*
X1434694Y1326091D03*
X1432528Y1327721D03*
X1436794Y1327491D03*
X1437443Y1406289D03*
X1444997Y1392885D03*
X1435462Y1393009D03*
Y1396409D03*
X1434312Y1415197D03*
X1443112Y1417929D03*
X1445020Y1412672D03*
X1443676Y1432624D03*
X1433750Y1429208D03*
X1439742Y1436924D03*
X1434720Y1454862D03*
X1440440Y1454892D03*
X1444468Y1570610D03*
X1433720Y1569762D03*
X1440105Y1593352D03*
X1446700Y1598400D03*
X1438300Y1606800D03*
Y1602600D03*
X1430250Y1612812D03*
X1441800Y1628700D03*
Y1624500D03*
X1438547Y1638212D03*
X1443617D03*
X1431575Y1634842D03*
X1442573Y1649862D03*
X1442587Y1659242D03*
X1438320Y1668292D03*
X1438220Y1673955D03*
X1446715Y1679957D03*
X1446000Y67802D03*
X1458720Y145362D03*
X1450270Y143022D03*
X1450720Y153362D03*
X1448820Y148092D03*
X1450720Y169862D03*
Y161862D03*
X1449740Y166912D03*
X1450720Y181862D03*
Y177862D03*
Y173862D03*
X1462561Y205982D03*
X1457361D03*
X1459961Y210432D03*
X1456150Y214382D03*
X1449110Y233742D03*
X1455600Y297200D03*
X1456770Y342942D03*
X1460849Y343327D03*
X1462790Y359042D03*
X1462870Y355012D03*
X1449777Y362021D03*
X1459900Y370823D03*
X1455920Y373941D03*
X1463600Y374462D03*
X1449777Y371039D03*
X1455642Y409646D03*
X1449296Y407347D03*
X1449600Y402322D03*
X1456777Y418596D03*
Y426546D03*
X1457176Y656992D03*
X1460814Y654892D03*
Y666892D03*
X1457176Y668992D03*
X1460814Y678892D03*
X1457176Y680992D03*
X1460814Y690892D03*
X1457176Y704992D03*
Y692992D03*
X1460814Y702892D03*
X1457176Y716992D03*
X1460814Y714892D03*
X1456237Y726945D03*
X1457620Y736195D03*
X1460187Y729805D03*
X1455692Y731401D03*
X1457714Y741622D03*
X1447149Y1161569D03*
X1449649D03*
X1447299Y1153369D03*
X1449799D03*
X1447149Y1170069D03*
X1449649D03*
X1449176Y1256866D03*
X1446666Y1256896D03*
X1449188Y1259373D03*
X1446678Y1259403D03*
X1459960Y1259351D03*
Y1256851D03*
X1449106Y1267358D03*
X1459886Y1267218D03*
X1446556Y1267298D03*
X1446678Y1261903D03*
X1449188Y1261873D03*
Y1264373D03*
X1446678Y1264403D03*
X1459960Y1261851D03*
X1459972Y1264358D03*
X1457026Y1321177D03*
X1461686D03*
X1459356Y1321927D03*
X1450622Y1329329D03*
X1446622Y1328591D03*
X1454832Y1330819D03*
X1453360Y1328361D03*
X1446622Y1331647D03*
X1459968Y1402765D03*
X1451176Y1399026D03*
X1451198Y1403047D03*
X1460224Y1407545D03*
X1458138Y1409955D03*
X1461062Y1413246D03*
X1455006Y1447938D03*
X1459111Y1445669D03*
Y1448669D03*
X1457577Y1526689D03*
X1457817Y1542509D03*
X1457967Y1553729D03*
X1458200Y1565037D03*
Y1560037D03*
X1448620Y1556162D03*
X1456030Y1590302D03*
X1456120Y1586262D03*
X1453600Y1595662D03*
X1451500Y1612800D03*
X1454167Y1638302D03*
X1459127D03*
X1448507Y1638212D03*
X1448920Y1675062D03*
X1474142Y61767D03*
X1462000Y153362D03*
X1470220Y169862D03*
X1473090Y204502D03*
X1472335Y209362D03*
X1467761Y205982D03*
X1471308Y230640D03*
X1463833Y230448D03*
X1474660Y252878D03*
X1463808Y244948D03*
X1463833Y235566D03*
X1473820Y265962D03*
X1471510Y252878D03*
X1471690Y259862D03*
X1463950Y258172D03*
X1463330Y264060D03*
X1463510Y273878D03*
X1475452Y289708D03*
X1475352Y306308D03*
X1476826Y312177D03*
X1467700Y370953D03*
X1472758Y370817D03*
X1465836Y408668D03*
X1470942Y409718D03*
X1475250Y401812D03*
X1469777Y418396D03*
X1469951Y429251D03*
X1469720Y434542D03*
X1469760Y452622D03*
X1471460Y633402D03*
X1468060D03*
X1465171Y647132D03*
X1469020Y647102D03*
X1472076Y657392D03*
Y671892D03*
X1475714Y659492D03*
Y673992D03*
X1472076Y686392D03*
X1475714Y688492D03*
X1472076Y700892D03*
X1475714Y702992D03*
X1470841Y721493D03*
X1472076Y715392D03*
X1475714Y717492D03*
X1468876Y728392D03*
X1472514Y730492D03*
X1464999Y1259317D03*
X1476369Y1259237D03*
X1465059Y1256747D03*
X1462470Y1259321D03*
Y1256821D03*
X1476291Y1275224D03*
X1464946Y1267248D03*
X1464989Y1261927D03*
X1464981Y1264624D03*
X1476339Y1264467D03*
Y1267037D03*
X1476309Y1261807D03*
X1476279Y1269637D03*
X1476291Y1272344D03*
X1462396Y1267188D03*
X1462470Y1261821D03*
X1462482Y1264328D03*
X1476291Y1278104D03*
X1464016Y1321927D03*
X1466819Y1324018D03*
X1469019Y1322618D03*
X1473956Y1341068D03*
X1472460Y1330493D03*
Y1333043D03*
X1475576Y1338799D03*
X1469019Y1325518D03*
X1464680Y1325772D03*
X1469019Y1328418D03*
X1466919Y1327018D03*
X1464680Y1328672D03*
X1467567Y1445669D03*
Y1448669D03*
X1475967Y1445669D03*
Y1448669D03*
X1478320Y1522962D03*
X1472565Y1623635D03*
X1478061Y1633864D03*
X1463767Y1638302D03*
X1476570Y1661124D03*
X1493120Y240412D03*
X1487958Y236062D03*
X1490060Y255378D03*
X1485320Y260362D03*
X1478745Y281508D03*
X1493289Y280027D03*
X1478526Y289677D03*
X1481445Y289708D03*
X1479745Y312208D03*
X1478426Y306277D03*
X1481345Y306308D03*
X1481484Y361688D03*
X1481766Y372288D03*
X1489443D03*
X1494784Y374188D03*
X1486040Y368392D03*
X1481766Y406238D03*
X1490384Y407292D03*
X1493384Y411313D03*
X1482650Y411190D03*
X1495527Y406215D03*
X1486880Y416863D03*
X1484805Y427577D03*
X1489310Y426822D03*
X1481539Y1259377D03*
X1478999Y1259257D03*
X1481479Y1261947D03*
X1481419Y1264547D03*
X1481431Y1267254D03*
X1478939Y1261827D03*
X1478879Y1264427D03*
X1478891Y1267134D03*
X1481359Y1271447D03*
X1492039D03*
X1481359Y1274144D03*
X1492091D03*
X1478859Y1271417D03*
Y1274114D03*
X1481361Y1280054D03*
X1492101D03*
X1478821D03*
X1481359Y1277024D03*
X1492091D03*
X1478859Y1276994D03*
X1489154Y1334603D03*
X1493814D03*
X1491484Y1335353D03*
X1482750Y1342755D03*
X1478750Y1342017D03*
X1486960Y1344245D03*
X1485488Y1341787D03*
X1478750Y1345073D03*
X1485387Y1420002D03*
X1481918Y1425579D03*
X1484442Y1445557D03*
Y1448557D03*
X1482830Y1525162D03*
X1480800Y1663600D03*
X1510500Y125992D03*
X1508959Y215802D03*
X1503020D03*
X1499922Y211240D03*
X1496720Y225292D03*
X1504484Y234562D03*
X1508410Y230842D03*
X1510017Y225516D03*
X1501840Y225502D03*
X1512420Y239116D03*
X1510810Y249742D03*
X1509040Y243362D03*
X1504890Y249862D03*
X1506600Y239092D03*
X1504650Y254392D03*
X1508049Y280056D03*
X1498984Y282797D03*
X1508558Y291175D03*
X1512244Y311522D03*
X1505922Y304583D03*
X1509539Y308467D03*
X1498184Y361723D03*
Y369798D03*
X1495150Y369842D03*
X1503450Y385843D03*
X1509638Y738627D03*
X1509350Y741315D03*
X1504747Y747293D03*
X1503514Y801361D03*
Y797961D03*
X1497199Y1275667D03*
X1497259Y1273097D03*
X1494629Y1271477D03*
X1494631Y1274144D03*
X1506569Y1285947D03*
X1508819Y1284797D03*
X1506539Y1288557D03*
X1508759Y1287367D03*
X1508699Y1289967D03*
X1494641Y1280054D03*
X1494631Y1277024D03*
X1506551Y1291254D03*
X1497199Y1278277D03*
X1497161Y1280974D03*
X1506689Y1283377D03*
X1506591Y1297014D03*
Y1294134D03*
X1508711Y1295554D03*
Y1298434D03*
Y1292674D03*
X1496784Y1341147D03*
X1498924Y1334882D03*
X1498950Y1339517D03*
X1501149Y1336287D03*
X1496784Y1338247D03*
X1496144Y1335353D03*
X1504588Y1353316D03*
Y1355816D03*
X1501033Y1341462D03*
X1498959Y1342930D03*
X1505570Y1364212D03*
X1507704Y1361597D03*
X1510027Y1425825D03*
X1507617Y1424045D03*
X1522920Y116180D03*
X1513900Y117762D03*
X1518575Y138662D03*
X1521115Y193262D03*
X1524539Y215551D03*
X1522009Y210825D03*
X1518110Y215551D03*
X1526998Y209645D03*
X1527732Y219488D03*
X1514520Y231116D03*
X1526152Y225114D03*
X1514593Y249698D03*
Y235116D03*
X1519758Y265161D03*
X1522786Y262558D03*
X1522258Y265161D03*
X1519833Y277297D03*
X1522258Y288956D03*
X1517669Y291516D03*
X1515940Y795815D03*
Y799215D03*
X1513789Y1290037D03*
X1511289Y1287397D03*
X1511199Y1290007D03*
X1513791Y1292704D03*
X1516351D03*
X1513791Y1298464D03*
Y1295584D03*
X1516351D03*
Y1298464D03*
X1511251Y1292704D03*
Y1298464D03*
Y1295584D03*
X1521282Y1357401D03*
X1525942D03*
X1514878Y1365553D03*
X1510878Y1364815D03*
X1519088Y1367043D03*
X1517616Y1364585D03*
X1510878Y1367871D03*
X1523612Y1358151D03*
X1512177Y1427795D03*
X1516137Y1432135D03*
X1513657Y1429985D03*
X1544010Y27552D03*
X1536310Y47492D03*
X1534060Y100162D03*
X1530660D03*
X1533520Y110662D03*
X1529500Y122122D03*
X1535575Y118862D03*
X1540090Y122782D03*
X1536925Y129937D03*
X1529500Y125862D03*
X1535520Y151562D03*
X1529233Y153162D03*
X1535450Y155262D03*
X1542401Y141561D03*
X1534720Y199803D03*
X1528720Y199862D03*
X1533385Y193108D03*
X1533148Y211614D03*
X1531824Y207677D03*
X1534194Y217519D03*
X1529670Y225522D03*
X1535561Y225393D03*
X1531110Y264862D03*
X1539150Y267132D03*
X1540958Y307756D03*
X1539720Y589862D03*
Y581862D03*
X1540377Y634165D03*
X1541211Y646178D03*
X1533178Y1360815D03*
X1530978Y1359315D03*
X1528912Y1361045D03*
X1531078Y1362315D03*
X1533178Y1363715D03*
X1528912Y1363945D03*
X1533178Y1357915D03*
X1528272Y1358151D03*
X1556413Y19495D03*
X1549308Y26431D03*
X1552708D03*
X1552960Y124359D03*
X1553189Y127781D03*
X1556049Y147711D03*
X1545763Y159305D03*
X1551160Y189342D03*
X1557900Y220362D03*
X1557760Y214792D03*
X1550353Y217352D03*
X1557320Y203297D03*
X1559400Y229832D03*
X1545668Y305266D03*
X1545768Y302766D03*
X1543958Y307556D03*
X1546458Y307856D03*
X1543858Y310056D03*
X1543720Y581862D03*
X1548720D03*
X1552720Y589862D03*
Y581862D03*
X1554753Y628860D03*
X1553312Y636815D03*
X1559354Y655716D03*
Y659116D03*
X1550487Y681565D03*
X1550320Y696562D03*
X1550917Y704332D03*
X1550390Y709885D03*
X1570586Y19495D03*
X1573986D03*
X1559813D03*
X1563481Y26431D03*
X1566881D03*
X1573560Y245078D03*
X1574760Y251032D03*
X1559722Y243110D03*
X1570675Y267857D03*
X1573246Y306650D03*
X1572396Y309450D03*
X1563714Y572792D03*
X1567114D03*
X1559557Y593290D03*
X1564768Y708159D03*
X1562871Y732316D03*
Y735716D03*
X1571577Y747145D03*
X1567547Y755485D03*
X1571920Y762662D03*
X1568490Y758162D03*
X1570374Y760093D03*
X1584759Y19495D03*
X1588159D03*
X1577654Y26431D03*
X1591828D03*
X1581054D03*
X1576589Y300927D03*
X1588314Y592553D03*
X1585714D03*
X1583114D03*
X1590914D03*
X1588254Y595103D03*
X1588284Y597613D03*
X1585654Y595103D03*
X1585684Y597613D03*
X1583084D03*
X1583054Y595103D03*
X1588284Y608655D03*
X1585684D03*
X1583084D03*
X1590854Y595103D03*
X1590884Y597613D03*
Y608655D03*
X1588254Y613715D03*
X1588224Y611205D03*
X1585654Y613715D03*
X1585624Y611205D03*
X1583024D03*
X1583054Y613715D03*
X1590854D03*
X1590824Y611205D03*
X1591368Y628727D03*
X1591428Y626177D03*
X1588928D03*
X1588868Y628727D03*
X1591398Y631237D03*
X1588898D03*
X1591368Y650877D03*
X1591338Y648367D03*
X1591398Y645817D03*
X1588868Y650877D03*
X1588838Y648367D03*
X1588898Y645817D03*
X1591368Y653377D03*
X1588868D03*
X1591448Y657677D03*
X1588948D03*
Y660177D03*
X1591448D03*
X1588968Y665237D03*
X1591468D03*
X1588938Y662727D03*
X1591438D03*
X1588938Y679807D03*
X1588878Y682357D03*
X1588908Y684867D03*
X1591438Y679807D03*
X1591378Y682357D03*
X1591408Y684867D03*
X1591328Y696727D03*
X1591388Y694177D03*
X1588888D03*
X1588828Y696727D03*
X1591358Y699277D03*
X1588858D03*
X1591358Y718837D03*
X1591328Y716327D03*
X1591388Y713777D03*
X1588858Y718837D03*
X1588828Y716327D03*
X1588888Y713777D03*
X1590915Y755793D03*
X1598933Y19495D03*
X1602333D03*
X1595228Y26431D03*
X1603747Y192951D03*
X1603530Y202402D03*
X1603706Y211526D03*
X1603580Y206902D03*
X1604200Y234642D03*
X1604240Y227892D03*
X1603920Y222922D03*
X1604270Y231490D03*
X1604240Y238242D03*
X1602980Y560002D03*
X1593514Y592553D03*
X1601830Y590685D03*
X1604430D03*
X1607200Y583962D03*
X1593484Y597613D03*
X1593454Y595103D03*
X1593484Y608655D03*
X1593424Y611205D03*
X1593454Y613715D03*
X1601830Y615201D03*
X1604430D03*
X1598868Y628727D03*
X1598928Y626177D03*
X1593868Y628727D03*
X1593928Y626177D03*
X1596428D03*
X1596368Y628727D03*
X1598898Y631237D03*
X1593898D03*
X1596398D03*
X1598868Y650877D03*
X1598838Y648367D03*
X1596368Y650877D03*
X1593868D03*
X1596338Y648367D03*
X1593838D03*
X1598898Y645817D03*
X1596398D03*
X1593898D03*
X1598868Y653377D03*
X1596368D03*
X1593868D03*
X1598948Y657677D03*
X1593948D03*
X1596448D03*
Y660177D03*
X1593948D03*
X1598948D03*
X1596468Y665237D03*
X1593968D03*
X1598968D03*
X1596438Y662727D03*
X1593938D03*
X1598938D03*
X1593938Y679807D03*
X1596438D03*
X1593878Y682357D03*
X1596378D03*
X1593908Y684867D03*
X1596408D03*
X1598878Y682357D03*
X1598908Y684867D03*
X1598938Y679807D03*
X1596288Y688902D03*
X1598888D03*
X1598828Y696727D03*
X1593828D03*
X1593888Y694177D03*
X1596388D03*
X1596328Y696727D03*
X1593858Y699277D03*
X1596358D03*
X1598888Y694177D03*
X1596288Y691502D03*
X1598858Y699277D03*
X1598888Y691502D03*
X1598858Y718837D03*
X1598828Y716327D03*
X1596358Y718837D03*
X1593858D03*
X1596328Y716327D03*
X1593828D03*
X1596388Y713777D03*
X1593888D03*
X1598888D03*
X1596250Y721452D03*
X1598850D03*
X1599010Y724002D03*
X1598440Y736692D03*
X1592760Y736652D03*
X1595600D03*
X1606788Y756199D03*
X1602788D03*
X1621920Y25962D03*
X1622220Y49862D03*
X1623881Y129627D03*
X1610788Y756199D03*
X1614788D03*
X1618788D03*
X1615062Y1421241D03*
X1613047Y1415669D03*
X1614927Y1426076D03*
Y1429896D03*
X1624353Y1428766D03*
Y1431316D03*
X1617215Y1440822D03*
X1634799Y19495D03*
X1638199D03*
X1627694Y26431D03*
X1631094D03*
X1633111Y206693D03*
X1632342Y216015D03*
X1635835Y343002D03*
X1636800Y429982D03*
X1639800D03*
X1636800Y426982D03*
X1639800D03*
X1636800Y438982D03*
X1639800D03*
X1636800Y435982D03*
X1639800D03*
X1636800Y432982D03*
X1639800D03*
X1638928Y756199D03*
X1630928D03*
X1634928D03*
X1638277Y1269065D03*
X1640812Y1270020D03*
X1631203Y1367492D03*
X1628653D03*
X1626153D03*
X1628653Y1372492D03*
X1631203D03*
X1626153D03*
X1631203Y1369992D03*
X1628653D03*
X1626153D03*
X1628653Y1379992D03*
Y1382492D03*
Y1377492D03*
Y1374992D03*
X1631203Y1377492D03*
Y1374992D03*
Y1379992D03*
Y1382492D03*
X1626153Y1379992D03*
Y1382492D03*
Y1374992D03*
Y1377492D03*
X1630643Y1440290D03*
X1627469Y1437072D03*
X1624853Y1440875D03*
X1634643Y1442982D03*
X1638785Y1442483D03*
X1637042Y1440215D03*
X1630643Y1443090D03*
X1635315Y1465745D03*
Y1462745D03*
X1632315Y1468745D03*
X1629815D03*
X1632315Y1465745D03*
X1629815D03*
X1632315Y1462745D03*
X1629815D03*
X1635315Y1468745D03*
Y1460245D03*
X1629815D03*
X1632315D03*
X1629815Y1457745D03*
X1632315D03*
X1635315D03*
X1639645Y1473645D03*
X1648972Y19495D03*
X1652372D03*
X1641867Y26431D03*
X1645267D03*
X1650020Y408952D03*
X1647310Y408922D03*
X1650020Y411452D03*
X1647310Y411422D03*
X1654110Y434177D03*
X1657755Y517910D03*
X1651851Y532057D03*
X1651112Y545572D03*
X1645530Y549160D03*
X1653230Y549322D03*
X1642720Y560862D03*
X1656238Y592113D03*
X1649833Y594946D03*
X1653794Y594956D03*
X1653774Y598576D03*
X1649844Y598555D03*
X1656955Y611090D03*
X1645300Y612202D03*
X1653220Y620662D03*
X1645681Y624011D03*
X1648581D03*
X1651481D03*
X1654809Y638101D03*
X1653319Y642311D03*
X1652351Y639573D03*
X1648811Y628277D03*
X1647081Y626211D03*
X1645917Y628917D03*
Y633577D03*
X1645167Y631247D03*
Y635907D03*
X1650081Y626111D03*
X1651711Y628277D03*
X1651635Y651836D03*
X1652581Y646311D03*
X1643582Y652601D03*
X1655637Y646311D03*
X1641082Y652601D03*
X1649363Y649485D03*
X1654809Y672101D03*
X1652351Y673573D03*
X1645681Y658011D03*
X1648581D03*
X1648811Y662277D03*
X1647081Y660211D03*
X1645917Y662917D03*
Y667577D03*
X1645167Y665247D03*
Y669907D03*
X1650081Y660111D03*
X1651481Y658011D03*
X1651711Y662277D03*
X1641082Y686601D03*
X1651635Y685836D03*
X1652581Y680311D03*
X1653319Y676311D03*
X1643582Y686601D03*
X1655113Y680835D03*
X1649363Y683485D03*
X1654809Y706101D03*
X1648811Y696277D03*
X1645167Y703907D03*
X1645917Y701577D03*
X1645167Y699247D03*
X1645917Y696917D03*
X1650081Y694111D03*
X1645681Y692011D03*
X1647081Y694211D03*
X1648581Y692011D03*
X1651711Y696277D03*
X1651481Y692011D03*
X1641082Y720601D03*
X1651635Y719836D03*
X1652581Y714311D03*
X1653319Y710311D03*
X1652351Y707573D03*
X1643582Y720601D03*
X1655637Y714311D03*
X1649363Y717485D03*
X1651509Y756492D03*
X1650771Y1367492D03*
X1648271D03*
X1645721D03*
X1648271Y1372492D03*
X1650771D03*
X1645721D03*
X1650771Y1369992D03*
X1648271D03*
X1645721D03*
X1648271Y1379992D03*
Y1382492D03*
X1650771Y1379992D03*
Y1382492D03*
X1648271Y1377492D03*
Y1374992D03*
X1650771Y1377492D03*
Y1374992D03*
X1645721Y1377492D03*
Y1374992D03*
Y1379992D03*
Y1382492D03*
X1641047Y1432876D03*
X1645707D03*
X1643377Y1433626D03*
X1648037D03*
X1655762Y1429794D03*
X1648677Y1436220D03*
X1653243Y1435690D03*
X1651043Y1434190D03*
X1653243Y1432790D03*
X1651143Y1437190D03*
X1653243Y1438590D03*
X1648677Y1439120D03*
X1655295Y1453879D03*
X1652295D03*
X1643065Y1462645D03*
Y1465645D03*
Y1468645D03*
Y1460145D03*
Y1457645D03*
X1655295Y1456899D03*
X1652295D03*
X1642645Y1473645D03*
X1646958Y1501553D03*
X1671828Y26431D03*
X1668100Y180852D03*
X1667739Y187187D03*
X1666690Y193290D03*
X1674432Y216981D03*
X1672596Y220541D03*
X1668426Y222432D03*
X1664866Y225162D03*
X1660861Y227548D03*
X1664970Y472112D03*
X1662447Y480619D03*
X1665790Y523417D03*
X1662262Y537334D03*
X1659740Y542222D03*
X1661872Y534703D03*
X1660243Y532071D03*
X1668917Y549992D03*
X1666902Y555115D03*
X1663502D03*
X1658738Y592113D03*
X1661238D03*
X1664197Y602191D03*
X1669222Y604490D03*
X1670700Y594562D03*
X1672500Y596462D03*
X1660660Y602273D03*
X1664410Y617953D03*
X1668920Y617637D03*
X1660754Y609837D03*
X1669397Y614064D03*
X1663471Y609837D03*
X1666686Y757162D03*
X1669303Y1372492D03*
X1664253D03*
X1666753D03*
X1669303Y1367492D03*
Y1369992D03*
X1666753Y1367492D03*
X1664253D03*
Y1369992D03*
X1666753D03*
X1669303Y1379992D03*
Y1382492D03*
Y1377492D03*
Y1374992D03*
X1666753Y1379992D03*
X1664253D03*
X1666753Y1382492D03*
X1664253D03*
X1666753Y1377492D03*
X1664253D03*
Y1374992D03*
X1666753D03*
X1662496Y1428791D03*
Y1431291D03*
X1665612Y1437072D03*
X1662996Y1440922D03*
X1672786Y1442982D03*
X1668786Y1440290D03*
Y1443256D03*
X1657920Y1453405D03*
X1660920D03*
X1657860Y1466545D03*
Y1464045D03*
X1657950Y1456210D03*
X1657860Y1459045D03*
Y1461545D03*
X1660950Y1456210D03*
X1660860Y1466545D03*
Y1464045D03*
Y1459045D03*
Y1461545D03*
X1666123Y1493362D03*
Y1501362D03*
Y1533862D03*
Y1520862D03*
Y1545862D03*
X1671673Y1550815D03*
X1666123Y1557557D03*
X1666198Y1561557D03*
X1671660Y1569412D03*
X1666198Y1581321D03*
X1678933Y19495D03*
X1682333D03*
X1686001Y26431D03*
X1689401D03*
X1675228D03*
X1678994Y217231D03*
X1690208Y421855D03*
X1689095Y462640D03*
X1684940Y463030D03*
X1685779Y491230D03*
X1690229Y481845D03*
X1687238Y485496D03*
X1681817Y495290D03*
X1675664Y513802D03*
X1690999Y513107D03*
X1683702Y514687D03*
X1676600Y523902D03*
X1688768Y518107D03*
X1689544Y543874D03*
X1689506Y539882D03*
X1679941Y552222D03*
X1678860Y556752D03*
X1683369Y562698D03*
Y566098D03*
X1676644Y655345D03*
Y652745D03*
X1679244Y655345D03*
X1681864Y655286D03*
X1679244Y652745D03*
X1676624Y642404D03*
X1676644Y644945D03*
Y647545D03*
Y650145D03*
X1679244Y642345D03*
X1681864Y642286D03*
X1679244Y644945D03*
Y647545D03*
X1681864Y644886D03*
Y647486D03*
Y650086D03*
Y652686D03*
X1679244Y650145D03*
X1673860Y726522D03*
X1681810Y752955D03*
X1688912Y1372492D03*
X1686362D03*
Y1367492D03*
Y1369992D03*
X1688912Y1367492D03*
Y1369992D03*
Y1377492D03*
Y1374992D03*
Y1382492D03*
Y1379992D03*
X1686362D03*
Y1382492D03*
Y1374992D03*
Y1377492D03*
X1679190Y1432876D03*
X1683850D03*
X1681520Y1433626D03*
X1686180D03*
X1686820Y1436520D03*
X1688886Y1434790D03*
X1688986Y1437790D03*
X1676928Y1442483D03*
X1675185Y1440215D03*
X1686820Y1439420D03*
X1680720Y1487062D03*
X1679508Y1498303D03*
X1678340Y1500862D03*
X1679508Y1517803D03*
X1677930Y1520362D03*
X1679508Y1538803D03*
X1678340Y1541362D03*
X1678230Y1590542D03*
X1674220Y1585321D03*
X1696506Y19495D03*
X1693106D03*
X1703617Y26459D03*
X1700217D03*
X1703570Y50649D03*
X1700170D03*
X1702490Y204780D03*
X1704223Y209707D03*
Y212207D03*
X1701164Y209758D03*
X1698566Y214904D03*
X1696066D03*
X1693725Y217409D03*
X1698566Y212404D03*
X1696066D03*
X1698725Y217409D03*
X1696225D03*
X1701164Y212258D03*
X1704264Y217458D03*
X1701264D03*
X1704264Y214958D03*
X1701264D03*
X1698566Y209704D03*
X1696066D03*
X1693466Y209504D03*
Y214704D03*
Y212204D03*
X1693725Y219909D03*
X1698725D03*
X1696225D03*
X1704264Y219958D03*
X1701264D03*
X1704185Y222710D03*
X1698220Y369652D03*
X1699809Y403985D03*
X1695579D03*
X1702959Y404243D03*
X1707780Y410738D03*
X1697161Y406602D03*
X1692429Y403985D03*
X1701124Y423802D03*
X1694050Y416643D03*
X1695455Y422287D03*
X1707544Y431745D03*
X1707568Y420370D03*
X1690140Y434160D03*
X1693720Y455862D03*
X1697220D03*
X1702127Y468719D03*
X1693236Y472650D03*
X1691151Y493678D03*
X1689943Y479304D03*
X1701811Y501318D03*
X1701635Y497177D03*
X1699300Y498632D03*
X1697210Y500802D03*
X1694050Y501422D03*
X1693711Y498527D03*
X1691129Y501697D03*
X1707200Y498962D03*
X1699553Y513107D03*
X1707552Y506731D03*
X1707716Y513562D03*
X1702930Y526102D03*
X1699265Y521507D03*
X1690999Y525507D03*
X1701726Y518107D03*
X1699666Y541507D03*
X1699251Y533642D03*
X1691104Y530503D03*
X1691445Y535011D03*
X1704886Y534564D03*
X1689769Y537339D03*
X1699107Y555783D03*
X1703306Y550064D03*
X1703452Y639381D03*
X1700852D03*
X1698232Y639440D03*
X1700852Y655141D03*
X1703452Y647341D03*
Y649941D03*
Y652541D03*
Y644741D03*
X1700852Y647341D03*
Y649941D03*
Y652541D03*
Y644741D03*
X1698232Y655200D03*
Y644800D03*
Y647400D03*
Y650000D03*
Y652600D03*
X1703452Y641981D03*
X1700852D03*
X1698232Y642040D03*
X1700922Y657781D03*
X1698302Y657840D03*
X1698048Y705662D03*
X1701320Y705678D03*
X1698020Y702962D03*
X1696402Y709533D03*
X1699110Y727452D03*
X1705035Y729210D03*
X1704973Y753019D03*
X1703310Y749455D03*
X1690620Y760702D03*
X1691412Y1372492D03*
Y1367492D03*
Y1369992D03*
Y1377492D03*
Y1374992D03*
Y1382492D03*
Y1379992D03*
X1691086Y1436290D03*
Y1433390D03*
X1693392Y1429808D03*
X1691086Y1439190D03*
X1704723Y1500862D03*
Y1520362D03*
Y1541362D03*
X1705003Y1564057D03*
X1707220Y15662D03*
X1715210Y18282D03*
X1714589Y21562D03*
X1709589Y26062D03*
X1719589Y25862D03*
X1717089D03*
X1710106Y48720D03*
Y40020D03*
X1720895Y68062D03*
X1716875D03*
X1712520Y117862D03*
X1712720Y111862D03*
X1719943Y112667D03*
Y116667D03*
X1713418Y130862D03*
X1721418Y135327D03*
X1717418D03*
X1714490Y142920D03*
X1717140Y148910D03*
X1711700Y140200D03*
X1717619Y165909D03*
X1718110Y159040D03*
X1719530Y162950D03*
X1722078Y189483D03*
X1720310Y191252D03*
X1707159Y217580D03*
Y215080D03*
Y210080D03*
Y222580D03*
Y225080D03*
Y220080D03*
X1713720Y381152D03*
X1717220D03*
X1719200Y371162D03*
X1713720Y391652D03*
Y384652D03*
Y388152D03*
X1717220Y391652D03*
Y388152D03*
Y384652D03*
X1709000Y413362D03*
X1706500D03*
X1709000Y415862D03*
X1706500D03*
X1721220Y458362D03*
X1713977Y457137D03*
X1708977Y458542D03*
X1721936Y469263D03*
X1716134Y478443D03*
X1715711Y474399D03*
X1713977Y470804D03*
X1708977D03*
X1716148Y483720D03*
X1716087Y495665D03*
X1716156Y487685D03*
X1716278Y491676D03*
X1707552Y503331D03*
X1709844Y516106D03*
X1707610Y534113D03*
X1709356Y541144D03*
X1709680Y545432D03*
X1716110Y532632D03*
X1707346Y547504D03*
X1717987Y569705D03*
X1716480Y691410D03*
X1710550Y691327D03*
X1712824Y696476D03*
X1710122Y703509D03*
X1713920Y700962D03*
X1709828Y719283D03*
X1713450Y728222D03*
X1719727Y1472088D03*
X1726720Y49862D03*
X1733720D03*
X1730220D03*
X1736040Y41792D03*
X1732810Y52482D03*
X1736040Y44292D03*
X1730140Y52552D03*
X1727600Y52582D03*
X1725320Y67962D03*
X1723018Y101667D03*
X1723218Y93267D03*
X1738220Y98862D03*
X1736720Y101862D03*
X1729080Y118132D03*
X1739720Y120892D03*
X1728999Y112895D03*
X1730765Y151362D03*
X1733920D03*
X1723670Y149102D03*
X1728320Y169862D03*
X1723090Y173072D03*
Y177072D03*
X1734857Y184865D03*
X1737470Y177147D03*
X1737500Y217962D03*
Y214962D03*
Y211962D03*
Y208962D03*
Y226962D03*
Y223962D03*
Y220962D03*
X1725344Y359334D03*
X1728300Y377787D03*
X1733780Y390620D03*
X1729810D03*
X1737660D03*
X1734290Y423820D03*
X1727700Y417265D03*
X1739316Y480939D03*
X1730954Y478062D03*
X1725522Y482869D03*
X1733354Y490869D03*
Y486869D03*
X1738014Y1287344D03*
X1724431Y1336311D03*
X1734717Y1404340D03*
X1729700Y1462932D03*
X1733200D03*
X1736700D03*
X1736400Y1458942D03*
Y1455442D03*
X1731600Y1457230D03*
X1726120Y1490262D03*
X1726149Y1496270D03*
X1724649Y1513945D03*
X1727674D03*
X1729310Y1520951D03*
X1735310D03*
X1724649Y1505895D03*
X1727674D03*
X1726310Y1530445D03*
X1732310D03*
X1729310D03*
X1735310D03*
X1726310Y1520951D03*
X1732310D03*
X1751065Y39017D03*
X1754620Y39062D03*
X1747720Y31862D03*
Y34362D03*
X1740858Y72330D03*
Y79830D03*
Y74830D03*
Y82330D03*
X1745220Y98862D03*
X1741720D03*
X1743720Y101862D03*
X1740220D03*
X1748720Y97362D03*
X1745010Y122952D03*
X1750820Y119972D03*
X1738520Y151362D03*
X1751220Y147562D03*
X1748465D03*
X1754120Y171562D03*
X1750920Y171662D03*
X1754234Y190836D03*
X1752078Y216728D03*
X1740500Y217962D03*
Y214962D03*
Y211962D03*
Y208962D03*
X1747600Y209062D03*
X1744600D03*
X1751800Y206762D03*
X1752078Y226728D03*
Y224228D03*
Y221728D03*
Y219228D03*
X1740500Y226962D03*
Y223962D03*
Y220962D03*
X1746484Y279682D03*
X1749450Y293862D03*
X1756204Y301695D03*
X1752000Y306562D03*
X1756933Y372452D03*
X1744380Y382892D03*
X1744510Y377452D03*
X1747080Y435870D03*
X1746720Y464862D03*
X1752316Y703969D03*
Y695669D03*
X1752217Y692988D03*
X1752276Y720529D03*
X1752316Y712269D03*
X1747814Y1287344D03*
X1742714Y1287244D03*
X1754165Y1304422D03*
Y1307422D03*
Y1301422D03*
Y1295422D03*
Y1298422D03*
Y1310422D03*
X1738740Y1451742D03*
X1740200Y1462932D03*
X1745111Y1463262D03*
X1747677Y1507388D03*
X1744677D03*
X1747304Y1524976D03*
X1744304D03*
X1762420Y21562D03*
X1765238Y22062D03*
X1768026Y24165D03*
X1769669Y15244D03*
X1761998Y15187D03*
X1765260Y18262D03*
X1757320Y15872D03*
X1758672Y26431D03*
X1755272D03*
X1767220Y26962D03*
X1758669Y50649D03*
X1755269D03*
X1762738Y53262D03*
X1767220Y53342D03*
X1767185Y48817D03*
X1767400Y39915D03*
X1769274Y50742D03*
X1771774Y53682D03*
X1758063Y72623D03*
X1767170Y83607D03*
X1767990Y76797D03*
X1760478Y90027D03*
X1770368Y72691D03*
X1757978Y116727D03*
X1760978D03*
X1763678Y106127D03*
X1769278Y108027D03*
Y110927D03*
Y113727D03*
X1755978Y108427D03*
Y111027D03*
X1760478Y106127D03*
X1758300Y128242D03*
X1763435Y166862D03*
X1765820Y182282D03*
X1767300Y174587D03*
X1755078Y216928D03*
X1761500Y214062D03*
X1765000D03*
X1768500D03*
X1755078Y219428D03*
Y221928D03*
Y224428D03*
X1760104Y301648D03*
X1761936Y310709D03*
X1769230Y310478D03*
X1756800Y364048D03*
Y368048D03*
X1770280Y372452D03*
X1770220Y377452D03*
Y382952D03*
X1757066Y435721D03*
X1757650Y461393D03*
X1768560Y539042D03*
X1766060D03*
X1768317Y686375D03*
X1755112Y703948D03*
Y695648D03*
X1755013Y692967D03*
X1757612Y703948D03*
Y695648D03*
X1755072Y720508D03*
X1755112Y712248D03*
X1757572Y720508D03*
X1757612Y712248D03*
X1757165Y1304422D03*
X1760165D03*
Y1307422D03*
X1757165D03*
X1769165Y1301422D03*
X1766165D03*
X1763165D03*
X1757165D03*
X1760165D03*
X1769165Y1295422D03*
X1766165D03*
X1763165D03*
X1760165D03*
X1757165D03*
X1760165Y1298422D03*
X1757165D03*
X1763165D03*
X1766165D03*
X1769165D03*
X1758352Y1317368D03*
Y1322168D03*
X1757165Y1310422D03*
X1760165D03*
X1759987Y1325375D03*
Y1328275D03*
X1763829Y1337548D03*
X1766829D03*
Y1340448D03*
X1769829Y1337548D03*
Y1340448D03*
X1766829Y1343348D03*
X1769829Y1346248D03*
Y1343348D03*
Y1349148D03*
Y1351858D03*
X1782305Y13647D03*
X1775556Y21471D03*
X1775830Y26522D03*
X1777754Y37746D03*
X1781774Y54462D03*
X1774274Y50742D03*
X1776710Y53562D03*
X1779411Y50692D03*
X1774328Y60087D03*
X1779778Y70027D03*
X1774328Y62987D03*
X1775580Y73330D03*
X1779778Y72927D03*
X1787790Y85132D03*
X1781485Y88192D03*
X1785142Y76032D03*
X1773611Y88293D03*
X1778578Y97927D03*
X1778478Y90627D03*
X1784178Y108227D03*
Y111127D03*
Y113927D03*
X1780320Y153162D03*
X1774950Y167392D03*
X1779500Y171692D03*
X1777520Y178403D03*
Y173903D03*
X1782600Y175932D03*
X1778778Y216928D03*
X1783878D03*
X1772000Y214062D03*
X1778778Y219428D03*
Y221928D03*
X1783878Y224428D03*
Y226928D03*
Y219428D03*
Y221928D03*
X1786089Y287641D03*
X1783563D03*
X1777354Y295489D03*
X1783018Y301729D03*
X1782324Y410432D03*
Y403932D03*
Y425432D03*
Y418932D03*
X1782420Y447137D03*
X1781470Y452065D03*
X1778310Y591152D03*
X1781720Y592742D03*
X1778165Y1307422D03*
Y1304422D03*
Y1301422D03*
X1775165D03*
X1772165D03*
X1778165Y1295422D03*
X1775165D03*
X1772165D03*
Y1298422D03*
X1775165D03*
X1778165D03*
X1784165Y1307422D03*
Y1304422D03*
X1781165Y1307422D03*
Y1304422D03*
X1784165Y1301422D03*
Y1295422D03*
Y1298422D03*
X1781165Y1301422D03*
Y1295422D03*
Y1298422D03*
X1781829Y1324448D03*
X1784829D03*
X1778829D03*
X1778165Y1310422D03*
Y1312922D03*
X1784165Y1310422D03*
Y1312922D03*
X1781165Y1310422D03*
Y1312922D03*
X1781829Y1333148D03*
Y1330248D03*
Y1327348D03*
X1784829Y1333148D03*
Y1330248D03*
Y1327348D03*
X1781829Y1337548D03*
Y1340448D03*
X1784829Y1337548D03*
Y1340448D03*
X1778829Y1333148D03*
Y1330248D03*
Y1327348D03*
Y1337548D03*
X1772829D03*
X1775829D03*
X1778829Y1340448D03*
X1775829D03*
X1772829D03*
X1781829Y1346248D03*
Y1343348D03*
Y1349148D03*
Y1351858D03*
Y1354758D03*
X1772829Y1346248D03*
X1775829D03*
X1778829D03*
X1772829Y1343348D03*
X1775829D03*
X1778829D03*
X1772829Y1349148D03*
X1775829D03*
X1778829D03*
X1772829Y1351858D03*
X1775829D03*
X1778829D03*
X1772829Y1354758D03*
X1775829D03*
X1778829D03*
X1799920Y52594D03*
X1788238Y82292D03*
Y78062D03*
Y74912D03*
X1803215Y154032D03*
X1793269Y287641D03*
X1790743D03*
X1791619Y294441D03*
X1789093D03*
X1800160Y362542D03*
X1800340Y387062D03*
X1791494Y386536D03*
X1792450Y410615D03*
X1792507Y403932D03*
X1792220Y425432D03*
X1792335Y418775D03*
X1796020Y451162D03*
X1791888Y683805D03*
X1800450Y1505230D03*
X1795561Y1524729D03*
X1806920Y150862D03*
X1808910Y143902D03*
X1813335Y155435D03*
X1813325Y177257D03*
X1807220Y179897D03*
X1817157Y373829D03*
X1816224Y410432D03*
X1816994Y398052D03*
X1815724Y423932D03*
X1810792Y417432D03*
X1812161Y472521D03*
X1814537Y1322105D03*
X1813700Y1494762D03*
X1807150Y1505675D03*
X1818289Y1501591D03*
X1811494Y1505349D03*
X1813994Y1507891D03*
X1825762Y167662D03*
X1835760Y185772D03*
X1829695Y226333D03*
X1832295D03*
X1827095D03*
X1824095D03*
X1834895D03*
Y223733D03*
X1824095D03*
X1827095D03*
X1832295D03*
X1829695D03*
X1832295Y233933D03*
X1829695D03*
X1827095D03*
X1824095D03*
X1829695Y231433D03*
X1832295D03*
X1829695Y228933D03*
X1832295D03*
X1827095Y231433D03*
X1824095D03*
X1827095Y228933D03*
X1824095D03*
X1834895Y233933D03*
Y231433D03*
Y228933D03*
X1828204Y328654D03*
X1829189Y363731D03*
X1829434Y406348D03*
X1834005Y401421D03*
X1821280Y413432D03*
X1834600Y406442D03*
X1826914Y431718D03*
X1829514Y1498198D03*
Y1500807D03*
X1832114Y1498198D03*
Y1500807D03*
X1824995Y1502201D03*
X1846691Y166450D03*
X1844157Y182210D03*
X1848435Y172187D03*
X1838880Y195162D03*
X1837895Y226333D03*
Y223733D03*
Y233933D03*
Y231433D03*
Y228933D03*
X1836294Y383592D03*
X1838379Y453921D03*
G54D31*
X174685Y647210D03*
X174393Y678354D03*
X195316Y1430034D03*
X383224Y1354446D03*
X412990D03*
X443326D03*
X458600Y1379662D03*
X472700Y1353962D03*
X526478Y1449795D03*
X708795Y1429579D03*
X1131715Y1532913D03*
X1168627Y1466363D03*
X1175215Y1532913D03*
X1359365Y1353946D03*
X1389131D03*
X1419467D03*
X1434200Y1379362D03*
X1449233Y1353946D03*
X1502956Y1449373D03*
X1670101Y1463655D03*
X1682882Y628017D03*
Y678952D03*
X1769790Y204632D03*
X1799350D03*
X1826405Y269763D03*
Y299056D03*
G54D26*
X70472Y173228D03*
Y236220D03*
G54D45*
X450000Y278543D03*
X470000D03*
X483500Y246362D03*
X473500D03*
X480000Y278543D03*
X490000D03*
X500000D03*
X498563Y607067D03*
X510000Y278543D03*
X520000D03*
X518563Y607067D03*
X508563D03*
X549236Y1441207D03*
X569236D03*
X688500Y1611900D03*
Y1621900D03*
X1041435Y143357D03*
X1056225Y143131D03*
X1041435Y163357D03*
X1056225Y163131D03*
X1099970Y1712570D03*
Y1722570D03*
X1689646Y115669D03*
X1679646D03*
X1689646Y125669D03*
Y135669D03*
X1679646Y125669D03*
Y135669D03*
X1689646Y145669D03*
Y155669D03*
X1679646Y145669D03*
Y155669D03*
X1689646Y165669D03*
X1679646D03*
X1689646Y175669D03*
X1679646D03*
X1771457Y1624646D03*
Y1644646D03*
G54D17*
X27699Y1258727D03*
Y1255381D03*
Y1265420D03*
Y1262074D03*
X36399Y960892D03*
Y957546D03*
Y967585D03*
X43841Y994357D03*
X36399Y1054593D03*
X43841Y1255381D03*
Y1258727D03*
Y1252034D03*
Y1262074D03*
Y1265420D03*
X57299Y766798D03*
X52541Y964239D03*
Y957546D03*
Y954200D03*
Y1021129D03*
Y1024475D03*
Y1051247D03*
X57399Y1258727D03*
X52820Y1253862D03*
X57399Y1265420D03*
Y1262074D03*
X66099Y780184D03*
Y773491D03*
Y786877D03*
Y803609D03*
Y796916D03*
Y790223D03*
Y816995D03*
Y810302D03*
Y833727D03*
Y823688D03*
Y827034D03*
Y847113D03*
Y840420D03*
Y853806D03*
Y860499D03*
Y863845D03*
Y883924D03*
Y877231D03*
Y870538D03*
Y890617D03*
Y897310D03*
Y900656D03*
Y914042D03*
Y907349D03*
Y927428D03*
Y920735D03*
Y934121D03*
Y944160D03*
Y937467D03*
Y960892D03*
Y950853D03*
Y957546D03*
Y980971D03*
Y974278D03*
Y967585D03*
Y994357D03*
Y987664D03*
Y1027822D03*
Y1021129D03*
Y1047900D03*
Y1041207D03*
Y1034515D03*
Y1061286D03*
Y1054593D03*
Y1074672D03*
Y1067979D03*
Y1091404D03*
Y1081365D03*
Y1084711D03*
Y1098097D03*
Y1111483D03*
Y1104790D03*
Y1128215D03*
Y1118176D03*
Y1121522D03*
Y1141601D03*
Y1134908D03*
Y1148294D03*
Y1154987D03*
Y1158333D03*
Y1171719D03*
Y1165026D03*
Y1185105D03*
Y1178412D03*
Y1191798D03*
Y1208530D03*
Y1201837D03*
Y1195144D03*
Y1221916D03*
Y1215223D03*
Y1238648D03*
Y1228609D03*
Y1231955D03*
Y1245341D03*
X73541Y1255381D03*
Y1258727D03*
Y1252034D03*
Y1265420D03*
Y1262074D03*
X82241Y770144D03*
X86999Y766798D03*
X82241Y776837D03*
Y786877D03*
Y783530D03*
Y800263D03*
Y793570D03*
Y813648D03*
Y806955D03*
Y820341D03*
Y830381D03*
Y823688D03*
Y850459D03*
Y843766D03*
Y837074D03*
Y867192D03*
Y860499D03*
Y857152D03*
Y873885D03*
Y880577D03*
Y887270D03*
Y897310D03*
Y893963D03*
Y917389D03*
Y910696D03*
Y904003D03*
Y924081D03*
Y934121D03*
Y930774D03*
Y947507D03*
Y940814D03*
Y964239D03*
Y957546D03*
Y954200D03*
Y977625D03*
Y970932D03*
Y991011D03*
Y984318D03*
Y994357D03*
Y1021129D03*
Y1024475D03*
Y1031168D03*
Y1044554D03*
Y1037861D03*
Y1051247D03*
Y1071326D03*
Y1064633D03*
Y1078018D03*
Y1094751D03*
Y1088058D03*
Y1081365D03*
Y1108137D03*
Y1101444D03*
Y1124869D03*
Y1118176D03*
Y1114829D03*
Y1144948D03*
Y1138255D03*
Y1131562D03*
Y1161680D03*
Y1154987D03*
Y1151641D03*
Y1175066D03*
Y1168373D03*
Y1181759D03*
Y1191798D03*
Y1188452D03*
Y1205184D03*
Y1198491D03*
Y1218570D03*
Y1211877D03*
Y1225263D03*
Y1241995D03*
Y1235302D03*
Y1228609D03*
X87099Y1258727D03*
X82241Y1248688D03*
X84334Y1254263D03*
X87099Y1265420D03*
Y1262074D03*
X95799Y960892D03*
Y957546D03*
X103241Y994357D03*
Y1255381D03*
Y1258727D03*
Y1252034D03*
Y1265420D03*
Y1262074D03*
X116567Y766775D03*
X125499Y780184D03*
Y773491D03*
Y786877D03*
Y803609D03*
Y796916D03*
Y790223D03*
Y847113D03*
Y853806D03*
Y860499D03*
Y863845D03*
Y883924D03*
Y877231D03*
Y870538D03*
Y890617D03*
Y897310D03*
Y900656D03*
Y914042D03*
Y907349D03*
Y960892D03*
Y957546D03*
X111941D03*
Y954200D03*
X125499Y1061286D03*
Y1074672D03*
Y1067979D03*
Y1091404D03*
Y1081365D03*
Y1084711D03*
Y1098097D03*
Y1111483D03*
Y1104790D03*
Y1128215D03*
Y1118176D03*
Y1121522D03*
Y1134908D03*
Y1185105D03*
Y1178412D03*
Y1191798D03*
Y1208530D03*
Y1201837D03*
Y1195144D03*
X116799Y1258727D03*
X111941Y1248688D03*
X114191Y1254604D03*
X116799Y1265420D03*
Y1262074D03*
X141641Y770144D03*
Y776837D03*
Y786877D03*
Y783530D03*
Y800263D03*
Y793570D03*
Y850459D03*
Y843766D03*
Y867192D03*
Y860499D03*
Y857152D03*
Y873885D03*
Y880577D03*
Y887270D03*
Y897310D03*
Y893963D03*
Y910696D03*
Y904003D03*
Y957546D03*
Y954200D03*
Y994357D03*
Y1057940D03*
Y1071326D03*
Y1064633D03*
Y1078018D03*
Y1094751D03*
Y1088058D03*
Y1081365D03*
Y1108137D03*
Y1101444D03*
Y1124869D03*
Y1118176D03*
Y1114829D03*
Y1131562D03*
Y1175066D03*
Y1181759D03*
Y1191798D03*
Y1188452D03*
Y1205184D03*
Y1198491D03*
X129933Y1238461D03*
X132941Y1255381D03*
Y1258727D03*
Y1252034D03*
X141641Y1248688D03*
X143675Y1255567D03*
X132941Y1265420D03*
Y1262074D03*
X146367Y766775D03*
X155199Y960892D03*
Y957546D03*
X160130Y1251847D03*
X146499Y1258727D03*
Y1265420D03*
Y1262074D03*
X176099Y766798D03*
X171341Y957546D03*
Y954200D03*
X162641Y994357D03*
X176199Y1258727D03*
X162641Y1255381D03*
Y1258727D03*
Y1252034D03*
X171341Y1248688D03*
X171947Y1255837D03*
X176199Y1265420D03*
X162641D03*
Y1262074D03*
X176199D03*
X184899Y960892D03*
Y957546D03*
Y1061286D03*
X192341Y1255381D03*
Y1258727D03*
Y1252034D03*
Y1265420D03*
Y1262074D03*
X188897Y1578182D03*
X192297D03*
X188897Y1590094D03*
X192297D03*
X205799Y766798D03*
X201041Y957546D03*
Y954200D03*
Y994357D03*
X205899Y1258727D03*
X201041Y1248688D03*
X201193Y1257900D03*
X205899Y1265420D03*
Y1262074D03*
X200957Y1578182D03*
X204357D03*
X200957Y1590094D03*
X204357D03*
X194197Y1614292D03*
X197597D03*
X206257D03*
X214599Y960892D03*
Y957546D03*
X222041D03*
Y954200D03*
Y994357D03*
Y1255381D03*
X219660Y1260492D03*
X222041Y1252034D03*
Y1265420D03*
Y1262074D03*
X225077Y1578182D03*
X213017D03*
X216417D03*
X225077Y1590094D03*
X213017D03*
X216417D03*
X209657Y1614292D03*
X218317D03*
X221717D03*
X235499Y766798D03*
X236391Y1002557D03*
X240521Y1000395D03*
X237841Y1000437D03*
X233891Y1002557D03*
X231391D03*
X228891D03*
X235599Y1258727D03*
X230741Y1248688D03*
X235480Y1265406D03*
X235599Y1262074D03*
X237137Y1578182D03*
X240537D03*
X228477D03*
X237137Y1590094D03*
X240537D03*
X228477D03*
X230377Y1614292D03*
X233777D03*
X244299Y960892D03*
Y957546D03*
X251741D03*
Y954200D03*
Y994357D03*
X254881Y999650D03*
X257561Y999608D03*
X244299Y1061286D03*
X248047Y1259155D03*
X250467Y1259175D03*
X251707Y1252034D03*
X249603Y1266204D03*
X251699Y1265254D03*
X249197Y1578182D03*
X252597D03*
X249197Y1590094D03*
X252597D03*
X242437Y1614292D03*
X254497D03*
X245837D03*
X272529Y111053D03*
X265442D03*
X261899D03*
Y108553D03*
X265442D03*
X268985Y111053D03*
Y108553D03*
X272529D03*
X260441Y1057940D03*
Y1248688D03*
X273317Y1578182D03*
X261257D03*
X264657D03*
X273317Y1590094D03*
X261257D03*
X264657D03*
X266557Y1614292D03*
X257897D03*
X269957D03*
X285377Y1578182D03*
X288777D03*
X276717D03*
X285377Y1590094D03*
X288777D03*
X276717D03*
X278617Y1614292D03*
X282017D03*
X297437Y1578182D03*
X300837D03*
X297437Y1590094D03*
X300837D03*
X290677Y1614292D03*
X302737D03*
X294077D03*
X306137D03*
X321557Y1578182D03*
X309497D03*
X312897D03*
X321557Y1590094D03*
X309497D03*
X312897D03*
X314797Y1614292D03*
X318197D03*
X333617Y1578182D03*
X337017D03*
X324957D03*
X333617Y1590094D03*
X337017D03*
X324957D03*
X330257Y1614292D03*
X338917D03*
X326857D03*
X345677Y1578182D03*
X349077D03*
X345677Y1590094D03*
X349077D03*
X350977Y1614292D03*
X342317D03*
X354377D03*
X369797Y1578182D03*
X357737D03*
X361137D03*
X369797Y1590094D03*
X357737D03*
X361137D03*
X363037Y1614292D03*
X366437D03*
X373197Y1578182D03*
Y1590094D03*
X375097Y1614292D03*
X378497D03*
X476451Y1578182D03*
X485111D03*
X473051D03*
X476451Y1590094D03*
X485111D03*
X473051D03*
X478351Y1614292D03*
X481751D03*
X500571Y1578182D03*
X488511D03*
X497171D03*
X500571Y1590094D03*
X488511D03*
X497171D03*
X490411Y1614292D03*
X493811D03*
X512631Y1578182D03*
X509231D03*
X512631Y1590094D03*
X509231D03*
X514531Y1614292D03*
X502471D03*
X517931D03*
X505871D03*
X524691Y1578182D03*
X533351D03*
X521291D03*
X524691Y1590094D03*
X533351D03*
X521291D03*
X526591Y1614292D03*
X529991D03*
X536751Y1578182D03*
X548811D03*
X545411D03*
X536751Y1590094D03*
X548811D03*
X545411D03*
X538651Y1614292D03*
X542051D03*
X560871Y1578182D03*
X557471D03*
X560871Y1590094D03*
X557471D03*
X562771Y1614292D03*
X550711D03*
X566171D03*
X554111D03*
X572931Y1578182D03*
X581591D03*
X569531D03*
X572931Y1590094D03*
X581591D03*
X569531D03*
X574831Y1614292D03*
X578231D03*
X597051Y1578182D03*
X584991D03*
X593651D03*
X597051Y1590094D03*
X584991D03*
X593651D03*
X598951Y1614292D03*
X586891D03*
X590291D03*
X609111Y1578182D03*
X605711D03*
X609111Y1590094D03*
X605711D03*
X611011Y1614292D03*
X614411D03*
X602351D03*
X629658Y766478D03*
X620799Y960892D03*
Y957546D03*
X623347Y999665D03*
X625780Y1000198D03*
X620899Y1061286D03*
X629931Y1258727D03*
X632080Y1262074D03*
X629699Y1255381D03*
X631270Y1264942D03*
X621171Y1578182D03*
X629831D03*
X617771D03*
X621171Y1590094D03*
X629831D03*
X617771D03*
X623071Y1614292D03*
X626471D03*
X636941Y957546D03*
Y954200D03*
X644347Y1003135D03*
X640327D03*
X640467Y1000735D03*
X647447Y1002865D03*
X647397Y1000135D03*
X644257Y1000325D03*
X636946Y1258414D03*
X647690Y1260812D03*
X637041Y1252034D03*
X645897Y1248785D03*
X647877Y1254076D03*
X636877Y1261235D03*
X645291Y1578182D03*
X633231D03*
X641891D03*
X645291Y1590094D03*
X633231D03*
X641891D03*
X647191Y1614292D03*
X635131D03*
X638531D03*
X667677Y441636D03*
X650499Y960892D03*
Y957546D03*
X650107Y1002825D03*
X650599Y1258727D03*
X666741Y1255381D03*
X664630Y1259442D03*
X649587Y1266766D03*
X661400Y1263522D03*
X657351Y1578182D03*
X653951D03*
X657351Y1590094D03*
X653951D03*
X662651Y1614292D03*
X659251D03*
X650591D03*
X674628Y424313D03*
X671479Y421163D03*
X667660Y429037D03*
X674628Y427462D03*
X677778Y414864D03*
Y424313D03*
X671479Y414864D03*
X674628Y421163D03*
Y418013D03*
X677778D03*
Y421163D03*
X668329D03*
X677778Y427462D03*
Y430612D03*
X674628Y436911D03*
X671479D03*
X677778Y433761D03*
X668329Y436911D03*
X677778Y440061D03*
X674628D03*
X677778Y436911D03*
Y443210D03*
X680928Y440061D03*
X674628Y430612D03*
X671479Y443211D03*
X677778Y449510D03*
X668329Y452659D03*
X674628D03*
X671479D03*
X677778D03*
X668329Y455809D03*
X671479Y458959D03*
X674628D03*
X668329D03*
X677778D03*
Y455809D03*
X674628D03*
X668067Y462090D03*
X677778Y462108D03*
X671479Y455809D03*
X680928Y458959D03*
X674628Y449510D03*
Y462108D03*
X677778Y477856D03*
Y471557D03*
Y474707D03*
X671479Y465258D03*
X674628D03*
X668329D03*
X677778D03*
Y468407D03*
X671479Y481006D03*
X667350Y470680D03*
X671479Y474707D03*
X674628Y484006D03*
X680299Y766798D03*
Y960892D03*
Y957546D03*
X666641D03*
Y954200D03*
X672063Y998632D03*
X680299Y1061286D03*
Y1258727D03*
X666741Y1252034D03*
X675537Y1248885D03*
X677980Y1262074D03*
X666741D03*
X666646Y1264464D03*
X680046Y1264964D03*
X695055Y112678D03*
Y115178D03*
X687227Y414864D03*
X690376Y421163D03*
Y418013D03*
Y414864D03*
X693526Y427462D03*
X687227Y424313D03*
X690376Y427462D03*
X680928Y414864D03*
Y418013D03*
X684077Y421163D03*
X680928Y427462D03*
X684077Y418013D03*
Y427462D03*
X680928Y421163D03*
X684077Y424313D03*
X687227Y427462D03*
X696676D03*
X693526Y421163D03*
Y424313D03*
X690376D03*
X696676Y421163D03*
Y424313D03*
Y418013D03*
X680928Y436911D03*
Y433761D03*
X693526Y430612D03*
X696676Y440061D03*
Y443210D03*
X684077Y430612D03*
Y440061D03*
X687227Y436911D03*
Y443210D03*
X684077D03*
Y436911D03*
X680928Y443210D03*
X690376Y436911D03*
Y443210D03*
X687227Y440061D03*
X693526Y433761D03*
X696676D03*
X684077D03*
X687227Y430612D03*
X690376D03*
X696676D03*
X687227Y433761D03*
X680928Y430612D03*
X687227Y462108D03*
X680928Y455809D03*
X693526Y462108D03*
X680928Y449510D03*
X687227D03*
X690376Y462108D03*
X684077Y449510D03*
X680928Y452659D03*
X684077D03*
X687227Y455809D03*
X684077D03*
X680928Y462108D03*
X696676Y449510D03*
Y452659D03*
X690376Y449510D03*
Y455809D03*
X687227Y452659D03*
X693526Y458959D03*
X696676D03*
Y462108D03*
X687227Y458959D03*
X684077D03*
Y468407D03*
X687227Y471557D03*
Y474707D03*
Y477856D03*
X684077Y471557D03*
X690376Y465258D03*
X684077D03*
X680928Y471557D03*
Y474707D03*
Y477856D03*
X693526Y465258D03*
Y471557D03*
X690376Y468407D03*
Y477856D03*
Y471557D03*
X687227Y465258D03*
X690376Y474707D03*
X687227Y468407D03*
X693526D03*
X684077Y474707D03*
X696676Y465258D03*
Y474707D03*
Y468407D03*
X693526Y474707D03*
X696676Y471557D03*
X693526Y477856D03*
X696441Y957546D03*
Y954200D03*
Y994357D03*
Y1255381D03*
X694100Y1261562D03*
X696441Y1248688D03*
X692233Y1252480D03*
X696046Y1263764D03*
X698598Y115178D03*
X705685D03*
X702141D03*
X698598Y112678D03*
X705685D03*
X702141D03*
X706125Y418013D03*
X712424Y424313D03*
X699825Y427462D03*
X699826Y414864D03*
X699825Y424313D03*
X712424Y430612D03*
X709274Y440061D03*
Y443210D03*
X706125D03*
X699825D03*
X709274Y433761D03*
X712424D03*
X699825D03*
X706125D03*
X699825Y430612D03*
X706125Y462108D03*
X709274D03*
X712424D03*
X709274Y449510D03*
X699825D03*
X706125D03*
X709274Y452659D03*
X699825Y458959D03*
X706125D03*
X709274D03*
X712424D03*
X699825Y462108D03*
X709274Y474707D03*
Y471557D03*
Y465258D03*
Y468407D03*
X712424Y474707D03*
Y468407D03*
Y465258D03*
X706125Y471557D03*
Y468407D03*
X699825Y471557D03*
Y474707D03*
X706125Y477856D03*
X699825Y465258D03*
X712424Y471557D03*
X706125Y481006D03*
X709899Y766798D03*
Y960892D03*
Y957546D03*
X709999Y1258727D03*
X708090Y1262074D03*
X705037Y1252034D03*
X706493Y1256563D03*
X705167Y1262074D03*
X709977Y1264985D03*
X721873Y427462D03*
X725022D03*
X728172Y418013D03*
X718723D03*
X715574Y427462D03*
X728172Y421163D03*
X718723Y414864D03*
X725022Y424313D03*
X721873D03*
X725022Y421163D03*
X728172Y427462D03*
X731322Y421163D03*
X725022Y418013D03*
X718723Y427462D03*
Y424313D03*
Y421163D03*
X715574Y424313D03*
Y421163D03*
Y418013D03*
X728172Y424313D03*
X718723Y436911D03*
X721873Y433761D03*
Y436911D03*
Y440061D03*
Y430612D03*
X718723Y433761D03*
Y440061D03*
X725022Y436911D03*
Y433761D03*
X728172D03*
X718723Y430612D03*
X715574D03*
X725022D03*
X728172Y436911D03*
X715574D03*
Y440061D03*
Y443210D03*
X728172D03*
Y430612D03*
X725022Y440061D03*
X718723Y443210D03*
X721873D03*
X725022D03*
X728172Y440061D03*
X731322D03*
X728172Y455809D03*
Y458959D03*
X718723Y455809D03*
X721873Y458959D03*
Y452659D03*
X725022D03*
X728172D03*
X715574Y462108D03*
X725022Y458959D03*
X721873Y455809D03*
X725022Y462108D03*
X718723Y452659D03*
X715574Y449510D03*
Y452659D03*
Y455809D03*
X728172Y462108D03*
X718723Y449510D03*
X721873D03*
X725022D03*
X718723Y458959D03*
X721873Y462108D03*
X718723D03*
X725022Y468407D03*
X721873Y465258D03*
Y477856D03*
X718723Y468407D03*
X715574Y474707D03*
Y471557D03*
Y468407D03*
Y465258D03*
X718723Y474707D03*
Y471557D03*
X728172Y477856D03*
X721873Y471557D03*
X725022D03*
X718723Y465258D03*
X728172D03*
X725022Y474707D03*
X728172Y468407D03*
X721873Y474707D03*
Y468407D03*
X728172Y474707D03*
Y471557D03*
X725022Y465258D03*
X718723Y477856D03*
X725132Y481116D03*
X728272Y481006D03*
X726041Y957546D03*
Y954200D03*
Y994357D03*
X726141Y1057940D03*
Y1255381D03*
X723700Y1258727D03*
X726141Y1248688D03*
Y1262074D03*
X726107Y1265420D03*
X734471Y418013D03*
X731322Y427462D03*
Y418013D03*
X734471Y421163D03*
X731322Y424313D03*
X734471D03*
X737621D03*
X731322Y414864D03*
Y433761D03*
X734471Y436911D03*
X731322D03*
X734471Y443210D03*
X737621D03*
X731322D03*
Y455809D03*
X737621Y458959D03*
X731322D03*
X734471Y452659D03*
X731322D03*
Y449510D03*
X734471Y458959D03*
X731322Y465258D03*
Y477856D03*
X737621Y471557D03*
X734471Y468407D03*
X731322D03*
X731321Y474707D03*
X731322Y471557D03*
X734471Y481006D03*
X739699Y766798D03*
Y780184D03*
Y773491D03*
Y786877D03*
Y803609D03*
Y796916D03*
Y790223D03*
Y847113D03*
Y853806D03*
Y860499D03*
Y863845D03*
Y883924D03*
Y877231D03*
Y870538D03*
Y890617D03*
Y897310D03*
Y900656D03*
Y914042D03*
Y907349D03*
Y960892D03*
Y957546D03*
Y1061286D03*
Y1074672D03*
Y1067979D03*
Y1091404D03*
Y1081365D03*
Y1084711D03*
Y1098097D03*
Y1111483D03*
Y1104790D03*
Y1128215D03*
Y1118176D03*
Y1121522D03*
Y1134908D03*
Y1185105D03*
Y1178412D03*
Y1191798D03*
Y1208530D03*
Y1201837D03*
Y1195144D03*
Y1258727D03*
X734967Y1252034D03*
X737580Y1262074D03*
X739697Y1265420D03*
X755841Y770144D03*
Y776837D03*
Y786877D03*
Y783530D03*
Y800263D03*
Y793570D03*
Y850459D03*
Y843766D03*
Y867192D03*
Y860499D03*
Y857152D03*
Y873885D03*
Y880577D03*
Y887270D03*
Y897310D03*
Y893963D03*
Y910696D03*
Y904003D03*
Y957546D03*
Y954200D03*
Y994357D03*
X755541Y1057940D03*
X755676Y1071326D03*
X755741Y1064633D03*
X755841Y1078018D03*
Y1094751D03*
Y1088058D03*
Y1081365D03*
X755676Y1108137D03*
X755841Y1101444D03*
Y1124869D03*
Y1118176D03*
Y1114829D03*
Y1131562D03*
Y1175066D03*
X755676Y1181759D03*
X755841Y1191798D03*
X755676Y1188452D03*
X755841Y1205184D03*
Y1198491D03*
X750890Y1248500D03*
X755890Y1255381D03*
X753000Y1261352D03*
X755841Y1252034D03*
Y1248688D03*
X750040Y1254179D03*
X755841Y1262074D03*
X755797Y1265420D03*
X769399Y766798D03*
Y960892D03*
Y957546D03*
Y1258727D03*
X767080Y1262074D03*
X766148Y1255882D03*
X769399Y1265420D03*
X785541Y957546D03*
Y954200D03*
Y994357D03*
Y1255381D03*
X783130Y1259372D03*
X794157Y1252034D03*
X785541Y1248688D03*
X796880Y1262074D03*
X796280Y1254402D03*
X785541Y1265420D03*
Y1262074D03*
X797417Y767345D03*
X799099Y780184D03*
Y773491D03*
Y786877D03*
Y803609D03*
Y796916D03*
Y790223D03*
Y816995D03*
Y810302D03*
Y833727D03*
Y823688D03*
Y827034D03*
Y847113D03*
Y840420D03*
Y853806D03*
Y860499D03*
Y863845D03*
Y883924D03*
Y877231D03*
Y870538D03*
Y890617D03*
Y897310D03*
Y900656D03*
Y914042D03*
Y907349D03*
Y927428D03*
Y920735D03*
Y934121D03*
Y944160D03*
Y937467D03*
Y960892D03*
Y950853D03*
Y957546D03*
Y980971D03*
Y974278D03*
Y967585D03*
Y994357D03*
Y987664D03*
Y1027822D03*
Y1021129D03*
Y1047900D03*
Y1041207D03*
Y1034515D03*
Y1061286D03*
Y1054593D03*
Y1074672D03*
Y1067979D03*
Y1091404D03*
Y1081365D03*
Y1084711D03*
Y1098097D03*
Y1111483D03*
Y1104790D03*
Y1128215D03*
Y1118176D03*
Y1121522D03*
Y1141601D03*
Y1134908D03*
Y1148294D03*
Y1154987D03*
Y1158333D03*
Y1171719D03*
Y1165026D03*
Y1185105D03*
Y1178412D03*
Y1191798D03*
Y1208530D03*
Y1201837D03*
Y1195144D03*
Y1221916D03*
Y1215223D03*
Y1238648D03*
Y1228609D03*
Y1231955D03*
Y1245341D03*
Y1258727D03*
X812440D03*
X799099Y1265420D03*
X815241Y770144D03*
Y776837D03*
Y786877D03*
Y783530D03*
Y800263D03*
Y793570D03*
Y813648D03*
Y806955D03*
Y820341D03*
Y830381D03*
Y823688D03*
Y850459D03*
Y843766D03*
Y837074D03*
Y867192D03*
Y860499D03*
Y857152D03*
Y873885D03*
Y880577D03*
Y887270D03*
Y897310D03*
Y893963D03*
Y917389D03*
Y910696D03*
Y904003D03*
Y924081D03*
Y934121D03*
Y930774D03*
Y947507D03*
Y940814D03*
Y964239D03*
Y957546D03*
Y954200D03*
Y977625D03*
Y970932D03*
Y991011D03*
Y984318D03*
Y994357D03*
Y1021129D03*
Y1024475D03*
Y1031168D03*
Y1044554D03*
Y1037861D03*
X814941Y1051247D03*
X815241Y1071325D03*
Y1064633D03*
Y1078018D03*
Y1094751D03*
Y1088058D03*
Y1081365D03*
Y1108136D03*
Y1101444D03*
Y1124869D03*
Y1118176D03*
Y1114829D03*
Y1144947D03*
Y1138255D03*
Y1131562D03*
Y1161680D03*
Y1154987D03*
Y1151640D03*
Y1175066D03*
Y1168373D03*
Y1181758D03*
Y1191798D03*
Y1188451D03*
Y1205184D03*
Y1198491D03*
Y1218570D03*
Y1211877D03*
Y1225263D03*
Y1241995D03*
Y1235302D03*
Y1228609D03*
Y1255381D03*
X826750Y1262074D03*
X823877Y1252034D03*
X815241Y1248688D03*
X826501Y1254553D03*
X815241Y1265420D03*
Y1262074D03*
X828699Y766798D03*
X828799Y960892D03*
Y957546D03*
Y967585D03*
Y1054593D03*
Y1258727D03*
X842630Y1256912D03*
X828799Y1265420D03*
X844941Y964239D03*
X844841Y957546D03*
Y954200D03*
Y994357D03*
X844941Y1021129D03*
Y1024475D03*
Y1051247D03*
Y1258727D03*
Y1252034D03*
X844997Y1248155D03*
X844941Y1265420D03*
Y1262074D03*
X998205Y195735D03*
Y192191D03*
X1000705Y195735D03*
Y192191D03*
X998205Y199278D03*
X1000705D03*
X998205Y202821D03*
X1000705D03*
X1001970Y1251522D03*
X1003831Y1259077D03*
X1002070Y1256942D03*
X1003841Y1265420D03*
Y1262074D03*
X1012769Y766798D03*
X1012541Y960892D03*
Y957546D03*
Y967585D03*
X1019983Y994357D03*
X1012541Y1054593D03*
X1017900Y1247632D03*
X1019983Y1255381D03*
Y1252034D03*
Y1248688D03*
Y1262074D03*
Y1265420D03*
X1033441Y766798D03*
X1028683Y964239D03*
Y957546D03*
Y954200D03*
Y1021129D03*
Y1024475D03*
Y1051247D03*
X1033541Y1258727D03*
X1030830Y1261302D03*
X1030270Y1256042D03*
X1033541Y1265420D03*
X1042241Y780184D03*
Y773491D03*
Y786877D03*
Y803609D03*
Y796916D03*
Y790223D03*
Y816995D03*
Y810302D03*
Y833727D03*
Y823688D03*
Y827034D03*
Y847113D03*
Y840420D03*
Y853806D03*
Y860499D03*
Y863845D03*
Y883924D03*
Y877231D03*
Y870538D03*
Y890617D03*
Y897310D03*
Y900656D03*
Y914042D03*
Y907349D03*
Y927428D03*
Y920735D03*
Y934121D03*
Y944160D03*
Y937467D03*
Y960892D03*
Y950853D03*
Y957546D03*
Y980971D03*
Y974278D03*
Y967585D03*
Y994357D03*
Y987664D03*
Y1027822D03*
Y1021129D03*
Y1047900D03*
Y1041207D03*
Y1034515D03*
Y1061286D03*
Y1054593D03*
Y1074672D03*
Y1067979D03*
Y1091404D03*
Y1081365D03*
Y1084711D03*
Y1098097D03*
Y1111483D03*
Y1104790D03*
Y1128215D03*
Y1118176D03*
Y1121522D03*
Y1141601D03*
Y1134908D03*
Y1148294D03*
Y1154987D03*
Y1158333D03*
Y1171719D03*
Y1165026D03*
Y1185105D03*
Y1178412D03*
Y1191798D03*
Y1208530D03*
Y1201837D03*
Y1195144D03*
Y1221916D03*
Y1215223D03*
Y1238648D03*
Y1228609D03*
Y1231955D03*
Y1245341D03*
X1047010Y1259222D03*
X1049683Y1258727D03*
Y1265420D03*
Y1262074D03*
X1044930Y1263492D03*
X1058383Y770144D03*
X1063141Y766798D03*
X1058383Y776837D03*
Y786877D03*
Y783530D03*
Y800263D03*
Y793570D03*
Y813648D03*
Y806955D03*
Y820341D03*
Y830381D03*
Y823688D03*
Y850459D03*
Y843766D03*
Y837074D03*
Y867192D03*
Y860499D03*
Y857152D03*
Y873885D03*
Y880577D03*
Y887270D03*
Y897310D03*
Y893963D03*
Y917389D03*
Y910696D03*
Y904003D03*
Y924081D03*
Y934121D03*
Y930774D03*
Y947507D03*
Y940814D03*
Y964239D03*
Y957546D03*
Y954200D03*
Y977625D03*
Y970932D03*
Y991011D03*
Y984318D03*
Y994357D03*
Y1021129D03*
Y1024475D03*
Y1031168D03*
Y1044554D03*
Y1037861D03*
Y1051247D03*
Y1071326D03*
Y1064633D03*
Y1078018D03*
Y1094751D03*
Y1088058D03*
Y1081365D03*
Y1108137D03*
Y1101444D03*
Y1124869D03*
Y1118176D03*
Y1114829D03*
Y1144948D03*
Y1138255D03*
Y1131562D03*
Y1161680D03*
Y1154987D03*
Y1151641D03*
Y1175066D03*
Y1168373D03*
Y1181759D03*
Y1191798D03*
Y1188452D03*
Y1205184D03*
Y1198491D03*
Y1218570D03*
Y1211877D03*
Y1225263D03*
Y1241995D03*
Y1235302D03*
Y1228609D03*
X1063241Y1258727D03*
X1061330Y1262074D03*
X1058383Y1248688D03*
X1059410Y1252272D03*
X1063241Y1265420D03*
X1071941Y960892D03*
Y957546D03*
X1079383Y994357D03*
X1076520Y1259072D03*
X1079383Y1258727D03*
X1088262Y1252293D03*
X1079383Y1265420D03*
Y1262074D03*
X1092709Y766775D03*
X1101641Y780184D03*
Y773491D03*
Y786877D03*
Y803609D03*
Y796916D03*
Y790223D03*
Y847113D03*
Y853806D03*
Y860499D03*
Y863845D03*
Y883924D03*
Y877231D03*
Y870538D03*
Y890617D03*
Y897310D03*
Y900656D03*
Y914042D03*
Y907349D03*
Y960892D03*
Y957546D03*
X1088083D03*
Y954200D03*
X1101641Y1061286D03*
Y1074672D03*
Y1067979D03*
Y1091404D03*
Y1081365D03*
Y1084711D03*
Y1098097D03*
Y1111483D03*
Y1104790D03*
Y1128215D03*
Y1118176D03*
Y1121522D03*
Y1134908D03*
Y1185105D03*
Y1178412D03*
Y1191798D03*
Y1208530D03*
Y1201837D03*
Y1195144D03*
X1090273Y1246800D03*
X1092941Y1258727D03*
X1088083Y1248688D03*
X1091000Y1262074D03*
X1106200Y1250162D03*
X1092941Y1265420D03*
X1103530Y1263602D03*
X1117783Y770144D03*
Y776837D03*
Y786877D03*
Y783530D03*
Y800263D03*
Y793570D03*
Y850459D03*
Y843766D03*
Y867192D03*
Y860499D03*
Y857152D03*
Y873885D03*
Y880577D03*
Y887270D03*
Y897310D03*
Y893963D03*
Y910696D03*
Y904003D03*
Y957546D03*
Y954200D03*
Y994357D03*
Y1057940D03*
Y1071326D03*
Y1064633D03*
Y1078018D03*
Y1094751D03*
Y1088058D03*
Y1081365D03*
Y1108137D03*
Y1101444D03*
Y1124869D03*
Y1118176D03*
Y1114829D03*
Y1131562D03*
Y1175066D03*
Y1181759D03*
Y1191798D03*
Y1188452D03*
Y1205184D03*
Y1198491D03*
X1120800Y1262074D03*
X1117783Y1248688D03*
X1109083Y1265420D03*
X1109050Y1262972D03*
X1106740Y1267902D03*
X1122541Y766798D03*
X1131341Y960892D03*
Y957546D03*
X1122641Y1258727D03*
X1133200Y1255702D03*
X1122620Y1264622D03*
X1152241Y766798D03*
X1147483Y957546D03*
Y954200D03*
X1138783Y994357D03*
X1152341Y1258727D03*
X1138783Y1255381D03*
Y1258727D03*
Y1252034D03*
X1147483Y1248688D03*
X1150400Y1262074D03*
X1148563Y1257097D03*
X1152341Y1265420D03*
X1138783Y1262027D03*
X1137980Y1264212D03*
X1161041Y960892D03*
Y957546D03*
Y1061286D03*
X1168483Y1255381D03*
Y1258727D03*
Y1252034D03*
Y1265420D03*
Y1262074D03*
X1177183Y957546D03*
Y954200D03*
Y994357D03*
X1177120Y1248688D03*
X1177222Y1255567D03*
X1182041Y1265420D03*
X1181850Y1260192D03*
X1179180Y1265872D03*
X1190741Y960892D03*
Y957546D03*
X1198183D03*
Y954200D03*
Y994357D03*
Y1252034D03*
X1198180Y1262112D03*
X1196470Y1265382D03*
X1193590Y1267912D03*
X1195470Y1262802D03*
X1196772Y1590094D03*
X1200172D03*
X1211641Y766798D03*
X1213983Y1000437D03*
X1216663Y1000395D03*
X1212533Y1002557D03*
X1205033D03*
X1207533D03*
X1210033D03*
X1208830Y1256692D03*
X1206883Y1248688D03*
X1207048Y1255174D03*
X1211240Y1265502D03*
X1208750Y1266546D03*
X1212232Y1590094D03*
X1208832D03*
X1214132Y1614292D03*
X1202072D03*
X1217532D03*
X1205472D03*
X1214132Y1602380D03*
X1202072D03*
X1217532D03*
X1205472D03*
X1220441Y960892D03*
Y957546D03*
X1227883D03*
Y954200D03*
Y994357D03*
X1233703Y999608D03*
X1231023Y999650D03*
X1220441Y1061286D03*
X1224189Y1259155D03*
X1226899Y1257968D03*
X1227847Y1251715D03*
X1227670Y1265162D03*
X1225540Y1266402D03*
X1220892Y1590094D03*
X1232952D03*
X1224292D03*
X1226192Y1614292D03*
X1229592D03*
X1226192Y1602380D03*
X1229592D03*
X1236583Y1057940D03*
Y1248688D03*
X1245012Y1590094D03*
X1236352D03*
X1248412D03*
X1238252Y1614292D03*
X1241652D03*
X1238252Y1602380D03*
X1241652D03*
X1257072Y1590094D03*
X1260472D03*
X1262372Y1614292D03*
X1250312D03*
X1265772D03*
X1253712D03*
X1262372Y1602380D03*
X1250312D03*
X1265772D03*
X1253712D03*
X1269132Y1590094D03*
X1281192D03*
X1272532D03*
X1274432Y1614292D03*
X1277832D03*
X1274432Y1602380D03*
X1277832D03*
X1293252Y1590094D03*
X1284592D03*
X1296652D03*
X1298552Y1614292D03*
X1286492D03*
X1289892D03*
X1298552Y1602380D03*
X1286492D03*
X1289892D03*
X1305312Y1590094D03*
X1308712D03*
X1310612Y1614292D03*
X1314012D03*
X1301952D03*
X1310612Y1602380D03*
X1314012D03*
X1301952D03*
X1317372Y1590094D03*
X1320772D03*
X1329432D03*
X1322672Y1614292D03*
X1326072D03*
X1322672Y1602380D03*
X1326072D03*
X1332832Y1590094D03*
X1341492D03*
X1344892D03*
X1346792Y1614292D03*
X1334732D03*
X1338132D03*
X1346792Y1602380D03*
X1334732D03*
X1338132D03*
X1353552Y1590094D03*
X1356952D03*
X1358852Y1614292D03*
X1362252D03*
X1350192D03*
X1358852Y1602380D03*
X1362252D03*
X1350192D03*
X1365612Y1590094D03*
X1377672D03*
X1369012D03*
X1370912Y1614292D03*
X1374312D03*
X1370912Y1602380D03*
X1374312D03*
X1381072Y1590094D03*
X1382972Y1614292D03*
X1386372D03*
X1382972Y1602380D03*
X1386372D03*
X1477755Y1578182D03*
X1462295D03*
X1474355D03*
X1465695D03*
X1477755Y1590094D03*
X1462295D03*
X1474355D03*
X1465695D03*
X1467595Y1614292D03*
X1470995D03*
X1489815Y1578182D03*
X1486415D03*
X1489815Y1590094D03*
X1486415D03*
X1491715Y1614292D03*
X1479655D03*
X1483055D03*
X1501875Y1578182D03*
X1498475D03*
X1501875Y1590094D03*
X1498475D03*
X1503775Y1614292D03*
X1507175D03*
X1495115D03*
X1525995Y1578182D03*
X1513935D03*
X1522595D03*
X1510535D03*
X1525995Y1590094D03*
X1513935D03*
X1522595D03*
X1510535D03*
X1515835Y1614292D03*
X1519235D03*
X1538055Y1578182D03*
X1534655D03*
X1538055Y1590094D03*
X1534655D03*
X1527895Y1614292D03*
X1539955D03*
X1531295D03*
X1550115Y1578182D03*
X1558775D03*
X1546715D03*
X1550115Y1590094D03*
X1558775D03*
X1546715D03*
X1552015Y1614292D03*
X1555415D03*
X1543355D03*
X1574235Y1578182D03*
X1562175D03*
X1570835D03*
X1574235Y1590094D03*
X1562175D03*
X1570835D03*
X1564075Y1614292D03*
X1567475D03*
X1586295Y1578182D03*
X1582895D03*
X1586295Y1590094D03*
X1582895D03*
X1588195Y1614292D03*
X1576135D03*
X1591595D03*
X1579535D03*
X1605800Y766478D03*
X1596941Y960892D03*
Y957546D03*
X1601922Y1000198D03*
X1599489Y999665D03*
X1597041Y1061286D03*
X1606481Y1258649D03*
X1608000Y1261662D03*
X1607897Y1264445D03*
X1598355Y1578182D03*
X1607015D03*
X1594955D03*
X1598355Y1590094D03*
X1607015D03*
X1594955D03*
X1600255Y1614292D03*
X1603655D03*
X1613083Y957546D03*
Y954200D03*
X1616609Y1000735D03*
X1616469Y1003135D03*
X1623539Y1000135D03*
X1620489Y1003135D03*
X1623589Y1002865D03*
X1620399Y1000325D03*
X1621983Y1258727D03*
X1624600Y1262074D03*
X1613183Y1252034D03*
X1613027Y1248805D03*
X1609056Y1250602D03*
X1623930Y1252242D03*
X1613019Y1261235D03*
X1622475Y1578182D03*
X1610415D03*
X1619075D03*
X1622475Y1590094D03*
X1610415D03*
X1619075D03*
X1612315Y1614292D03*
X1615715D03*
X1626741Y766798D03*
X1626641Y960892D03*
Y957546D03*
X1626249Y1002825D03*
X1626741Y1258727D03*
X1634535Y1578182D03*
X1631135D03*
X1634535Y1590094D03*
X1631135D03*
X1636435Y1614292D03*
X1624375D03*
X1639835D03*
X1627775D03*
X1656441Y766798D03*
Y960892D03*
Y957546D03*
X1642783D03*
Y954200D03*
X1648205Y998632D03*
X1656441Y1061286D03*
X1642883Y1255381D03*
Y1258727D03*
Y1252034D03*
X1651679Y1248885D03*
X1653140Y1257862D03*
X1656188Y1264964D03*
X1642788Y1264464D03*
X1642883Y1262074D03*
X1656170Y1260352D03*
X1654600Y1262742D03*
X1646595Y1578182D03*
X1643195D03*
X1646595Y1590094D03*
X1643195D03*
X1651895Y1614292D03*
X1648495D03*
X1672583Y957546D03*
Y954200D03*
Y994357D03*
Y1255381D03*
Y1258727D03*
Y1248688D03*
X1672188Y1263764D03*
X1686041Y766798D03*
Y960892D03*
Y957546D03*
X1686141Y1258727D03*
X1681179Y1252034D03*
X1683578Y1253780D03*
X1686119Y1264985D03*
X1681309Y1262074D03*
X1683500Y1264312D03*
X1702183Y957546D03*
Y954200D03*
Y994357D03*
X1702283Y1057940D03*
X1699852Y1245418D03*
X1699089Y1258842D03*
X1702283Y1248688D03*
X1702249Y1265420D03*
X1702283Y1262074D03*
X1699030Y1263912D03*
X1715841Y766798D03*
Y780184D03*
Y773491D03*
Y786877D03*
Y803609D03*
Y796916D03*
Y790223D03*
Y847113D03*
Y853806D03*
Y860499D03*
Y863845D03*
Y883924D03*
Y877231D03*
Y870538D03*
Y890617D03*
Y897310D03*
Y900656D03*
Y914042D03*
Y907349D03*
Y960892D03*
Y957546D03*
Y1061286D03*
Y1074672D03*
Y1067979D03*
Y1091404D03*
Y1081365D03*
Y1084711D03*
Y1098097D03*
Y1111483D03*
Y1104790D03*
Y1128215D03*
Y1118176D03*
Y1121522D03*
Y1134908D03*
Y1185105D03*
Y1178412D03*
Y1191798D03*
Y1208530D03*
Y1201837D03*
Y1195144D03*
X1713620Y1258512D03*
X1711109Y1252034D03*
X1713930Y1262074D03*
X1715839Y1265420D03*
X1737020Y112177D03*
Y109677D03*
X1731983Y770144D03*
Y776837D03*
Y786877D03*
Y783530D03*
Y800263D03*
Y793570D03*
Y850459D03*
Y843766D03*
Y867192D03*
Y860499D03*
Y857152D03*
Y873885D03*
Y880577D03*
Y887270D03*
Y897310D03*
Y893963D03*
Y910696D03*
Y904003D03*
Y957546D03*
Y954200D03*
Y994357D03*
X1731683Y1057940D03*
X1731818Y1071326D03*
X1731883Y1064633D03*
X1731983Y1078018D03*
Y1094751D03*
Y1088058D03*
Y1081365D03*
X1731818Y1108137D03*
X1731983Y1101444D03*
Y1124869D03*
Y1118176D03*
Y1114829D03*
Y1131562D03*
Y1175066D03*
X1731818Y1181759D03*
X1731983Y1191798D03*
X1731818Y1188452D03*
X1731983Y1205184D03*
Y1198491D03*
X1727041Y1248688D03*
X1731983Y1255381D03*
Y1258727D03*
Y1252034D03*
Y1248688D03*
X1731939Y1265420D03*
X1731983Y1262074D03*
X1747650Y109677D03*
Y112177D03*
X1744106Y109677D03*
Y112177D03*
X1740563Y109677D03*
Y112177D03*
X1745541Y766798D03*
Y960892D03*
Y957546D03*
Y1258727D03*
X1743710Y1262074D03*
X1742337Y1252300D03*
X1745541Y1265420D03*
X1761683Y957546D03*
Y954200D03*
Y994357D03*
X1756922Y1247632D03*
X1761683Y1255381D03*
Y1258727D03*
X1770299Y1252034D03*
X1761683Y1248688D03*
Y1262074D03*
Y1265420D03*
X1773559Y767345D03*
X1775241Y780184D03*
Y773491D03*
Y786877D03*
Y803609D03*
Y796916D03*
Y790223D03*
Y816995D03*
Y810302D03*
Y833727D03*
Y823688D03*
Y827034D03*
Y847113D03*
Y840420D03*
Y853806D03*
Y860499D03*
Y863845D03*
Y883924D03*
Y877231D03*
Y870538D03*
Y890617D03*
Y897310D03*
Y900656D03*
Y914042D03*
Y907349D03*
Y927428D03*
Y920735D03*
Y934121D03*
Y944160D03*
Y937467D03*
Y960892D03*
Y950853D03*
Y957546D03*
Y980971D03*
Y974278D03*
Y967585D03*
Y994357D03*
Y987664D03*
Y1027822D03*
Y1021129D03*
Y1047900D03*
Y1041207D03*
Y1034515D03*
Y1061286D03*
Y1054593D03*
Y1074672D03*
Y1067979D03*
Y1091404D03*
Y1081365D03*
Y1084711D03*
Y1098097D03*
Y1111483D03*
Y1104790D03*
Y1128215D03*
Y1118176D03*
Y1121522D03*
Y1141601D03*
Y1134908D03*
Y1148294D03*
Y1154987D03*
Y1158333D03*
Y1171719D03*
Y1165026D03*
Y1185105D03*
Y1178412D03*
Y1191798D03*
Y1208530D03*
Y1201837D03*
Y1195144D03*
Y1221916D03*
Y1215223D03*
Y1238648D03*
Y1228609D03*
Y1231955D03*
Y1245341D03*
Y1258727D03*
X1788219Y1259312D03*
X1773390Y1262074D03*
X1773480Y1253692D03*
X1775241Y1265420D03*
X1788360Y1264522D03*
X1791383Y770144D03*
Y776837D03*
Y786877D03*
Y783530D03*
Y800263D03*
Y793570D03*
Y813648D03*
Y806955D03*
Y820341D03*
Y830381D03*
Y823688D03*
Y850459D03*
Y843766D03*
Y837074D03*
Y867192D03*
Y860499D03*
Y857152D03*
Y873885D03*
Y880577D03*
Y887270D03*
Y897310D03*
Y893963D03*
Y917389D03*
Y910696D03*
Y904003D03*
Y924081D03*
Y934121D03*
Y930774D03*
Y947507D03*
Y940814D03*
Y964239D03*
Y957546D03*
Y954200D03*
Y977625D03*
Y970932D03*
Y991011D03*
Y984318D03*
Y994357D03*
Y1021129D03*
Y1024475D03*
Y1031168D03*
Y1044554D03*
Y1037861D03*
X1791083Y1051247D03*
X1791383Y1071325D03*
Y1064633D03*
Y1078018D03*
Y1094751D03*
Y1088058D03*
Y1081365D03*
Y1108136D03*
Y1101444D03*
Y1124869D03*
Y1118176D03*
Y1114829D03*
Y1144947D03*
Y1138255D03*
Y1131562D03*
Y1161680D03*
Y1154987D03*
Y1151640D03*
Y1175066D03*
Y1168373D03*
Y1181758D03*
Y1191798D03*
Y1188451D03*
Y1205184D03*
Y1198491D03*
Y1218570D03*
Y1211877D03*
Y1225263D03*
X1788373Y1241769D03*
X1791383Y1241995D03*
Y1235302D03*
Y1228609D03*
X1800427Y1248125D03*
X1803100Y1262074D03*
X1800019Y1252034D03*
X1791383Y1248688D03*
Y1265420D03*
Y1262074D03*
X1804841Y766798D03*
X1804941Y960892D03*
Y957546D03*
Y967585D03*
Y1054593D03*
X1815063Y1233103D03*
X1804941Y1258727D03*
X1813814Y1254693D03*
X1804941Y1265420D03*
X1821083Y964239D03*
X1820983Y957546D03*
Y954200D03*
Y994357D03*
X1821083Y1021129D03*
Y1024475D03*
Y1051247D03*
X1830379Y1250358D03*
X1829920Y1258322D03*
X1821139Y1248155D03*
X1821083Y1262074D03*
Y1265420D03*
X1829940Y1263662D03*
G54D29*
X159474Y1328627D03*
X183847Y1328652D03*
X208247D03*
X275289Y583576D03*
Y607735D03*
Y631889D03*
Y656043D03*
X270252Y676260D03*
Y700414D03*
X387897Y1242785D03*
X412297D03*
X436619D03*
X461019D03*
X485419D03*
X673093Y1328652D03*
X697466Y1328677D03*
X721866D03*
X1100800Y259362D03*
X1100700Y283662D03*
X1131100Y1364962D03*
X1155500D03*
X1179900D03*
X1364038Y1242785D03*
X1388438D03*
X1412760D03*
X1437160D03*
X1461560D03*
X1577000Y599762D03*
Y624262D03*
Y648762D03*
Y673162D03*
Y697662D03*
Y722162D03*
X1634259Y1362248D03*
X1658632Y1362273D03*
X1683032D03*
G54D51*
X705760Y-26500D03*
Y-16500D03*
D03*
Y-6500D03*
X730760Y-26500D03*
Y-16500D03*
D03*
Y-6500D03*
X822720Y3500D03*
Y13500D03*
D03*
Y23500D03*
X847720Y3500D03*
Y13500D03*
D03*
Y23500D03*
X973180Y-26500D03*
Y-16500D03*
D03*
Y-6500D03*
Y3500D03*
Y13500D03*
Y23500D03*
Y13500D03*
X998180Y-26500D03*
Y-16500D03*
D03*
Y-6500D03*
Y3500D03*
Y13500D03*
Y23500D03*
Y13500D03*
X1015152Y-26511D03*
Y-36511D03*
Y-26511D03*
Y-16511D03*
D03*
Y-6511D03*
D03*
Y3489D03*
D03*
Y13489D03*
D03*
Y23489D03*
X1040152Y-26511D03*
Y-36511D03*
Y-26511D03*
Y-16511D03*
D03*
Y-6511D03*
D03*
Y3489D03*
D03*
Y13489D03*
D03*
Y23489D03*
X1282572Y-36511D03*
Y-26511D03*
D03*
Y-16511D03*
D03*
Y-6511D03*
Y3489D03*
Y-6511D03*
Y3489D03*
Y13489D03*
Y23489D03*
Y13489D03*
X1307572Y-36511D03*
Y-26511D03*
D03*
Y-16511D03*
D03*
Y-6511D03*
Y3489D03*
Y-6511D03*
Y3489D03*
Y13489D03*
Y23489D03*
Y13489D03*
X1324471Y-26511D03*
Y-36511D03*
Y-26511D03*
Y-16511D03*
D03*
Y-6511D03*
D03*
Y3489D03*
D03*
Y13489D03*
D03*
Y23489D03*
X1349471Y-26511D03*
Y-36511D03*
Y-26511D03*
Y-16511D03*
D03*
Y-6511D03*
D03*
Y3489D03*
D03*
Y13489D03*
D03*
Y23489D03*
X1474931Y-36511D03*
Y-26511D03*
D03*
Y-16511D03*
D03*
Y-6511D03*
Y3489D03*
Y-6511D03*
Y3489D03*
Y13489D03*
Y23489D03*
Y13489D03*
X1499931Y-36511D03*
Y-26511D03*
D03*
Y-16511D03*
D03*
Y-6511D03*
Y3489D03*
Y-6511D03*
Y3489D03*
Y13489D03*
Y23489D03*
Y13489D03*
X1565236Y184783D03*
Y264035D03*
G54D54*
X793879Y194881D03*
X789942Y204724D03*
X793879Y214567D03*
X805690Y188976D03*
Y220472D03*
X817501Y194881D03*
Y214567D03*
X821438Y204724D03*
X841240Y1407480D03*
X832154Y1411244D03*
X828390Y1420330D03*
X832154Y1429416D03*
X841240Y1433180D03*
X850326Y1411244D03*
X854090Y1420330D03*
X850326Y1429416D03*
X1003390Y1420330D03*
X1016240Y1407480D03*
X1007154Y1411244D03*
Y1429416D03*
X1016240Y1433180D03*
X1025326Y1411244D03*
X1029090Y1420330D03*
X1025326Y1429416D03*
X1045847Y194881D03*
X1041910Y204724D03*
X1045847Y214567D03*
X1069469Y194881D03*
X1057658Y188976D03*
X1069469Y214567D03*
X1057658Y220472D03*
X1073406Y204724D03*
G54D11*
X3010Y63308D03*
Y123308D03*
Y163308D03*
Y183308D03*
Y203308D03*
Y223308D03*
Y243308D03*
Y263308D03*
Y283308D03*
Y303308D03*
X10884Y321693D03*
Y341693D03*
Y361693D03*
Y381693D03*
Y401693D03*
Y421693D03*
Y441693D03*
Y461693D03*
Y481693D03*
Y501693D03*
Y521693D03*
Y661693D03*
Y681693D03*
Y701693D03*
Y721693D03*
Y741693D03*
Y781693D03*
Y801693D03*
Y821693D03*
Y841693D03*
Y861693D03*
Y881693D03*
Y901693D03*
Y921693D03*
Y941693D03*
Y961693D03*
Y981693D03*
Y1001693D03*
Y1021693D03*
Y1041693D03*
Y1061693D03*
Y1081693D03*
Y1101693D03*
Y1121693D03*
Y1141693D03*
Y1161693D03*
Y1181693D03*
Y1201693D03*
Y1221693D03*
Y1241693D03*
Y1401693D03*
Y1421693D03*
Y1441693D03*
Y1461693D03*
Y1481693D03*
Y1501693D03*
Y1521693D03*
Y1541693D03*
Y1561693D03*
Y1581693D03*
X26615Y670036D03*
X28601Y1617541D03*
Y1637541D03*
Y1657541D03*
Y1677541D03*
X38220Y595862D03*
X54593Y19183D03*
X87565Y670441D03*
X94473Y698926D03*
X127313Y649765D03*
X114021Y669409D03*
X118021D03*
X127738Y659226D03*
X117220Y1680287D03*
X130067Y650213D03*
X134205Y643603D03*
X128193Y662015D03*
X128275Y665515D03*
X190800Y675662D03*
X219752Y1405499D03*
Y1401999D03*
Y1398599D03*
X259845Y461117D03*
X282640Y214102D03*
X301751Y127466D03*
Y124466D03*
Y121466D03*
X311758Y124469D03*
Y121469D03*
Y127469D03*
X313995Y237724D03*
X335285Y210609D03*
X332285D03*
X325755Y230719D03*
X338985Y229509D03*
X325855Y227619D03*
X325055Y237219D03*
X328965Y237214D03*
X332465D03*
X381068Y1674824D03*
X373320Y1688202D03*
X388220Y1631404D03*
X445944Y359053D03*
X446730Y382432D03*
X443744Y429553D03*
X451421D03*
X443744Y452462D03*
X437520Y484837D03*
X447520D03*
X442520D03*
X451520D03*
X448079Y1562177D03*
X443910Y1555602D03*
X450020Y1570412D03*
X453621Y359053D03*
X462720Y404762D03*
X465421Y424928D03*
X466520Y475812D03*
X456520Y484837D03*
X461520D03*
X456961Y1559697D03*
X456020Y1580412D03*
X464020D03*
X462079Y1572177D03*
X454661Y1596755D03*
X459779Y1609235D03*
X480393Y429412D03*
X479169Y484696D03*
X474169D03*
X484169D03*
X478308Y1439986D03*
X502070Y424787D03*
X488070Y429412D03*
X498169Y484696D03*
X493169D03*
X488169D03*
X513444Y473281D03*
X503169Y475671D03*
X550024Y369123D03*
Y401023D03*
X557701Y369123D03*
X649218Y504277D03*
X641386Y1687283D03*
X661534Y41748D03*
X656877Y514716D03*
X661743Y521166D03*
X657734Y528255D03*
X656725Y1657619D03*
X669004Y41698D03*
X694720Y491962D03*
X690720D03*
X702462Y1673258D03*
X725537Y-23978D03*
Y-19022D03*
Y-13978D03*
Y-9022D03*
X719194Y172909D03*
X714202D03*
X719194Y177865D03*
X714202D03*
X719194Y184909D03*
X714202D03*
X719194Y189865D03*
X714202D03*
X719194Y196409D03*
X714202D03*
X719194Y201365D03*
X714202D03*
X719194Y208243D03*
X714202D03*
X719194Y213199D03*
X714202D03*
X714203Y1639776D03*
X745685Y265322D03*
Y269322D03*
X742655Y1682362D03*
Y1678362D03*
X761720Y283262D03*
X748085Y278942D03*
X758360Y276122D03*
X755859Y1686090D03*
X755183Y1709850D03*
X764850Y249792D03*
X763359Y1729520D03*
X785135Y281822D03*
Y267822D03*
X842497Y6022D03*
Y16022D03*
Y20978D03*
Y10978D03*
X908675Y455386D03*
X913913Y455396D03*
X957420Y153699D03*
X960420D03*
X968022Y1620730D03*
X965022D03*
X971022D03*
X965022Y1632730D03*
X968022Y1629730D03*
X965022D03*
X968022Y1626730D03*
X965022D03*
Y1623730D03*
X968022D03*
X971022Y1626730D03*
Y1623730D03*
Y1629730D03*
Y1632730D03*
X968022D03*
X981445Y181058D03*
X1002735Y153943D03*
X999735D03*
X999915Y180548D03*
X996415D03*
X992505Y180553D03*
X993205Y174053D03*
X993305Y170953D03*
X990495Y212923D03*
X1001065Y304622D03*
Y307122D03*
Y309622D03*
X996662Y1620870D03*
X999662D03*
X1002662D03*
Y1626870D03*
Y1623870D03*
X996662Y1629870D03*
X999662Y1626870D03*
X996662D03*
Y1623870D03*
X999662D03*
X996662Y1632870D03*
X1021908Y60392D03*
Y120392D03*
X1015300Y148736D03*
X1012187Y148749D03*
X1006435Y172843D03*
X1009895Y192359D03*
X1008067Y194356D03*
X1019935Y206463D03*
Y203333D03*
X1010828Y304822D03*
Y307322D03*
Y309822D03*
X1034929Y-33989D03*
Y-29033D03*
Y-13989D03*
Y-9033D03*
Y-23989D03*
Y-19033D03*
Y-3989D03*
Y967D03*
X1036915Y290969D03*
X1035920Y428962D03*
X1034252Y1623870D03*
Y1626870D03*
X1031252Y1623870D03*
Y1626870D03*
X1028252Y1623870D03*
Y1626870D03*
X1031252Y1620870D03*
X1034252D03*
X1028252D03*
X1065721Y1633043D03*
X1068721D03*
Y1624043D03*
Y1627043D03*
Y1630043D03*
X1065721Y1624043D03*
Y1627043D03*
Y1630043D03*
X1062721Y1633043D03*
Y1624043D03*
Y1627043D03*
Y1630043D03*
X1059721Y1633043D03*
Y1624043D03*
Y1627043D03*
Y1630043D03*
X1068721Y1621043D03*
X1065721D03*
X1062721D03*
X1059721D03*
X1099901Y1633203D03*
Y1624203D03*
Y1627203D03*
Y1630203D03*
Y1621203D03*
X1093901Y1633203D03*
X1096901D03*
Y1624203D03*
Y1627203D03*
Y1630203D03*
X1093901Y1624203D03*
Y1627203D03*
Y1630203D03*
X1090901Y1633203D03*
X1087901D03*
X1090901Y1624203D03*
X1087901D03*
Y1627203D03*
X1090901D03*
X1087901Y1630203D03*
X1090901D03*
X1096901Y1621203D03*
X1093901D03*
X1087901D03*
X1090901D03*
X1132142Y1555301D03*
X1120472Y1615010D03*
X1127377Y1628485D03*
X1131632Y1625969D03*
X1148220Y501362D03*
X1139392Y1620851D03*
X1172720Y527862D03*
X1202600Y759662D03*
X1245574Y234042D03*
X1245593Y241462D03*
Y237462D03*
X1280223Y256841D03*
X1279841Y253052D03*
X1344248Y-33989D03*
Y-29033D03*
Y-13989D03*
Y-9033D03*
Y-23989D03*
Y-19033D03*
Y-3989D03*
Y967D03*
X1412954Y138742D03*
X1404402D03*
X1409716Y171696D03*
X1418268D03*
X1454829Y1439732D03*
X1465179Y213102D03*
X1477700Y236522D03*
X1466292Y631634D03*
X1473228D03*
X1486884Y374338D03*
X1479207D03*
X1478203Y406207D03*
X1493384Y419263D03*
X1481384Y419392D03*
X1505378Y225502D03*
X1509571Y239053D03*
X1507860Y249792D03*
X1513110Y247412D03*
X1522883Y305187D03*
X1526216Y306909D03*
X1529002Y32290D03*
X1528716Y306909D03*
X1533716D03*
X1536216D03*
X1534899Y310447D03*
X1559387Y589340D03*
X1564690Y663302D03*
X1619980Y590685D03*
X1615800Y584062D03*
X1620170Y623762D03*
X1622770D03*
X1612980D03*
X1620170Y626362D03*
X1622770D03*
X1612980D03*
X1615580Y650092D03*
Y657762D03*
X1620170D03*
X1622770D03*
X1622109Y652469D03*
X1619509D03*
X1612980Y657762D03*
Y650092D03*
X1615580Y660362D03*
X1620170D03*
X1622770D03*
X1612980D03*
X1622109Y686469D03*
X1619509D03*
X1615580Y684092D03*
X1612980D03*
X1622770Y691762D03*
Y694362D03*
X1620170Y691762D03*
Y694362D03*
X1615580D03*
X1612980D03*
X1615580Y691762D03*
X1612980D03*
X1619509Y720469D03*
X1622109D03*
X1612980Y718092D03*
X1615580D03*
X1610100Y725152D03*
X1637667Y587844D03*
Y590444D03*
X1629867D03*
Y587844D03*
X1632467Y590444D03*
Y587844D03*
X1635067Y590444D03*
Y587844D03*
X1626606Y616576D03*
X1629206D03*
X1631806D03*
X1634406D03*
X1637006D03*
X1639606D03*
X1630570Y623762D03*
X1627970D03*
X1625370D03*
X1636412Y638451D03*
X1636417Y630007D03*
X1640061Y639497D03*
X1636412Y641051D03*
X1630570Y626362D03*
X1627970D03*
X1625370D03*
X1630198Y638651D03*
Y636051D03*
Y641251D03*
X1633305Y638651D03*
Y641251D03*
X1630198Y632851D03*
X1630214Y629907D03*
X1633321D03*
X1640061Y644457D03*
Y641977D03*
X1630570Y657762D03*
X1627970D03*
X1625370D03*
X1629909Y652469D03*
X1632509D03*
X1624709D03*
X1627309D03*
X1630198Y643851D03*
X1633305Y646451D03*
Y643851D03*
X1630198Y646451D03*
X1636412Y672451D03*
X1636417Y664007D03*
X1640061Y673497D03*
X1630570Y660362D03*
X1627970D03*
X1625370D03*
X1630198Y672651D03*
Y670051D03*
X1633305Y672651D03*
X1630198Y666851D03*
X1630214Y663907D03*
X1633321D03*
X1629909Y686469D03*
X1632509D03*
X1624709D03*
X1627309D03*
X1640061Y678457D03*
Y675977D03*
X1636412Y675051D03*
X1630198Y677851D03*
Y675251D03*
X1633305Y680451D03*
Y675251D03*
Y677851D03*
X1630198Y680451D03*
X1636417Y698007D03*
X1636412Y706451D03*
X1630214Y697907D03*
X1633321D03*
X1630198Y704051D03*
Y706651D03*
X1633305D03*
X1630198Y700851D03*
X1625370Y691762D03*
Y694362D03*
X1630570D03*
Y691762D03*
X1627970D03*
Y694362D03*
X1640061Y707497D03*
Y712457D03*
Y709977D03*
X1636412Y709051D03*
X1632509Y720469D03*
X1627309D03*
X1629909D03*
X1624709D03*
X1633305Y711851D03*
Y709251D03*
X1630198D03*
Y711851D03*
X1633305Y714451D03*
X1630198D03*
X1642873Y604206D03*
Y607206D03*
X1645625Y600495D03*
Y603295D03*
X1642873Y601206D03*
Y598206D03*
X1645625Y597795D03*
Y594995D03*
X1642873Y595006D03*
X1642340Y618546D03*
X1642873Y610206D03*
X1645661Y639497D03*
X1656550Y653086D03*
X1645661Y644457D03*
Y641977D03*
Y673497D03*
X1656550Y687086D03*
X1645661Y678457D03*
Y675977D03*
Y707497D03*
Y709977D03*
Y712457D03*
X1665700Y583462D03*
X1661510Y583442D03*
X1672770Y580512D03*
X1669770D03*
X1663720Y620434D03*
X1659914Y649681D03*
Y683681D03*
Y717681D03*
X1686154Y434160D03*
X1704444Y407045D03*
X1697914Y427155D03*
X1698014Y424055D03*
X1701124Y433650D03*
X1697214Y433655D03*
X1704624Y433650D03*
X1717280Y174970D03*
X1707444Y407045D03*
X1711144Y425945D03*
X1765870Y179392D03*
X1780320Y177602D03*
G54D14*
X26054Y195148D03*
X25752Y203274D03*
X24754Y220220D03*
X24814Y236472D03*
X35600Y227380D03*
X45182Y426310D03*
X45034Y449106D03*
X62833Y410047D03*
X62808Y418425D03*
X50138Y426310D03*
X60393D03*
X49990Y449106D03*
X73020Y28406D03*
Y40020D03*
X65349Y426310D03*
X75516Y436519D03*
X73865Y763164D03*
X94279Y28406D03*
X87193D03*
X80106D03*
X94279Y40020D03*
X87193D03*
X80106D03*
X85826Y424319D03*
Y420319D03*
X82661Y449604D03*
X79451Y699517D03*
X92895Y1737108D03*
X108453Y28406D03*
X101366D03*
X108453Y40020D03*
X101366D03*
X104220Y400862D03*
X101720D03*
X113597Y488434D03*
X102152Y509374D03*
X102334Y500628D03*
X102359Y497374D03*
X102152Y513374D03*
X108909Y654926D03*
X102909Y648926D03*
Y642926D03*
Y655102D03*
X108909Y642926D03*
X122626Y28406D03*
X115539D03*
X122626Y40020D03*
X115539D03*
X125007Y392071D03*
Y388071D03*
Y384071D03*
Y396071D03*
X114507Y404571D03*
X117597Y488434D03*
X114909Y654926D03*
Y648926D03*
Y642926D03*
X116798Y1617262D03*
X112895Y1737108D03*
X129713Y28406D03*
Y40020D03*
X136301Y179095D03*
X143340Y204622D03*
X140974Y396885D03*
Y401885D03*
Y399385D03*
X142166Y490835D03*
X144263Y1412275D03*
X138492Y1717592D03*
X132895Y1737108D03*
X158492Y28406D03*
X151405D03*
X158492Y40020D03*
X151405D03*
X147901Y188852D03*
X159125Y448664D03*
X152171Y490615D03*
X149472Y502810D03*
X149486Y498810D03*
X149518Y522810D03*
X159898Y1360790D03*
X152895Y1737108D03*
X172665Y28406D03*
X165579D03*
X172665Y40020D03*
X165579D03*
X175640Y453779D03*
X162398Y1360790D03*
X164898D03*
X172895Y1737108D03*
X166761Y1732967D03*
X179752Y28406D03*
Y40020D03*
X184490Y402203D03*
X191305Y430216D03*
X188221Y454048D03*
X184147Y447078D03*
X192895Y1737108D03*
X202626Y28406D03*
X195539D03*
X202626Y40020D03*
X195539D03*
X199047Y428626D03*
X199139Y422882D03*
X196215Y447565D03*
X194858Y684348D03*
X203441Y1360790D03*
X198041D03*
X200941D03*
X223886Y28406D03*
X216799D03*
X209713D03*
X223886Y40020D03*
X216799D03*
X209713D03*
X223330Y426467D03*
X220843Y430004D03*
X220874Y442079D03*
X224137Y1414345D03*
X224077Y1416975D03*
X224350Y1432032D03*
X212895Y1737108D03*
X230972Y28406D03*
Y40020D03*
X242215Y151788D03*
X253000Y28362D03*
X256500D03*
X249500D03*
X252195Y144320D03*
X257434Y415896D03*
X252895Y1737108D03*
X260000Y28362D03*
X258746Y407842D03*
X260807Y424403D03*
X270322Y740207D03*
X272895Y1737108D03*
X286071Y28406D03*
X278984D03*
X279277Y99183D03*
X289557Y121803D03*
X280687Y140746D03*
X284482Y569548D03*
X286582Y630757D03*
X305025Y144202D03*
X302891Y141811D03*
X292895Y1737108D03*
X324733Y148598D03*
X321119Y1313108D03*
X317119D03*
X313119D03*
X330417Y380482D03*
X336370Y406302D03*
X325119Y1313108D03*
X328915Y1326704D03*
X331515D03*
X332895Y1737108D03*
X344776Y148462D03*
X343411Y363143D03*
Y375364D03*
X343354Y387988D03*
X343720Y400628D03*
X339769Y1299868D03*
X342769D03*
X352895Y1737108D03*
X366675Y158702D03*
X364179Y394596D03*
X371066Y400628D03*
X369690Y431812D03*
X365970Y444662D03*
X361769Y1300008D03*
X364769D03*
X383140Y119822D03*
X375330Y121182D03*
X374981Y131433D03*
X376770Y387272D03*
X385520Y429262D03*
X373190Y438342D03*
X384510Y438662D03*
X385730Y460922D03*
X382860Y471122D03*
X383239Y1286578D03*
X378069Y1286568D03*
X375069D03*
X386239Y1286578D03*
X372895Y1737108D03*
X403700Y402422D03*
X390892Y406863D03*
X403260Y439352D03*
X391150Y445302D03*
X396570Y472602D03*
X391360Y495712D03*
X402780Y499372D03*
X394860Y518812D03*
X403200Y572622D03*
X396139Y1286708D03*
X399139D03*
X400926Y1402207D03*
X391249Y1401048D03*
X396921Y1549810D03*
X396946Y1560810D03*
X419012Y368762D03*
X418602Y394722D03*
X417010Y439352D03*
X415130Y480202D03*
X410532Y1153341D03*
X407948Y1153370D03*
Y1161570D03*
X410532Y1161541D03*
X407948Y1169597D03*
X410532D03*
X429050Y117491D03*
X430980Y132672D03*
X432006Y363644D03*
X431596Y389604D03*
X424980Y439462D03*
X427790Y500862D03*
X427880Y506442D03*
X428510Y515842D03*
X436822Y1161570D03*
Y1153370D03*
X431722D03*
Y1161570D03*
X434272Y1153370D03*
Y1161570D03*
X436822Y1170070D03*
X431722D03*
X434272D03*
X430999Y1286758D03*
X423229D03*
X426229D03*
X433999D03*
X436920Y1541562D03*
X422566Y1550046D03*
X432996Y1558322D03*
X436840Y1632682D03*
X436880Y1622442D03*
X432895Y1737108D03*
X447100Y1622562D03*
X447020Y1632632D03*
X452895Y1737108D03*
X465236Y293823D03*
X467736Y312938D03*
X455326Y520389D03*
X457196Y1161570D03*
X459696D03*
X462196D03*
X459696Y1153370D03*
X457196D03*
X462196D03*
X459696Y1170070D03*
X462196D03*
X457196D03*
X460049Y1286978D03*
X463049D03*
X469019Y1286718D03*
X465749Y1401238D03*
X455602Y1412334D03*
X473870Y506622D03*
X474220Y572782D03*
X471940Y597532D03*
X483030Y1153370D03*
Y1161570D03*
Y1170070D03*
X474509Y1286848D03*
X481509D03*
X477509D03*
X484509D03*
X475285Y1395402D03*
X477835Y1673462D03*
Y1685462D03*
X472895Y1737108D03*
X498636Y293123D03*
X501136Y312238D03*
X486861Y309398D03*
X490759Y1291978D03*
X495309Y1300058D03*
X498309D03*
X492895Y1737108D03*
X517914Y42257D03*
X517902Y49194D03*
X510815D03*
X517989Y1300108D03*
X514989D03*
X508881Y1404880D03*
X506181D03*
X503559Y1405025D03*
X508775Y1409889D03*
X508828Y1407385D03*
X508802Y1412420D03*
X506075Y1409889D03*
X506128Y1407385D03*
X503572Y1407539D03*
Y1415039D03*
Y1412539D03*
X506102Y1412420D03*
X503572Y1410039D03*
X512895Y1737108D03*
X525000Y42257D03*
X524988Y49194D03*
X532533Y299500D03*
X529533D03*
X526941Y447802D03*
X521561Y550819D03*
X526280Y569122D03*
X520710Y592552D03*
X532895Y1737108D03*
X549610Y120682D03*
X535290Y572932D03*
X543450Y590262D03*
X562780Y32842D03*
X564430Y45132D03*
X565849Y1346968D03*
X552895Y1737108D03*
X578620Y45112D03*
X573849Y1346968D03*
X569849D03*
X572895Y1737108D03*
X596840Y45152D03*
X593925Y49193D03*
X590350Y294402D03*
X607890Y34389D03*
X615420Y42342D03*
X605060Y42402D03*
X615185Y49193D03*
X611310Y266272D03*
X612895Y1737108D03*
X621740Y265952D03*
X632895Y1737108D03*
X661681Y49193D03*
X654595D03*
X652895Y1737108D03*
X675854Y49193D03*
X668768D03*
X673517Y1360815D03*
X676017D03*
X678517D03*
X671112Y1639962D03*
X672895Y1737108D03*
X697122Y1632667D03*
X683592Y1634844D03*
X697197Y1644667D03*
X712433Y103308D03*
X712060Y1360815D03*
X722580Y49182D03*
X724133Y141288D03*
X713820Y488762D03*
Y484662D03*
X714560Y1360815D03*
X717060D03*
X744800Y1664840D03*
X732895Y1737108D03*
X762198Y129684D03*
Y126684D03*
X758110Y172636D03*
X752895Y1737108D03*
X777283Y320892D03*
X772208Y1731911D03*
X792208D03*
X810781Y372615D03*
X821164Y372312D03*
X812208Y1731911D03*
X836502Y161553D03*
X837975Y210064D03*
X832208Y1731911D03*
X856776Y129268D03*
X846846Y127064D03*
X851895Y160262D03*
X849710Y212062D03*
X845220Y216532D03*
X854706Y229878D03*
X852206D03*
X856842Y410760D03*
X852208Y1731911D03*
X874295Y163862D03*
X863488Y176332D03*
X872208Y1731911D03*
X886280Y174085D03*
X887671Y487831D03*
Y494767D03*
X878931Y509051D03*
X878941Y503813D03*
X892208Y1731911D03*
X899625Y473856D03*
X893321Y480293D03*
X893311Y485531D03*
X893572Y503050D03*
Y496114D03*
X920246Y184138D03*
X914550Y239924D03*
X923403Y983327D03*
X923322Y990227D03*
X921880Y1525110D03*
X924380D03*
X921880Y1527610D03*
X924380D03*
X912208Y1731911D03*
X935496Y195925D03*
Y203012D03*
Y210098D03*
Y217185D03*
Y224272D03*
Y231358D03*
X940596Y498648D03*
X939097Y527257D03*
X939282Y534020D03*
X930233Y983298D03*
X930274Y990237D03*
X939380Y1525110D03*
X926880D03*
X929380D03*
X931880D03*
X934380D03*
X936880D03*
X926880Y1527610D03*
X929380D03*
X931880D03*
X934380D03*
X936880D03*
X939380D03*
X932208Y1731911D03*
X947190Y527330D03*
X952208Y1731911D03*
X972208D03*
X989910Y-27961D03*
X989925Y-25446D03*
X983632Y-26655D03*
X989925Y-21572D03*
X983632Y-16626D03*
X989910Y-17932D03*
X989925Y-15417D03*
Y-11543D03*
X989910Y-7903D03*
X989925Y-5388D03*
X983632Y-6597D03*
X989925Y4641D03*
X989910Y2126D03*
X983632Y3432D03*
X989925Y14670D03*
X989910Y12155D03*
X989925Y8515D03*
X983632Y13461D03*
X989925Y19044D03*
X983632Y23990D03*
X987259Y276094D03*
X998500Y269862D03*
X1002500D03*
X992208Y1731911D03*
X1014500Y269862D03*
X1018000D03*
X1006500D03*
X1010500D03*
X1021419Y305704D03*
X1012208Y1731911D03*
X1032208D03*
X1053028Y246518D03*
X1053428Y261118D03*
X1052208Y1731911D03*
X1058028Y246518D03*
X1055528D03*
X1068093Y265503D03*
X1058428Y261118D03*
X1055928D03*
X1067618Y273800D03*
X1070718Y273700D03*
X1067718Y285600D03*
X1070618D03*
X1072208Y1731911D03*
X1102561Y78461D03*
X1117574Y1448604D03*
X1111866Y1737108D03*
X1135709Y1397119D03*
X1133209D03*
X1127008Y1524203D03*
X1135748Y1524187D03*
X1131866Y1737108D03*
X1138209Y1397119D03*
X1170337Y607327D03*
X1171752Y1397119D03*
X1176752D03*
X1174252D03*
X1179922Y1524203D03*
X1201110Y1681767D03*
X1191866Y1737108D03*
X1211866D03*
X1231866D03*
X1253586Y1334649D03*
X1257586D03*
X1251866Y1737108D03*
X1276745Y125850D03*
X1275807Y132922D03*
X1281600Y137962D03*
X1282568Y212722D03*
X1272707Y1334865D03*
X1271866Y1737108D03*
X1293024Y-36695D03*
Y-26666D03*
Y-16637D03*
Y-6608D03*
Y3421D03*
Y13450D03*
Y23979D03*
X1291280Y58262D03*
X1293860Y58312D03*
X1284930Y124922D03*
X1285793Y141562D03*
X1288258Y145501D03*
X1283781Y149115D03*
Y155788D03*
X1283425Y179272D03*
X1283397Y202085D03*
X1295150Y1323217D03*
X1298150D03*
X1291010Y1323307D03*
X1288010D03*
X1291866Y1737108D03*
X1299317Y-35486D03*
Y-31612D03*
X1299302Y-38001D03*
Y-27972D03*
X1299317Y-25457D03*
Y-21583D03*
X1299302Y-17943D03*
X1299317Y-15428D03*
Y-11554D03*
X1299302Y-7914D03*
X1299317Y-5399D03*
Y4630D03*
X1299302Y2115D03*
X1299317Y-1525D03*
Y14659D03*
X1299302Y12144D03*
X1299317Y8504D03*
Y19033D03*
X1304066Y1323578D03*
X1307656Y1326704D03*
X1305056D03*
X1311866Y1737108D03*
X1323958Y146227D03*
X1333811Y235348D03*
X1338652Y536654D03*
Y543590D03*
X1337663Y1301001D03*
X1340663D03*
X1331866Y1737108D03*
X1349704Y145385D03*
X1357888Y145893D03*
X1361111Y236448D03*
X1353982Y1287048D03*
X1362382D03*
X1359382D03*
X1350982D03*
X1351866Y1737108D03*
X1366868Y147341D03*
X1369593Y147462D03*
X1369916Y154132D03*
X1379969Y176330D03*
X1370586Y176366D03*
X1370405Y186938D03*
X1369479Y208384D03*
X1370636Y227292D03*
X1369410Y224504D03*
X1375463Y1287048D03*
X1372463D03*
X1376666Y1402778D03*
X1376686Y1399758D03*
X1371866Y1737108D03*
X1384173Y1161549D03*
X1384089Y1153369D03*
X1386673Y1161520D03*
Y1153340D03*
X1384173Y1169599D03*
X1386673Y1169570D03*
X1391866Y1737108D03*
X1407613Y177159D03*
X1398770D03*
X1402258Y184263D03*
X1411101D03*
X1407913Y1161569D03*
X1410413Y1153369D03*
X1407913D03*
X1410613Y1161569D03*
X1407913Y1170069D03*
X1410613D03*
X1410819Y1287198D03*
X1407819D03*
X1399419D03*
X1402419D03*
X1411866Y1737108D03*
X1420222Y184263D03*
X1429250Y1623391D03*
X1419270Y1631000D03*
X1429382Y184263D03*
X1430000Y220018D03*
X1435387Y1161569D03*
X1435837Y1153369D03*
X1432887Y1161569D03*
X1433337Y1153369D03*
X1435387Y1170069D03*
X1432887D03*
X1437258Y1287198D03*
X1445106Y1287158D03*
X1440258Y1287198D03*
X1431829Y1412370D03*
X1443325Y1410068D03*
X1431717Y1424125D03*
X1441800Y1620300D03*
Y1632900D03*
X1431866Y1737108D03*
X1458911Y1161569D03*
Y1170069D03*
X1453366Y1287198D03*
X1458766D03*
X1461766D03*
X1450366D03*
X1474180Y1300407D03*
X1471180D03*
X1491661Y-27972D03*
X1491676Y-25457D03*
X1485383Y-26666D03*
X1491661Y-38001D03*
X1491676Y-35486D03*
Y-31612D03*
X1485383Y-36695D03*
X1491661Y-17943D03*
X1491676Y-15428D03*
Y-11554D03*
X1485383Y-16637D03*
X1491676Y-21583D03*
X1485383Y3421D03*
X1491661Y2115D03*
X1491676Y4630D03*
X1491661Y-7914D03*
X1491676Y-5399D03*
Y-1525D03*
X1485383Y-6608D03*
X1491676Y14659D03*
X1491661Y12144D03*
X1485383Y13450D03*
X1491676Y8504D03*
Y19033D03*
X1485383Y23979D03*
X1487058Y281456D03*
X1484958Y289656D03*
X1487658D03*
X1484758Y312356D03*
X1487458D03*
X1484858Y305956D03*
X1487558D03*
X1491840Y1300447D03*
X1479658Y1405397D03*
X1485301Y1409442D03*
X1485274Y1406911D03*
X1485380Y1412202D03*
X1479671Y1410411D03*
Y1412911D03*
Y1407911D03*
X1482201Y1409442D03*
X1482174Y1406911D03*
X1482280Y1412202D03*
X1491866Y1737108D03*
X1504602Y312867D03*
X1494840Y1300447D03*
X1511866Y1737108D03*
X1540937Y576522D03*
X1536527Y589012D03*
X1531866Y1737108D03*
X1547429Y28406D03*
X1554515D03*
Y40020D03*
X1547429D03*
X1547312Y579080D03*
X1551866Y1737108D03*
X1561602Y28406D03*
X1568688D03*
Y40020D03*
X1561602D03*
X1575775Y28406D03*
X1582862D03*
X1589948D03*
Y40020D03*
X1582862D03*
X1575775D03*
X1591866Y1737108D03*
X1597035Y28406D03*
X1604122D03*
Y40020D03*
X1597035D03*
X1623881Y117627D03*
X1619980Y615201D03*
X1614116Y1411169D03*
X1611866Y1737108D03*
X1625814Y28406D03*
X1632901D03*
X1639988D03*
X1625814Y40020D03*
X1632901D03*
X1639988D03*
X1637183Y1394411D03*
X1639683D03*
X1634683D03*
X1631866Y1737108D03*
X1654161Y28406D03*
X1647074D03*
Y40020D03*
X1654161D03*
X1652113Y527325D03*
X1652138Y524071D03*
X1651931Y540071D03*
Y536071D03*
X1649291Y556057D03*
X1649149Y607022D03*
X1653929Y604546D03*
X1649139Y604576D03*
X1653736Y607033D03*
X1649117Y602139D03*
X1653930Y602099D03*
X1651866Y1737108D03*
X1669948Y28406D03*
Y40020D03*
X1663376Y515531D03*
X1667376D03*
X1664997Y604762D03*
X1659458Y637149D03*
X1658085Y639511D03*
X1659458Y671149D03*
X1658085Y673511D03*
X1659458Y705149D03*
X1658085Y707511D03*
X1673226Y1394411D03*
X1671866Y1737108D03*
X1677035Y28406D03*
X1684122D03*
X1677035Y40020D03*
X1684122D03*
X1681612Y499290D03*
X1675926Y1394411D03*
X1678426D03*
X1691208Y28406D03*
X1698295D03*
X1705381D03*
X1697824Y39974D03*
X1691208Y40020D03*
X1693987Y230174D03*
Y233174D03*
X1703487Y232174D03*
X1699265Y525507D03*
X1699291Y537507D03*
X1699251Y529507D03*
X1699297Y549507D03*
X1705723Y1583821D03*
X1691866Y1737108D03*
X1711866D03*
X1738200Y193862D03*
X1731866Y1737108D03*
X1753388Y28360D03*
X1754398Y100307D03*
X1752200Y197762D03*
X1748500Y193862D03*
X1745500D03*
X1741200D03*
X1740831Y489362D03*
X1740886Y493960D03*
X1751866Y1737108D03*
X1760475Y28360D03*
X1764678Y122927D03*
X1766880Y234842D03*
Y231842D03*
X1758500Y231822D03*
Y234822D03*
X1755378Y233528D03*
X1782000Y128455D03*
X1771915Y128393D03*
X1782000Y125955D03*
Y123455D03*
X1771915Y125893D03*
Y123393D03*
X1783800Y231762D03*
Y234762D03*
X1775140Y234792D03*
Y231792D03*
X1779226Y275604D03*
X1783563Y273471D03*
X1786089D03*
X1771866Y1737108D03*
X1797663Y269571D03*
X1800189D03*
X1790563Y273471D03*
X1793089D03*
X1802763Y308671D03*
X1795763D03*
X1798289D03*
X1788763D03*
X1791289D03*
X1814349Y269634D03*
X1811823D03*
X1807249D03*
X1804723D03*
X1812349Y308734D03*
X1809823D03*
X1805289Y308671D03*
X1828777Y156520D03*
X1841257Y151402D03*
G54D19*
X20188Y1599396D03*
G54D66*
X1156378Y133866D03*
G54D70*
X1850331Y311946D03*
G54D25*
X60303Y20354D03*
X312921Y24291D03*
X505185Y41142D03*
X757803Y45079D03*
X922441Y237697D03*
X929331Y160413D03*
X1534712Y20354D03*
X1787330Y24291D03*
G54D41*
X337778Y854584D03*
X335924Y857789D03*
X334079Y880219D03*
X332228Y877014D03*
X335928D03*
X334078Y893036D03*
X335928Y896240D03*
X332229Y902649D03*
X332228Y915466D03*
X335928D03*
X332229Y921875D03*
Y941100D03*
X332228Y934692D03*
X335928D03*
X334079Y957122D03*
X335928Y953917D03*
X332228D03*
X332229Y973143D03*
X334079Y976347D03*
X338210Y996480D03*
X332661Y1006093D03*
X338211Y1002888D03*
X332661Y1025318D03*
Y1018910D03*
X338211Y1015705D03*
Y1022114D03*
X332661Y1044544D03*
X338211Y1041340D03*
X334511D03*
X338211Y1060565D03*
X336360Y1082995D03*
X338211Y1111834D03*
Y1105426D03*
Y1124651D03*
X336361Y1115039D03*
Y1127856D03*
X347028Y844971D03*
X345178Y848176D03*
X350727Y844971D03*
X347027Y851380D03*
X343327D03*
X354429D03*
X341478Y854584D03*
X339628Y857789D03*
X347029Y864197D03*
Y857789D03*
X348878Y854584D03*
X345179Y860993D03*
X343327Y857789D03*
X354429Y864197D03*
X350729D03*
X341479Y867401D03*
X348879D03*
X352579D03*
X354429Y877014D03*
X339629D03*
X341479Y873810D03*
X345179Y880219D03*
Y873810D03*
X343329Y877014D03*
X352579Y880219D03*
X350729Y877014D03*
X339629Y883423D03*
X347029D03*
X350729D03*
X352578Y899445D03*
X339629Y896240D03*
Y889832D03*
X348879Y886627D03*
X345179Y893036D03*
X343328Y896240D03*
X352578Y893036D03*
Y886627D03*
X345179Y899445D03*
X348878Y905853D03*
X352578D03*
X341479Y912262D03*
X341478Y905853D03*
X347029Y909057D03*
Y902649D03*
X345179Y912262D03*
X352578D03*
X339629Y915466D03*
X343329D03*
X348878Y925079D03*
X352578D03*
Y918670D03*
X341478Y925079D03*
X347029Y928283D03*
Y921875D03*
X345179Y918670D03*
X341479Y931488D03*
X345179D03*
X352578D03*
X341478Y944304D03*
X352578D03*
X347029Y941100D03*
X348878Y944304D03*
X347029Y947509D03*
X352578Y937896D03*
X339629Y934692D03*
X345179Y937896D03*
X343328Y934692D03*
X348878Y963530D03*
X347029Y960326D03*
X343328D03*
X343329Y966735D03*
X339629D03*
Y953917D03*
X343328D03*
X345179Y957122D03*
X352578D03*
X347029Y966735D03*
X352578Y963530D03*
X341479Y950713D03*
X345179D03*
X352578D03*
X354428Y973143D03*
X339629D03*
X345179Y976347D03*
Y969939D03*
X350729Y973143D03*
X347029Y979552D03*
X352579Y976347D03*
X352578Y969939D03*
X348878Y982756D03*
X352578D03*
X339629Y979552D03*
X343329Y973143D03*
X341911Y1009297D03*
Y1002888D03*
X347461Y999684D03*
X345611Y1009297D03*
X343761Y1006093D03*
X345611Y1002888D03*
X351162Y1006093D03*
X354861D03*
X353011Y1009297D03*
Y1002888D03*
X347461Y1012501D03*
X353011Y1028523D03*
Y1015705D03*
X341911Y1022114D03*
Y1015705D03*
X349311D03*
X347461Y1018910D03*
X345611Y1028523D03*
X343761Y1018910D03*
X345611Y1022114D03*
Y1015705D03*
X353011Y1022114D03*
X343761Y1031727D03*
X347461D03*
X353011Y1034931D03*
Y1047749D03*
X341911Y1041340D03*
X343761Y1038136D03*
X349311Y1034931D03*
X347461Y1038136D03*
X345611Y1041340D03*
X343761Y1044544D03*
X353011Y1041340D03*
X345611Y1047749D03*
X349311Y1054157D03*
X353011Y1060565D03*
Y1054157D03*
X343761Y1057361D03*
Y1050952D03*
X347461D03*
Y1057361D03*
X345611Y1060565D03*
X343761Y1063770D03*
X353011Y1073383D03*
X343761Y1076587D03*
Y1070178D03*
X340062Y1076587D03*
X347461D03*
Y1070178D03*
X349312Y1073383D03*
X345611Y1066974D03*
X353011D03*
X345611Y1079791D03*
X341911D03*
X353011D03*
Y1086200D03*
X349310Y1092609D03*
X347461Y1089404D03*
X345610Y1086200D03*
X343760Y1082995D03*
X340060D03*
X353011Y1092608D03*
X340061Y1095813D03*
X347461Y1108630D03*
X354861D03*
X353011Y1099017D03*
X340061Y1108630D03*
Y1102221D03*
X349311Y1099017D03*
X347461Y1102221D03*
X343761D03*
X340061Y1115039D03*
X349311Y1124651D03*
X349312Y1118243D03*
X345611D03*
X343761Y1115039D03*
X341911Y1124651D03*
X354861Y1115039D03*
X351161Y1121447D03*
Y1115039D03*
X345611Y1137469D03*
Y1131060D03*
X349311D03*
X343761Y1134264D03*
X353011Y1137469D03*
Y1131060D03*
X361829Y851380D03*
X358129D03*
X365529Y864197D03*
X361829D03*
X359979Y854584D03*
X358129Y864197D03*
X369229D03*
X367379Y854584D03*
X359979Y867401D03*
X367379D03*
X365529Y877014D03*
X361829D03*
X358129D03*
X369229D03*
X367379Y880219D03*
X356278Y886627D03*
X365529Y896240D03*
Y889832D03*
X361828Y896240D03*
X361829Y889832D03*
X359979Y893036D03*
X358128Y889832D03*
X369229Y896240D03*
Y889832D03*
X356278Y905853D03*
X365529Y909057D03*
Y902649D03*
X359978Y912262D03*
X358128Y909057D03*
X358129Y902649D03*
X371079Y912262D03*
X365529Y915466D03*
X361828D03*
X369229D03*
X356279Y925079D03*
X365529Y928283D03*
Y921875D03*
X358128Y928283D03*
X358129Y921875D03*
X371078Y918670D03*
X359978Y931488D03*
X371079D03*
X358128Y947509D03*
X358129Y941100D03*
X356279Y944304D03*
X365529Y947509D03*
Y934691D03*
X361828D03*
X369229D03*
X356279Y963530D03*
X358129Y960326D03*
X359979Y957122D03*
X358128Y966735D03*
X361829Y953917D03*
X359978Y950713D03*
X371078Y957122D03*
X371079Y950713D03*
X365529Y953917D03*
X367378Y963530D03*
X363679D03*
X365529Y960326D03*
X365528Y966735D03*
X369229Y953917D03*
X359979Y976347D03*
X358129Y979552D03*
X359978Y969939D03*
X361828Y973143D03*
X356279Y982756D03*
X371078Y976347D03*
X371079Y969939D03*
X369229Y973143D03*
X365529Y979552D03*
Y973143D03*
X365962Y999684D03*
Y1006093D03*
X362261D03*
X360411Y1009297D03*
X360412Y1002888D03*
X358562Y999684D03*
X371512Y1009297D03*
X365961Y1012501D03*
X358561D03*
X356712Y1015705D03*
X365962Y1025318D03*
Y1018910D03*
X364112Y1015705D03*
X360411Y1028523D03*
X362261Y1025318D03*
X360412Y1022114D03*
X358562Y1018910D03*
X369662Y1025318D03*
X367811Y1015705D03*
X371511Y1028523D03*
Y1022114D03*
X365962Y1031727D03*
X358561D03*
X356712Y1034931D03*
X365962Y1044544D03*
Y1038136D03*
X362261Y1044544D03*
X360412Y1041340D03*
X358562Y1038136D03*
X369662Y1044544D03*
X371511Y1041340D03*
X360411Y1047749D03*
X371511D03*
X356712Y1054157D03*
X365962Y1057361D03*
Y1050952D03*
X360412Y1060565D03*
X358562Y1057361D03*
X358561Y1050952D03*
X371511Y1060565D03*
X365962Y1063770D03*
X362261D03*
X369662D03*
X356712Y1073383D03*
X365962Y1070178D03*
X360411Y1066974D03*
X358561Y1070178D03*
X358562Y1076587D03*
X371512Y1066974D03*
X360412Y1079791D03*
X371511D03*
X365962Y1089404D03*
Y1082995D03*
X362261D03*
X360411Y1086200D03*
X358561Y1089404D03*
X356712Y1092608D03*
X369662Y1082995D03*
X371512Y1086200D03*
X365962Y1095813D03*
X358561D03*
X365962Y1102221D03*
X362262D03*
X360411Y1099017D03*
X356711Y1105426D03*
Y1099017D03*
X371512Y1105426D03*
Y1099017D03*
X364112Y1111834D03*
X356712D03*
X371512D03*
X364111Y1118243D03*
X362261Y1115039D03*
X360411Y1118243D03*
X356711D03*
X367811D03*
X371511D03*
X365962Y1127856D03*
X358561D03*
X365961Y1140973D03*
X364112Y1131060D03*
X360412D03*
X358561Y1140973D03*
X356712Y1131060D03*
X367811D03*
X371511D03*
X382179Y854584D03*
X380329Y864197D03*
X376629D03*
X374779Y854584D03*
X372929Y864197D03*
X384029D03*
X387729D03*
X382179Y867401D03*
X374779D03*
X382179Y880219D03*
X380329Y877014D03*
X376629D03*
X374779Y880219D03*
X372929Y877014D03*
X384029D03*
X387729D03*
X380329Y889832D03*
X378479Y893036D03*
X376629Y889832D03*
X372929D03*
X384029D03*
X387729Y896240D03*
Y889832D03*
X378478Y899445D03*
X385879D03*
X382179Y905853D03*
X378478Y912262D03*
Y905853D03*
X374778D03*
X372929Y909057D03*
X372928Y902649D03*
X385878Y912262D03*
X384028Y909057D03*
X384029Y902649D03*
X387728Y915466D03*
X382179Y925079D03*
X378478D03*
Y918670D03*
X374778Y925079D03*
X372929Y928283D03*
X372928Y921875D03*
X385879Y918670D03*
X384028Y928283D03*
X384029Y921875D03*
X385878Y931488D03*
X384029Y941100D03*
X384028Y947509D03*
X374778Y944304D03*
X372929Y947509D03*
X372928Y941100D03*
X382179Y944304D03*
X378478D03*
Y937896D03*
X385879D03*
X387728Y934691D03*
X387729Y953917D03*
X372928Y960326D03*
X374778Y963530D03*
X372929Y966735D03*
X382179Y963530D03*
X378478D03*
Y957122D03*
X384029Y960326D03*
X385879Y957122D03*
X384028Y966735D03*
X385878Y950713D03*
X378478D03*
X387728Y973143D03*
X376629D03*
X380328D03*
X378479Y976347D03*
X378478Y969939D03*
X385879Y976347D03*
X384029Y979552D03*
X385878Y969939D03*
X374778Y982756D03*
X382179D03*
X378478D03*
X372928Y979552D03*
X375210Y996480D03*
X373361Y999684D03*
X378911Y1009297D03*
Y1002888D03*
X386311Y1009297D03*
X386312Y1002888D03*
X384462Y999684D03*
X373362Y1012501D03*
X384461D03*
X382612Y1015705D03*
X378911Y1028523D03*
Y1022114D03*
Y1015705D03*
X375211D03*
X373361Y1018910D03*
X386311Y1028523D03*
X386312Y1022114D03*
X384462Y1018910D03*
X373362Y1031727D03*
X384461D03*
X382612Y1034931D03*
X378911Y1041340D03*
Y1034931D03*
X375211D03*
X373361Y1038136D03*
X386312Y1041340D03*
X384462Y1038136D03*
X378911Y1047749D03*
X386311D03*
X382612Y1054157D03*
X378911D03*
X375211D03*
X373361Y1057361D03*
X373362Y1050952D03*
X386312Y1060565D03*
X384462Y1057361D03*
X384461Y1050952D03*
X382612Y1073383D03*
X378911D03*
Y1066974D03*
X375211Y1073383D03*
X373361Y1076587D03*
X373362Y1070178D03*
X386311Y1066974D03*
X384462Y1076587D03*
X384461Y1070178D03*
X378911Y1079791D03*
X386311D03*
X382611Y1092608D03*
X378911D03*
Y1086200D03*
X375211Y1092608D03*
X373362Y1089404D03*
X386311Y1086200D03*
X384461Y1089404D03*
X373362Y1095813D03*
X384462D03*
X380762Y1108630D03*
X378911Y1099017D03*
X377062Y1102221D03*
X373361Y1108630D03*
Y1102221D03*
X386312Y1099017D03*
X384462Y1102221D03*
X382611Y1118243D03*
X378911D03*
X377061Y1115039D03*
X375211Y1118243D03*
X373361Y1115039D03*
X386311Y1118243D03*
X384461Y1115039D03*
X380761Y1127856D03*
X373361D03*
X382611Y1131060D03*
X380761Y1140973D03*
X378911Y1131060D03*
X375211D03*
X373361Y1140973D03*
X386311Y1131060D03*
X396979Y841467D03*
X398829Y851380D03*
X395129D03*
X391429D03*
X402529D03*
X398829Y864197D03*
X396979Y854584D03*
X395129Y864197D03*
X391429D03*
X389579Y854584D03*
X402529Y864197D03*
X396979Y867401D03*
X389579D03*
X398829Y877014D03*
X396979Y880219D03*
X395129Y877014D03*
X391429D03*
X389579Y880219D03*
X402529Y877014D03*
X398829Y889832D03*
X395129Y896240D03*
Y889832D03*
X391428Y896240D03*
X391429Y889832D03*
X389579Y893036D03*
X402529Y889832D03*
X398829Y909057D03*
X398828Y902649D03*
X396979Y912262D03*
X391429Y909057D03*
Y902649D03*
X395129Y915466D03*
X391429D03*
X398829Y928283D03*
X398828Y921875D03*
X396978Y918670D03*
X391429Y928283D03*
Y921875D03*
X400678Y925079D03*
X396979Y931488D03*
X398828Y941100D03*
X395129Y934691D03*
X391429Y941100D03*
Y934691D03*
X400678Y937896D03*
X398829Y947509D03*
X391429D03*
X398828Y960326D03*
X396978Y957122D03*
X396979Y950713D03*
X395129Y953917D03*
X391429Y960326D03*
Y953917D03*
X400678Y957122D03*
X398829Y966735D03*
X391429D03*
X400678Y963530D03*
X398828Y979552D03*
X396978Y976347D03*
X396979Y969939D03*
X395129Y973143D03*
X391429Y979552D03*
Y973143D03*
X400678Y982756D03*
Y969939D03*
X397412Y1009297D03*
X397411Y1002888D03*
X395562Y1006093D03*
X391862D03*
Y999684D03*
X388161Y1006093D03*
X401111Y1002888D03*
X399262Y1012501D03*
X391861D03*
X399261Y1018910D03*
X397411Y1028523D03*
Y1022114D03*
X395562Y1025318D03*
X393711Y1015705D03*
X391862Y1025318D03*
Y1018910D03*
X390012Y1015705D03*
X388161Y1025318D03*
X399262Y1031727D03*
X391862D03*
X399261Y1038136D03*
X397411Y1041340D03*
X395562Y1044544D03*
X391862D03*
Y1038136D03*
X388161Y1044544D03*
X397411Y1047749D03*
X399261Y1057361D03*
X399262Y1050952D03*
X397411Y1060565D03*
X391862Y1057361D03*
Y1050952D03*
X395562Y1063770D03*
X391862D03*
X388161D03*
X399261Y1076587D03*
X399262Y1070178D03*
X397412Y1066974D03*
X391862Y1076587D03*
Y1070178D03*
X401111Y1073383D03*
X397411Y1079791D03*
X401111D03*
X399262Y1089404D03*
X397412Y1086200D03*
X395562Y1082995D03*
X391862Y1089404D03*
Y1082995D03*
X388161D03*
X401112Y1092608D03*
X401111Y1086200D03*
X399261Y1095813D03*
X391862D03*
X402962D03*
X399262Y1102221D03*
X397412Y1099017D03*
X395562Y1102221D03*
X390011Y1105426D03*
X388162Y1108630D03*
Y1102221D03*
X401111Y1105426D03*
X397411Y1111834D03*
X390011D03*
X397411Y1118243D03*
X395561Y1115039D03*
X393711Y1118243D03*
X390011D03*
X388161Y1115039D03*
X401111Y1118243D03*
X395561Y1127856D03*
X388161D03*
X402961D03*
X397411Y1131060D03*
X395561Y1140973D03*
X393711Y1131060D03*
X390011D03*
X388161Y1140973D03*
X402961D03*
X401111Y1131060D03*
X419179Y841467D03*
X404379D03*
X411779D03*
X413629Y851380D03*
X409929D03*
X406229D03*
X417329D03*
X404379Y854584D03*
X413629Y864197D03*
X411779Y854584D03*
X409929Y864197D03*
X406229D03*
X419179Y854584D03*
X417329Y864197D03*
X404379Y867401D03*
X411779D03*
X419179D03*
X404379Y880219D03*
X413629Y877014D03*
X411779Y880219D03*
X409929Y877014D03*
Y870606D03*
X406229Y877014D03*
X419179Y880219D03*
X417329Y877014D03*
X413629Y889832D03*
X411779Y893036D03*
X409929Y889832D03*
X408079Y893036D03*
X406229Y889832D03*
X419179Y893036D03*
X417329Y889832D03*
X413629Y902649D03*
X409929Y909057D03*
Y902649D03*
X404378Y912262D03*
Y905853D03*
X419178Y912262D03*
X419179Y905853D03*
X417329Y902649D03*
X409929Y915466D03*
Y921875D03*
X404378Y918670D03*
X418229Y926896D03*
X419178Y918670D03*
X405048Y930812D03*
X405145Y946239D03*
Y948539D03*
X414093Y942098D03*
X405048Y938046D03*
Y935746D03*
X416393Y942098D03*
X418693D03*
X405122Y965896D03*
Y963596D03*
X414365Y971140D03*
X416755D03*
X404861Y981269D03*
Y978969D03*
Y986421D03*
X405101Y992971D03*
Y995271D03*
X404861Y988721D03*
X405227Y1007156D03*
X405231Y1004848D03*
X417575Y1000060D03*
X415185D03*
X404986Y1022427D03*
X404998Y1026821D03*
X408325Y1031971D03*
Y1034271D03*
X408511Y1041340D03*
X417762Y1044544D03*
X412211Y1047749D03*
X404811D03*
X415911Y1060565D03*
Y1054157D03*
X412211Y1060565D03*
X410361Y1050952D03*
X408511Y1054157D03*
X404811Y1060565D03*
X417761Y1050952D03*
X415911Y1066974D03*
X410362Y1076587D03*
Y1070178D03*
X406661Y1076587D03*
X404811Y1066974D03*
X419611Y1073383D03*
X412211Y1079791D03*
X404811D03*
X415911Y1092608D03*
X415912Y1086200D03*
X412211Y1092608D03*
X408511Y1086200D03*
X417761Y1089404D03*
Y1082995D03*
X410362Y1095813D03*
X406662D03*
X415912Y1099017D03*
X414062Y1108630D03*
X412211Y1099017D03*
X410362Y1102221D03*
X406661Y1108630D03*
Y1102221D03*
X404812Y1105426D03*
X417762Y1102221D03*
X404812Y1111834D03*
X415911Y1118243D03*
X414061Y1121447D03*
X412211Y1124651D03*
Y1118243D03*
X410361Y1115039D03*
X408511Y1118243D03*
X406661Y1115039D03*
X404811Y1118243D03*
X417761Y1115039D03*
X410361Y1127856D03*
X414062Y1134264D03*
X412212Y1131060D03*
X410361Y1140973D03*
X408511Y1131060D03*
X404811D03*
X432128Y844671D03*
X426579Y841467D03*
X432129Y851380D03*
X428429D03*
X424729D03*
X421029D03*
X432129Y864197D03*
X428429D03*
X426579Y854584D03*
X424729Y864197D03*
X421029D03*
X433979Y854584D03*
X426579Y867401D03*
X433979D03*
X432129Y877014D03*
X428429D03*
X426579Y880219D03*
X424729Y877014D03*
X421029D03*
X433979Y880219D03*
X432129Y889832D03*
X428429D03*
X426579Y893036D03*
X424729Y889832D03*
X421029D03*
X433979Y893036D03*
X424729Y902649D03*
X432129D03*
X428429Y909057D03*
Y902649D03*
X421029D03*
X428429Y915466D03*
X433980Y925079D03*
Y931487D03*
X426875Y947199D03*
Y949499D03*
X427875Y936470D03*
X426905Y965935D03*
Y963635D03*
Y980336D03*
Y978036D03*
Y994722D03*
Y992422D03*
Y1006875D03*
Y1009175D03*
Y1021963D03*
Y1019663D03*
X428862Y1044544D03*
X430712Y1047749D03*
X423311D03*
X425162Y1057361D03*
X432561Y1050952D03*
X434411Y1060565D03*
Y1054157D03*
X421462Y1063770D03*
X430711Y1073383D03*
X427011D03*
Y1066974D03*
X425162Y1076587D03*
X423311Y1066974D03*
X432561Y1076587D03*
X434411Y1073383D03*
Y1066974D03*
X427012Y1079791D03*
X434411D03*
X428861Y1082995D03*
X425162Y1089404D03*
X421462Y1082995D03*
X432561Y1089404D03*
Y1082995D03*
X434411Y1086200D03*
X428861Y1095813D03*
X421462D03*
X432561D03*
X427011Y1099017D03*
X425161Y1102221D03*
X423311Y1105426D03*
X421462Y1108630D03*
X434411Y1105426D03*
X423311Y1111834D03*
X434411D03*
X423311Y1124651D03*
Y1118243D03*
X421462Y1115039D03*
X434411Y1124651D03*
Y1118243D03*
X423312Y1137469D03*
X423311Y1131060D03*
X434412Y1137769D03*
X434411Y1131060D03*
X452478Y848176D03*
X445078D03*
X441378D03*
X439529Y844671D03*
X446929Y851380D03*
X443228D03*
X439529D03*
X448779Y854584D03*
X446929Y864197D03*
X443229D03*
X441379Y854584D03*
X439529Y864197D03*
X439528Y857789D03*
X437680Y860992D03*
X450629Y864197D03*
X448779Y867401D03*
X441379D03*
X448779Y880219D03*
X446929Y877014D03*
X443229D03*
X441379Y880219D03*
X439529Y877014D03*
X448779Y893036D03*
X446929Y889832D03*
X443229D03*
X441379Y893036D03*
X439529Y896240D03*
Y889832D03*
X437678Y886627D03*
X450629Y889832D03*
X437679Y899445D03*
X446929Y909057D03*
Y902649D03*
X443229D03*
X439528D03*
X437679Y905853D03*
X450629Y902649D03*
X446929Y915466D03*
X446930Y928283D03*
X441379Y925079D03*
Y931487D03*
X446929Y921875D03*
X437678Y918670D03*
X448779Y937897D03*
X447360Y1038136D03*
X452911Y1041340D03*
X451061Y1044544D03*
X449211Y1047749D03*
X447361Y1057361D03*
Y1050952D03*
X452911Y1060565D03*
X447361Y1063770D03*
Y1076587D03*
Y1070178D03*
X449211Y1073383D03*
X452911Y1079791D03*
X449211D03*
X447361Y1082995D03*
X452911Y1092608D03*
X451062Y1089404D03*
X449212Y1086200D03*
X451062Y1095813D03*
X447361Y1108630D03*
Y1102221D03*
X452911Y1099017D03*
X447361Y1121447D03*
Y1115039D03*
Y1127856D03*
Y1134264D03*
X461729Y851380D03*
X458029D03*
X454328D03*
X456179Y841467D03*
X463579D03*
X469129Y851380D03*
X465429D03*
X456179Y854584D03*
X463579D03*
X461729Y864197D03*
X458029D03*
X454329D03*
X469129D03*
X465429D03*
X456179Y867401D03*
X463579D03*
X461729Y877014D03*
X458029D03*
X456179Y880219D03*
X454329Y877014D03*
X463579Y880219D03*
X469129Y877014D03*
X465429D03*
X461729Y889832D03*
X458029D03*
X456179Y893036D03*
X454329Y889832D03*
X463579Y893036D03*
X469129Y896240D03*
Y889832D03*
X465429D03*
X461729Y902649D03*
X458029D03*
X456178Y905853D03*
X454329Y902649D03*
X465429D03*
Y909057D03*
Y915466D03*
X454103Y931359D03*
Y933659D03*
X456178Y918670D03*
X454434Y1022186D03*
Y1019886D03*
X460311Y1041340D03*
X467372Y1036874D03*
X465861Y1044544D03*
X456611Y1047749D03*
X464011D03*
X456611Y1054157D03*
X462162Y1050952D03*
X454761Y1076587D03*
X462162Y1070178D03*
X456612Y1079791D03*
X467711D03*
X458461Y1082995D03*
X456611Y1086200D03*
X460311Y1092608D03*
X464011Y1086200D03*
X467712D03*
Y1092608D03*
X460312Y1105426D03*
X458462Y1102221D03*
X456611Y1099017D03*
X464012Y1105426D03*
Y1099017D03*
X462162Y1108630D03*
X465861D03*
Y1102221D03*
X464012Y1111834D03*
X467711Y1105426D03*
Y1111834D03*
X458462Y1121447D03*
Y1115039D03*
X467712Y1124651D03*
X467711Y1118243D03*
X465862Y1121447D03*
Y1115039D03*
X458462Y1127856D03*
Y1134264D03*
X478379Y841467D03*
X470979D03*
X476529Y851380D03*
X480229D03*
X472829D03*
X483929D03*
X480229Y864197D03*
X478379Y854584D03*
X476529Y864197D03*
X470979Y854584D03*
X472829Y864197D03*
X483929D03*
X478379Y867401D03*
X470979D03*
X480229Y877014D03*
X478379Y880219D03*
X476529Y877014D03*
X472829D03*
X472828Y870606D03*
X470979Y880219D03*
Y873810D03*
X483929Y877014D03*
X480228Y896240D03*
X480229Y889832D03*
X478379Y893036D03*
X470979D03*
X476529Y889832D03*
X472829D03*
X483929D03*
X482078Y899445D03*
X474678Y905853D03*
X483929Y909057D03*
X482079Y912262D03*
X483928Y902649D03*
X476285Y930126D03*
X476528Y921875D03*
X474678Y918670D03*
X483929Y928283D03*
X482078Y918670D03*
X483928Y921875D03*
X482079Y931488D03*
X476285Y934726D03*
X476180Y945355D03*
Y947655D03*
X478378Y944304D03*
X480229Y934691D03*
X483928Y941100D03*
X482079Y944304D03*
X482078Y937896D03*
X483928Y947509D03*
X476285Y962326D03*
Y960026D03*
Y964626D03*
X483928Y960326D03*
X482078Y957122D03*
X482079Y950713D03*
X483929Y966735D03*
X476285Y966926D03*
X476192Y977670D03*
X476335Y980737D03*
X482079Y969939D03*
X483928Y979552D03*
X482078Y976347D03*
X476285Y996826D03*
Y994526D03*
Y989926D03*
Y987626D03*
X476295Y1010500D03*
X476285Y1012926D03*
Y1006026D03*
Y1003726D03*
X484361Y999684D03*
X482512Y1009297D03*
X482511Y1002888D03*
X484362Y1012501D03*
X476275Y1022636D03*
X476285Y1017526D03*
X482511Y1028523D03*
Y1022114D03*
X484361Y1018910D03*
Y1031727D03*
X471282Y1036526D03*
X473507Y1035928D03*
X475111Y1041340D03*
X482511D03*
X482512Y1034931D03*
X484361Y1038136D03*
X471411Y1047749D03*
X482511D03*
X480662Y1050952D03*
X471411Y1054157D03*
X482511Y1060565D03*
X484362Y1050952D03*
Y1070178D03*
X482511Y1079791D03*
X480662Y1082995D03*
X476962Y1089404D03*
X473262Y1082995D03*
X469561Y1089404D03*
X482512Y1086200D03*
X484362Y1089404D03*
X480661Y1095813D03*
X469562D03*
X484362D03*
X480662Y1108630D03*
X478811Y1099017D03*
X473262Y1108630D03*
X476962Y1102221D03*
X475112Y1099017D03*
X471411D03*
X469562Y1102221D03*
X482511Y1105426D03*
Y1111834D03*
X484362Y1108630D03*
X475111Y1111834D03*
X471411D03*
X478811Y1105426D03*
X469562Y1108630D03*
X473262Y1102221D03*
X482511Y1099017D03*
X478811Y1111834D03*
X476962Y1108630D03*
X471411Y1105426D03*
X475111D03*
X484362Y1102221D03*
X480661Y1115039D03*
X478811Y1118243D03*
X476961Y1115039D03*
X475111Y1118243D03*
X471411D03*
X469561Y1115039D03*
X482511Y1118243D03*
X476961Y1127856D03*
X469562D03*
X484361D03*
X484362Y1115039D03*
X473262D03*
X478811Y1131060D03*
X476961Y1140973D03*
X475111Y1131060D03*
X471412Y1137469D03*
Y1131060D03*
X469561Y1140973D03*
X473261Y1134264D03*
X482511Y1131060D03*
X484361Y1140973D03*
X493179Y841467D03*
X485779D03*
X500579D03*
X495029Y851380D03*
X491329D03*
X487629D03*
X498729D03*
X495029Y864197D03*
X493179Y854584D03*
X491329Y864197D03*
X487629D03*
X485779Y854584D03*
X498729Y864197D03*
X500579Y854584D03*
X493179Y867401D03*
X485779D03*
X500579D03*
X495029Y877014D03*
X493179Y880219D03*
X491329Y877014D03*
X487629D03*
X485779Y880219D03*
X500579D03*
X498729Y877014D03*
X489479Y893036D03*
X495029Y889832D03*
X491329D03*
X487629D03*
X498729D03*
X500579Y893036D03*
X498729Y896240D03*
X496879Y899445D03*
X489478D03*
X496878Y912262D03*
X495029Y909057D03*
X489478Y905853D03*
X495029Y902649D03*
X493179Y905853D03*
X485778D03*
X498728Y915466D03*
X495028Y928283D03*
X493179Y925079D03*
X489478D03*
Y918670D03*
X485778Y925079D03*
X496879Y918670D03*
X495029Y921875D03*
X496878Y931488D03*
X489478D03*
X496879Y937896D03*
X495029Y941100D03*
X493179Y944304D03*
X489478D03*
Y937896D03*
X485778Y944304D03*
X498729Y934691D03*
X495028Y947509D03*
X496879Y957122D03*
X495029Y960326D03*
X489478Y957122D03*
Y950713D03*
X496878D03*
X498729Y953917D03*
X495028Y966735D03*
X493179Y963530D03*
X485778D03*
X489478D03*
X500579D03*
X496879Y976347D03*
X496878Y969939D03*
X489478Y976347D03*
Y969939D03*
X495029Y979552D03*
X498728Y973143D03*
X493179Y982756D03*
X489478D03*
X485778D03*
X497311Y1009297D03*
X497312Y1002888D03*
X495462Y999684D03*
X489911Y1009297D03*
X489912Y1002888D03*
X491761Y1006093D03*
X488062D03*
X499161D03*
X495461Y1012501D03*
X497311Y1028523D03*
X489911D03*
Y1022114D03*
Y1015705D03*
X497311Y1022114D03*
X495462Y1018910D03*
X493612Y1015705D03*
X486211D03*
X501012D03*
X499161Y1025318D03*
X495461Y1031727D03*
X497312Y1041340D03*
X489911D03*
Y1034931D03*
X495462Y1038136D03*
X493612Y1034931D03*
X486211D03*
X499161Y1044544D03*
X489911Y1047749D03*
X497311D03*
Y1060565D03*
X489911D03*
Y1054157D03*
X495461Y1050952D03*
X493611Y1054157D03*
X486211D03*
X489911Y1066974D03*
X495461Y1070178D03*
X489911Y1073383D03*
X497312Y1079791D03*
X489911D03*
X497311Y1086200D03*
X493612Y1092608D03*
X489911D03*
Y1086200D03*
X486211Y1092608D03*
X495461Y1089404D03*
X499161Y1082995D03*
X495462Y1095813D03*
X499162D03*
X491762D03*
X497312Y1105426D03*
X493611D03*
X491762Y1102221D03*
X488061D03*
X486211Y1105426D03*
X486212Y1099017D03*
X499161Y1108630D03*
Y1102221D03*
X497312Y1111834D03*
X489911D03*
Y1099017D03*
X495462Y1102221D03*
X501011Y1099017D03*
X493611D03*
X497311D03*
X489911Y1105426D03*
X486211Y1111834D03*
X491762Y1108630D03*
X488062D03*
X497311Y1118243D03*
X495462Y1121447D03*
X493612Y1118243D03*
X489911D03*
X486211D03*
X501011D03*
X499161Y1115039D03*
X491761Y1127856D03*
X499161D03*
X491762Y1115039D03*
X495462D03*
X497311Y1131060D03*
X493611D03*
X489911D03*
X486211D03*
X491761Y1140973D03*
X501011Y1131060D03*
X499161Y1140973D03*
X507979Y841467D03*
X515379D03*
X506129Y851380D03*
X502429D03*
X513529D03*
X509829D03*
X517229D03*
X513529Y864197D03*
X509829D03*
X506129D03*
X502429D03*
X507979Y854584D03*
X515379D03*
X517229Y864197D03*
X507979Y867401D03*
X515379D03*
X509829Y877014D03*
X507979Y880219D03*
X502429Y877014D03*
X513529D03*
X506129D03*
X515379Y880219D03*
X517229Y877014D03*
X506129Y889832D03*
X502428Y896240D03*
X502429Y889832D03*
X513529D03*
X509829D03*
X506128Y896240D03*
X504279Y893036D03*
X515379D03*
X517229Y889832D03*
X507978Y899445D03*
X515378D03*
X511678Y905853D03*
X509829Y909057D03*
X507979Y912262D03*
X502429Y909057D03*
Y902649D03*
X509828D03*
X515378Y912262D03*
Y905853D03*
X502429Y915466D03*
X506129D03*
X511678Y925079D03*
X509829Y928283D03*
X502429D03*
Y921875D03*
X509828D03*
X507978Y918670D03*
X515378Y925079D03*
Y918670D03*
X507979Y931488D03*
X515378D03*
X511678Y944304D03*
X509828Y941100D03*
X506129Y934691D03*
X502429Y941100D03*
Y934691D03*
X515378Y944304D03*
Y937896D03*
X502429Y947509D03*
X509828Y960326D03*
X507978Y957122D03*
X506129Y953917D03*
X502429Y960326D03*
Y953917D03*
X507979Y950713D03*
X515378Y957122D03*
Y950713D03*
X509829Y966735D03*
X502428D03*
X511678Y963530D03*
X504278D03*
X515378D03*
X507978Y976347D03*
X507979Y969939D03*
X502429Y979552D03*
Y973143D03*
X513529D03*
X509828Y979552D03*
X506129Y973143D03*
X515379Y976347D03*
X515378Y969939D03*
X517228Y973143D03*
X511678Y982756D03*
X515378D03*
X510261Y999684D03*
X508411Y1002888D03*
X506562Y1006093D03*
X502862Y999684D03*
X502861Y1012501D03*
X508412Y1009297D03*
X510262Y1012501D03*
X515811Y1009297D03*
Y1002888D03*
X508411Y1028523D03*
X502862Y1025318D03*
Y1018910D03*
X510261D03*
X508411Y1022114D03*
X506562Y1025318D03*
X504711Y1015705D03*
X515811Y1028523D03*
Y1022114D03*
X510262Y1031727D03*
X502862D03*
X515811Y1015705D03*
X512111D03*
X502862Y1044544D03*
Y1038136D03*
X512111Y1034931D03*
X510261Y1038136D03*
X508411Y1041340D03*
X506562Y1044544D03*
X515811Y1034931D03*
Y1041340D03*
X508411Y1047749D03*
X515811D03*
X508411Y1060565D03*
X502862Y1057361D03*
Y1050952D03*
X512111Y1054157D03*
X510262Y1050952D03*
X515811Y1054157D03*
Y1060565D03*
X502862Y1063770D03*
X510262Y1070178D03*
X502862Y1076587D03*
Y1070178D03*
X515811Y1073383D03*
Y1079791D03*
X512112Y1092608D03*
X510262Y1089404D03*
X508412Y1086200D03*
X506562Y1082995D03*
X502862Y1089404D03*
Y1082995D03*
X515812Y1092608D03*
X513961Y1095813D03*
X502862D03*
X517662D03*
X513962Y1108630D03*
Y1102221D03*
X512112Y1099017D03*
X508411D03*
X506562Y1108630D03*
X504711Y1099017D03*
X502862Y1102221D03*
X515811Y1105426D03*
Y1111834D03*
X517662Y1108630D03*
X513961Y1115039D03*
X512111Y1118243D03*
X508411D03*
X504711D03*
X510261Y1115039D03*
X515811Y1118243D03*
X513961Y1127856D03*
X506561D03*
X517662Y1115039D03*
X513961Y1140973D03*
X512111Y1131060D03*
X508411D03*
X504711D03*
X506561Y1140973D03*
X515811Y1131060D03*
X528329Y844671D03*
X522779Y841467D03*
X528329Y851380D03*
X524629D03*
X520929D03*
X532029D03*
X528329Y864197D03*
X524629D03*
X520929D03*
X530179Y860993D03*
Y854584D03*
X522779D03*
X532028Y857789D03*
X533879Y860993D03*
X530178Y867401D03*
X522779D03*
X533879D03*
X528329Y877014D03*
X522779Y880219D03*
X520929Y877014D03*
X530179Y880219D03*
X524629Y877014D03*
X532029D03*
X533879Y880219D03*
Y873810D03*
X532028Y883423D03*
X528329Y896240D03*
Y889832D03*
X524629D03*
X526479Y893036D03*
X524629Y896240D03*
X520929Y889832D03*
X532029D03*
Y896240D03*
X533879Y893036D03*
X522779Y899445D03*
X533879D03*
X528329Y902649D03*
X522778Y912262D03*
X520928Y909057D03*
X519079Y905853D03*
X520929Y902649D03*
X528329Y915466D03*
X524628D03*
X532029D03*
X528329Y909057D03*
X533879Y912262D03*
X528329Y921875D03*
X520928Y928283D03*
X519079Y925079D03*
X522779Y918670D03*
X520929Y921875D03*
X522778Y931488D03*
X528329Y928283D03*
X533879Y918670D03*
X533878Y931488D03*
X528329Y941100D03*
Y934691D03*
X524628D03*
X522779Y937896D03*
X520929Y941100D03*
X519079Y944304D03*
X520928Y947509D03*
X532029Y934691D03*
X533879Y937896D03*
X528329Y947509D03*
Y960326D03*
Y953917D03*
X524629D03*
X522779Y957122D03*
X520929Y960326D03*
X522778Y950713D03*
X520928Y966735D03*
X526479Y963530D03*
X519079D03*
X533879Y957122D03*
X532029Y953917D03*
X533879Y950713D03*
X530178Y963530D03*
X528329Y966735D03*
Y979552D03*
Y973143D03*
X522779Y976347D03*
X522778Y969939D03*
X524628Y973143D03*
X520929Y979552D03*
X533879Y976347D03*
X519079Y982756D03*
X533901Y980606D03*
X533879Y969939D03*
X532029Y973143D03*
X521361Y1012501D03*
Y999684D03*
X528762Y1006093D03*
Y999684D03*
X525061Y1006093D03*
X523211Y1009297D03*
X523212Y1002888D03*
X534311Y1009297D03*
Y1002888D03*
X532461Y1006093D03*
X528761Y1012501D03*
X528762Y1025318D03*
X523211Y1028523D03*
X525061Y1025318D03*
X528762Y1031727D03*
X521361D03*
X519512Y1015705D03*
X521362Y1018910D03*
X523211Y1022114D03*
X526912Y1015705D03*
X528762Y1018910D03*
X530611Y1015705D03*
X534311Y1028523D03*
X534310Y1022114D03*
X532461Y1025318D03*
X528762Y1044544D03*
X525061D03*
X523212Y1041340D03*
X521362Y1038136D03*
X519512Y1034931D03*
X532462Y1044544D03*
X523211Y1047749D03*
X528762Y1038136D03*
X534311Y1041340D03*
Y1047749D03*
X528762Y1057361D03*
Y1050952D03*
X523212Y1060565D03*
X521361Y1050952D03*
X519512Y1054157D03*
X528762Y1063770D03*
X534311Y1060565D03*
X528762Y1076587D03*
Y1070178D03*
X521361D03*
X523212Y1079791D03*
X534311D03*
X523211Y1086200D03*
X521361Y1089404D03*
X519511Y1092608D03*
X528762Y1089404D03*
Y1082995D03*
X525061D03*
X532462Y1082996D03*
X534311Y1086200D03*
X528761Y1095813D03*
X526911Y1105426D03*
X521361Y1102221D03*
X519511Y1105426D03*
X519512Y1099017D03*
X532461Y1108630D03*
X530612Y1111834D03*
X523211D03*
X526911Y1099017D03*
X534311D03*
X532460Y1102221D03*
X521362Y1108630D03*
X525062D03*
X534311Y1111834D03*
X523211Y1105426D03*
X534311D03*
X528762Y1108630D03*
X519511Y1111834D03*
X526911D03*
X530611Y1124651D03*
Y1118243D03*
X528762Y1121447D03*
X523211Y1118243D03*
X521361Y1115039D03*
X519511Y1118243D03*
X532461Y1115039D03*
X528761Y1127856D03*
X521361D03*
X525062Y1115039D03*
X528762D03*
X530612Y1137469D03*
Y1131060D03*
X526912D03*
X523211D03*
X519511D03*
X528761Y1134264D03*
X521361Y1140973D03*
X534311Y1131060D03*
X537580Y848176D03*
X535729Y844671D03*
Y851380D03*
X544979Y860993D03*
Y854584D03*
X539428Y864197D03*
X537579Y854584D03*
Y860993D03*
X544979Y867401D03*
X541279D03*
X537579D03*
X546829Y870606D03*
X541279Y873810D03*
X535729Y870606D03*
Y883423D03*
X541279Y880219D03*
X546829Y883423D03*
X537579Y893036D03*
X541279Y886627D03*
X544979D03*
X537579D03*
X535729Y889832D03*
X550529D03*
X537579Y899445D03*
X548679Y912262D03*
X537579D03*
X539429Y909057D03*
X537579Y905853D03*
X535729Y909057D03*
X543129D03*
X535729Y902649D03*
X548679Y905853D03*
X537579Y918670D03*
X535729Y921875D03*
X537578Y931488D03*
X548678D03*
X537579Y937896D03*
X535729Y941100D03*
X539429Y947509D03*
X535729D03*
X537579Y957122D03*
Y950713D03*
X535729Y960326D03*
Y966735D03*
X537579Y963530D03*
X539429Y979552D03*
X537579Y982756D03*
X541279Y969939D03*
X539429Y973143D03*
X535729D03*
X539862Y1006092D03*
X539861Y999684D03*
X536161D03*
Y1006093D03*
X543563Y1006092D03*
X549254Y1000648D03*
X536161Y1012501D03*
Y1025318D03*
X539861Y1018910D03*
X541712Y1015705D03*
X545412D03*
X538012D03*
X536161Y1018910D03*
X549112Y1015705D03*
X536161Y1031727D03*
X545412Y1034931D03*
X539862Y1044544D03*
X539861Y1038136D03*
X541711Y1034931D03*
X538011D03*
X536161Y1038136D03*
X549112Y1034931D03*
X541711Y1054157D03*
X538011D03*
X545411D03*
X538011Y1060565D03*
X536161Y1050952D03*
X538011Y1066974D03*
X539861Y1076587D03*
X536162Y1082996D03*
X538011Y1092608D03*
X536161Y1089404D03*
X545411Y1092608D03*
X547262Y1082996D03*
X543561Y1095813D03*
X536161D03*
X547261D03*
X545412Y1105426D03*
X541711D03*
X539861Y1108630D03*
Y1102221D03*
X536161D03*
X541711Y1111834D03*
X545411D03*
X538011Y1105426D03*
X536161Y1108630D03*
X538011Y1111834D03*
X543561Y1108630D03*
X545411Y1124651D03*
Y1118243D03*
X543562Y1115039D03*
X539862D03*
X538011Y1124651D03*
X536161Y1115039D03*
X541711Y1131060D03*
X536162Y1134264D03*
X551429Y979057D03*
X550701Y972608D03*
X550961Y1031727D03*
X560571Y1614292D03*
X580431Y1602380D03*
X688999Y1051247D03*
X748399D03*
X1293802Y162999D03*
X1297007Y161149D03*
X1297012Y168549D03*
X1297007Y164849D03*
X1293802Y183349D03*
Y187049D03*
Y190749D03*
Y198149D03*
Y194449D03*
Y201849D03*
X1296999Y209249D03*
X1300774Y155288D03*
X1309832Y161149D03*
X1303417D03*
X1309832Y168549D03*
X1303417D03*
X1303422Y172249D03*
X1313033Y174099D03*
X1306622D03*
X1300207Y185199D03*
X1306617Y181499D03*
X1300207Y192599D03*
X1309817Y187049D03*
X1306617Y192599D03*
X1313023Y199999D03*
X1306617D03*
X1300207D03*
X1303407Y201849D03*
X1303422Y209249D03*
X1313032Y214799D03*
X1306622Y218499D03*
X1303417Y212949D03*
Y216649D03*
X1300207Y214799D03*
X1301151Y225450D03*
X1309828Y224049D03*
X1306622Y222199D03*
X1309100Y236477D03*
X1313920Y854584D03*
X1312266Y857972D03*
X1312070Y877014D03*
X1310221Y880219D03*
X1308370Y877014D03*
X1312070Y896240D03*
X1310220Y893036D03*
X1308371Y902649D03*
X1312070Y915466D03*
X1308370D03*
X1308371Y921875D03*
X1312070Y934692D03*
X1308371Y941100D03*
X1308370Y934692D03*
X1312070Y953917D03*
X1308370D03*
X1310221Y957122D03*
X1308371Y973143D03*
X1310221Y976347D03*
X1314352Y996480D03*
X1314353Y1002888D03*
X1308803Y1006093D03*
X1314353Y1015705D03*
Y1022114D03*
X1308803Y1025318D03*
Y1018910D03*
X1314353Y1041340D03*
X1308803Y1044544D03*
X1310653Y1041340D03*
X1314353Y1060565D03*
X1312502Y1082995D03*
X1314353Y1111834D03*
Y1105426D03*
X1312503Y1115039D03*
Y1127856D03*
X1320469Y155288D03*
X1322652Y161149D03*
X1316242D03*
X1319452Y166699D03*
X1329062Y168549D03*
X1319442Y170399D03*
X1318502Y176574D03*
Y186024D03*
Y182874D03*
X1329062Y172249D03*
X1316237D03*
X1331102Y176574D03*
X1327952Y186024D03*
Y182874D03*
X1318502Y189174D03*
X1315352Y195474D03*
X1327952Y189174D03*
X1331102Y195474D03*
X1327952Y198624D03*
X1321652D03*
X1325852Y214799D03*
X1319442Y218499D03*
X1329062Y209249D03*
X1319442Y207399D03*
X1329062Y216649D03*
X1319442Y222199D03*
X1329061Y224049D03*
X1326377Y235784D03*
X1321986Y236726D03*
X1326869Y844971D03*
X1323170D03*
X1321320Y848176D03*
X1330571Y851380D03*
X1323170D03*
X1319469D03*
X1317620Y854584D03*
X1315770Y857789D03*
X1330571Y864197D03*
X1326871D03*
X1323171D03*
Y857789D03*
X1325020Y854584D03*
X1321321Y860993D03*
X1319469Y857789D03*
X1317621Y867401D03*
X1328721D03*
X1325021D03*
X1330571Y877014D03*
X1328722Y880219D03*
X1326871Y877014D03*
X1321321Y873810D03*
X1315771Y877014D03*
X1317621Y873810D03*
X1321321Y880219D03*
X1319471Y877014D03*
X1315771Y883423D03*
X1326871D03*
X1323171D03*
X1328720Y899445D03*
X1315771Y896240D03*
Y889832D03*
X1328720Y893036D03*
Y886627D03*
X1325021D03*
X1321321Y893036D03*
X1319470Y896240D03*
X1321321Y899445D03*
X1328720Y905853D03*
X1325020D03*
X1317621Y912262D03*
X1317620Y905853D03*
X1328720Y912262D03*
X1323171Y909057D03*
Y902649D03*
X1321321Y912262D03*
X1315771Y915466D03*
X1319471D03*
X1328720Y925079D03*
Y918670D03*
X1325020Y925079D03*
X1317620D03*
X1323171Y928283D03*
Y921875D03*
X1321321Y918670D03*
X1317621Y931488D03*
X1328720D03*
X1321321D03*
X1323171Y941100D03*
X1325020Y944304D03*
X1323171Y947509D03*
X1317620Y944304D03*
X1328720D03*
Y937896D03*
X1315771Y934692D03*
X1321321Y937896D03*
X1319470Y934692D03*
X1321321Y957122D03*
X1323171Y966735D03*
X1325020Y963530D03*
X1323171Y960326D03*
X1321321Y950713D03*
X1315771Y953917D03*
Y966735D03*
X1319470Y953917D03*
X1319471Y966735D03*
X1319470Y960326D03*
X1317621Y950713D03*
X1328720Y957122D03*
Y963530D03*
Y950713D03*
X1321321Y969939D03*
X1325020Y982756D03*
X1323171Y979552D03*
X1321321Y976347D03*
X1315771Y973143D03*
X1319471D03*
X1328720Y969939D03*
X1330570Y973143D03*
X1326871D03*
X1328720Y982756D03*
X1328721Y976347D03*
X1315771Y979552D03*
X1318053Y1009297D03*
Y1002888D03*
X1327304Y1006093D03*
X1331003D03*
X1329153Y1009297D03*
Y1002888D03*
X1323603Y999684D03*
X1321753Y1009297D03*
X1319903Y1006093D03*
X1321753Y1002888D03*
X1323603Y1012501D03*
X1329153Y1028523D03*
Y1015705D03*
X1318053Y1022114D03*
Y1015705D03*
X1329153Y1022114D03*
X1325453Y1015705D03*
X1323603Y1018910D03*
X1321753Y1028523D03*
X1319903Y1018910D03*
X1321753Y1022114D03*
Y1015705D03*
X1319903Y1031727D03*
X1323603D03*
X1329153Y1034931D03*
Y1047749D03*
X1318053Y1041340D03*
X1319903Y1038136D03*
X1329153Y1041340D03*
X1325453Y1034931D03*
X1323603Y1038136D03*
X1321753Y1041340D03*
X1319903Y1044544D03*
X1321753Y1047749D03*
X1329153Y1060565D03*
Y1054157D03*
X1325453D03*
X1319903Y1057361D03*
Y1050952D03*
X1323603D03*
Y1057361D03*
X1321753Y1060565D03*
X1319903Y1063770D03*
X1329153Y1073383D03*
X1319903Y1076587D03*
Y1070178D03*
X1316204Y1076587D03*
X1329153Y1066974D03*
X1323603Y1076587D03*
Y1070178D03*
X1325454Y1073383D03*
X1321753Y1066974D03*
X1329153Y1079791D03*
X1321753D03*
X1318053D03*
X1329153Y1086200D03*
Y1092608D03*
X1325452Y1092609D03*
X1323603Y1089404D03*
X1321752Y1086200D03*
X1319902Y1082995D03*
X1316202D03*
X1316203Y1095813D03*
X1331003Y1108630D03*
X1329153Y1099017D03*
X1323603Y1108630D03*
X1316203D03*
Y1102221D03*
X1325453Y1099017D03*
X1323603Y1102221D03*
X1319903D03*
X1316203Y1115039D03*
X1331003D03*
X1327303Y1121447D03*
Y1115039D03*
X1325453Y1124651D03*
X1325454Y1118243D03*
X1321753D03*
X1319903Y1115039D03*
X1329152Y1137469D03*
X1329153Y1131060D03*
X1321752Y1137469D03*
X1325453Y1131060D03*
X1319903Y1134264D03*
X1344103Y155288D03*
X1342936Y159301D03*
X1335472Y161149D03*
X1346137Y168549D03*
X1342907Y166699D03*
X1332268D03*
X1346137Y164849D03*
X1339727D03*
X1335472Y168549D03*
X1339568Y176028D03*
X1339727Y179649D03*
X1342937Y181499D03*
Y185199D03*
X1346137Y172249D03*
X1335472D03*
X1339727Y190749D03*
X1342937Y188899D03*
X1334252Y195474D03*
X1346137Y194449D03*
Y190749D03*
X1346147Y209248D03*
X1332262Y218499D03*
Y214799D03*
X1332285Y226210D03*
X1342937Y222199D03*
X1332267D03*
X1343521Y841467D03*
X1336121D03*
X1345371Y851380D03*
X1341671D03*
X1337971D03*
X1334271D03*
X1345371Y864197D03*
X1343521Y854584D03*
X1341671Y864197D03*
X1337971D03*
X1336121Y854584D03*
X1334271Y864197D03*
X1343521Y867401D03*
X1336121D03*
X1345371Y877014D03*
X1343521Y880219D03*
X1341671Y877014D03*
X1337971D03*
X1334271D03*
X1332420Y886627D03*
X1345371Y896240D03*
Y889832D03*
X1341671Y896240D03*
Y889832D03*
X1337970Y896240D03*
X1337971Y889832D03*
X1336121Y893036D03*
X1334270Y889832D03*
X1332420Y905853D03*
X1341671Y909057D03*
Y902649D03*
X1336120Y912262D03*
X1334270Y909057D03*
X1334271Y902649D03*
X1347221Y912262D03*
X1345371Y915466D03*
X1341671D03*
X1337970D03*
X1332421Y925079D03*
X1341671Y928283D03*
Y921875D03*
X1334270Y928283D03*
X1334271Y921875D03*
X1347220Y918670D03*
X1336120Y931488D03*
X1347221D03*
X1341671Y947509D03*
X1334270D03*
X1334271Y941100D03*
X1332421Y944304D03*
X1345371Y934691D03*
X1341671D03*
X1337970D03*
X1337971Y953917D03*
X1345371D03*
X1341671D03*
Y960326D03*
X1347220Y957122D03*
X1343520Y963530D03*
X1339821D03*
X1341670Y966735D03*
X1347221Y950713D03*
X1334271Y960326D03*
X1336121Y957122D03*
X1332421Y963530D03*
X1334270Y966735D03*
X1336120Y950713D03*
X1347221Y969939D03*
X1337970Y973143D03*
X1347220Y976347D03*
X1345371Y973143D03*
X1341671Y979552D03*
Y973143D03*
X1336120Y969939D03*
X1336121Y976347D03*
X1334271Y979552D03*
X1332421Y982756D03*
X1342104Y999684D03*
Y1006093D03*
X1338403D03*
X1336553Y1009297D03*
X1336554Y1002888D03*
X1334704Y999684D03*
X1347654Y1009297D03*
X1342103Y1012501D03*
X1334703D03*
X1332854Y1015705D03*
X1345804Y1025318D03*
X1343953Y1015705D03*
X1342104Y1025318D03*
Y1018910D03*
X1340254Y1015705D03*
X1336553Y1028523D03*
X1338403Y1025318D03*
X1336554Y1022114D03*
X1334704Y1018910D03*
X1347653Y1028523D03*
Y1022114D03*
X1342104Y1031727D03*
X1334703D03*
X1332854Y1034931D03*
X1345804Y1044544D03*
X1342104D03*
Y1038136D03*
X1338403Y1044544D03*
X1336554Y1041340D03*
X1334704Y1038136D03*
X1347653Y1041340D03*
X1336553Y1047749D03*
X1347653D03*
X1332854Y1054157D03*
X1342104Y1057361D03*
Y1050952D03*
X1336554Y1060565D03*
X1334704Y1057361D03*
X1334703Y1050952D03*
X1347653Y1060565D03*
X1345804Y1063770D03*
X1342104D03*
X1338403D03*
X1332854Y1073383D03*
X1342104Y1070178D03*
X1336553Y1066974D03*
X1334703Y1070178D03*
X1334704Y1076587D03*
X1347654Y1066974D03*
X1336554Y1079791D03*
X1347653D03*
X1345804Y1082995D03*
X1342104Y1089404D03*
Y1082995D03*
X1338403D03*
X1336553Y1086200D03*
X1334703Y1089404D03*
X1332854Y1092608D03*
X1347654Y1086200D03*
X1342104Y1095813D03*
X1334703D03*
X1342104Y1102221D03*
X1338404D03*
X1336553Y1099017D03*
X1332853Y1105426D03*
Y1099017D03*
X1347654Y1105426D03*
Y1099017D03*
X1340254Y1111834D03*
X1332854D03*
X1347654D03*
X1343953Y1118243D03*
X1340253D03*
X1338403Y1115039D03*
X1336553Y1118243D03*
X1332853D03*
X1347653D03*
X1342104Y1127856D03*
X1334703D03*
X1343953Y1131060D03*
X1342103Y1140973D03*
X1340254Y1131060D03*
X1336554D03*
X1334703Y1140973D03*
X1332854Y1131060D03*
X1347653D03*
X1349351Y159298D03*
X1355758D03*
X1355761Y162998D03*
X1358865Y166732D03*
Y158854D03*
Y162793D03*
X1349351Y166698D03*
X1352557Y164848D03*
X1358865Y170671D03*
Y174603D03*
Y182484D03*
Y178544D03*
X1355761Y170398D03*
X1352557Y179648D03*
X1358371Y188778D03*
X1358865Y195240D03*
Y199180D03*
X1349351Y196298D03*
X1352561Y194448D03*
X1352551Y190748D03*
X1349345Y188898D03*
X1355761Y192598D03*
X1358865Y207060D03*
Y203120D03*
Y213994D03*
Y217934D03*
X1352560Y205549D03*
X1355765Y207399D03*
X1349351Y214798D03*
X1352561Y212948D03*
X1349351Y211098D03*
Y222198D03*
X1358321Y841467D03*
X1350921D03*
X1360171Y851380D03*
X1356471D03*
X1352771D03*
X1349071D03*
X1363871D03*
X1360171Y864197D03*
X1358321Y854584D03*
X1356471Y864197D03*
X1352771D03*
X1350921Y854584D03*
X1349071Y864197D03*
X1363871D03*
X1358321Y867401D03*
X1350921D03*
X1360171Y877014D03*
X1358321Y880219D03*
X1356471Y877014D03*
X1352771D03*
X1350921Y880219D03*
X1349071Y877014D03*
X1363871D03*
X1360171Y889832D03*
X1356471D03*
X1354621Y893036D03*
X1352771Y889832D03*
X1349071D03*
X1363871Y896240D03*
Y889832D03*
X1362021Y899445D03*
X1354620D03*
X1362020Y912262D03*
X1360170Y909057D03*
X1360171Y902649D03*
X1358321Y905853D03*
X1354620Y912262D03*
Y905853D03*
X1350920D03*
X1349071Y909057D03*
X1349070Y902649D03*
X1363870Y915466D03*
X1362021Y918670D03*
X1360170Y928283D03*
X1360171Y921875D03*
X1358321Y925079D03*
X1354620D03*
Y918670D03*
X1350920Y925079D03*
X1349071Y928283D03*
X1349070Y921875D03*
X1362020Y931488D03*
X1360171Y941100D03*
X1358321Y944304D03*
X1354620D03*
X1360170Y947509D03*
X1350920Y944304D03*
X1349071Y947509D03*
X1349070Y941100D03*
X1362021Y937896D03*
X1354620D03*
X1363870Y934691D03*
X1363871Y953917D03*
X1360171Y960326D03*
X1362021Y957122D03*
X1354620D03*
X1358321Y963530D03*
X1354620D03*
X1360170Y966735D03*
X1354620Y950713D03*
X1362020D03*
X1349070Y960326D03*
X1350920Y963530D03*
X1349071Y966735D03*
X1362020Y969939D03*
X1354620D03*
X1363870Y973143D03*
X1362021Y976347D03*
X1360171Y979552D03*
X1358321Y982756D03*
X1356470Y973143D03*
X1354620Y982756D03*
X1354621Y976347D03*
X1350920Y982756D03*
X1349070Y979552D03*
X1352771Y973143D03*
X1351352Y996480D03*
X1349503Y999684D03*
X1362453Y1009297D03*
X1362454Y1002888D03*
X1360604Y999684D03*
X1355053Y1009297D03*
Y1002888D03*
X1360603Y1012501D03*
X1349504D03*
X1362453Y1028523D03*
X1362454Y1022114D03*
X1360604Y1018910D03*
X1358754Y1015705D03*
X1355053Y1028523D03*
Y1022114D03*
Y1015705D03*
X1351353D03*
X1349503Y1018910D03*
X1360603Y1031727D03*
X1349504D03*
X1362454Y1041340D03*
X1360604Y1038136D03*
X1358754Y1034931D03*
X1355053Y1041340D03*
Y1034931D03*
X1351353D03*
X1349503Y1038136D03*
X1362453Y1047749D03*
X1355053D03*
X1362454Y1060565D03*
X1360604Y1057361D03*
X1360603Y1050952D03*
X1358754Y1054157D03*
X1355053D03*
X1351353D03*
X1349503Y1057361D03*
X1349504Y1050952D03*
X1362453Y1066974D03*
X1360604Y1076587D03*
X1360603Y1070178D03*
X1358754Y1073383D03*
X1355053D03*
Y1066974D03*
X1351353Y1073383D03*
X1349503Y1076587D03*
X1349504Y1070178D03*
X1362453Y1079791D03*
X1355053D03*
X1362453Y1086200D03*
X1360603Y1089404D03*
X1358753Y1092608D03*
X1355053D03*
Y1086200D03*
X1351353Y1092608D03*
X1349504Y1089404D03*
X1360604Y1095813D03*
X1349504D03*
X1362454Y1099017D03*
X1360604Y1102221D03*
X1356904Y1108630D03*
X1355053Y1099017D03*
X1353204Y1102221D03*
X1349503Y1108630D03*
Y1102221D03*
X1362453Y1118243D03*
X1360603Y1115039D03*
X1358753Y1118243D03*
X1355053D03*
X1353203Y1115039D03*
X1351353Y1118243D03*
X1349503Y1115039D03*
X1356903Y1127856D03*
X1349503D03*
X1362453Y1131060D03*
X1358753D03*
X1356903Y1140973D03*
X1355053Y1131060D03*
X1351353D03*
X1349503Y1140973D03*
X1373121Y841467D03*
X1365721D03*
X1378671Y851380D03*
X1374971D03*
X1371271D03*
X1367571D03*
X1378671Y864197D03*
X1374971D03*
X1373121Y854584D03*
X1371271Y864197D03*
X1367571D03*
X1365721Y854584D03*
X1373121Y867401D03*
X1365721D03*
X1378671Y877014D03*
X1374971D03*
X1373121Y880219D03*
X1371271Y877014D03*
X1367571D03*
X1365721Y880219D03*
X1378671Y889832D03*
X1374971D03*
X1371271Y896240D03*
Y889832D03*
X1367570Y896240D03*
X1367571Y889832D03*
X1365721Y893036D03*
X1374971Y909057D03*
X1374970Y902649D03*
X1373121Y912262D03*
X1367571Y909057D03*
Y902649D03*
X1371271Y915466D03*
X1367571D03*
X1376820Y925079D03*
X1374971Y928283D03*
X1374970Y921875D03*
X1373120Y918670D03*
X1367571Y928283D03*
Y921875D03*
X1376820Y937896D03*
X1374970Y941100D03*
X1371271Y934691D03*
X1367571Y941100D03*
Y934691D03*
X1374971Y947509D03*
X1367571D03*
X1376820Y957122D03*
X1374970Y960326D03*
X1373120Y957122D03*
X1373121Y950713D03*
X1371271Y953917D03*
X1367571Y960326D03*
Y953917D03*
X1376820Y963530D03*
X1374971Y966735D03*
X1367571D03*
X1376820Y982756D03*
Y969939D03*
X1374970Y979552D03*
X1373120Y976347D03*
X1373121Y969939D03*
X1371271Y973143D03*
X1367571Y979552D03*
Y973143D03*
X1364303Y1006093D03*
X1377253Y1002888D03*
X1373554Y1009297D03*
X1373553Y1002888D03*
X1371704Y1006093D03*
X1368004D03*
Y999684D03*
X1375404Y1012501D03*
X1368003D03*
X1364303Y1025318D03*
X1375403Y1018910D03*
X1373553Y1028523D03*
Y1022114D03*
X1371704Y1025318D03*
X1369853Y1015705D03*
X1368004Y1025318D03*
Y1018910D03*
X1366154Y1015705D03*
X1375404Y1031727D03*
X1368004D03*
X1364303Y1044544D03*
X1375403Y1038136D03*
X1373553Y1041340D03*
X1371704Y1044544D03*
X1368004D03*
Y1038136D03*
X1373553Y1047749D03*
X1375403Y1057361D03*
X1375404Y1050952D03*
X1373553Y1060565D03*
X1368004Y1057361D03*
Y1050952D03*
X1364303Y1063770D03*
X1371704D03*
X1368004D03*
X1377253Y1073383D03*
X1375403Y1076587D03*
X1375404Y1070178D03*
X1373554Y1066974D03*
X1368004Y1076587D03*
Y1070178D03*
X1377253Y1079791D03*
X1373553D03*
X1364303Y1082995D03*
X1377254Y1092608D03*
X1377253Y1086200D03*
X1375404Y1089404D03*
X1373554Y1086200D03*
X1371704Y1082995D03*
X1368004Y1089404D03*
Y1082995D03*
X1379104Y1095813D03*
X1375403D03*
X1368004D03*
X1364304Y1108630D03*
Y1102221D03*
X1377253Y1105426D03*
X1375404Y1102221D03*
X1373554Y1099017D03*
X1371704Y1102221D03*
X1366153Y1105426D03*
X1373553Y1111834D03*
X1366153D03*
X1364303Y1115039D03*
X1377253Y1118243D03*
X1373553D03*
X1371703Y1115039D03*
X1369853Y1118243D03*
X1366153D03*
X1364303Y1127856D03*
X1379103D03*
X1371703D03*
X1364303Y1140973D03*
X1379103D03*
X1377253Y1131060D03*
X1373553D03*
X1371703Y1140973D03*
X1369853Y1131060D03*
X1366153D03*
X1380521Y841467D03*
X1395321D03*
X1387921D03*
X1393471Y851380D03*
X1389771D03*
X1386071D03*
X1382371D03*
X1380521Y854584D03*
X1395321D03*
X1393471Y864197D03*
X1389771D03*
X1387921Y854584D03*
X1386071Y864197D03*
X1382371D03*
X1380521Y867401D03*
X1395321D03*
X1387921D03*
X1380521Y880219D03*
X1395321D03*
X1393471Y877014D03*
X1389771D03*
X1387921Y880219D03*
X1386071Y877014D03*
Y870606D03*
X1382371Y877014D03*
X1395321Y893036D03*
X1393471Y889832D03*
X1389771D03*
X1387921Y893036D03*
X1386071Y889832D03*
X1384221Y893036D03*
X1382371Y889832D03*
X1386071Y902649D03*
X1380520Y912262D03*
Y905853D03*
X1395320Y912262D03*
X1395321Y905853D03*
X1393471Y902649D03*
X1389771D03*
X1386071Y909057D03*
Y915466D03*
X1380520Y918670D03*
X1395187Y926265D03*
X1395320Y918670D03*
X1386071Y921875D03*
X1381189Y930811D03*
Y938045D03*
X1381287Y946239D03*
Y948539D03*
X1381189Y935745D03*
X1390234Y942097D03*
X1381264Y965896D03*
Y963596D03*
X1390506Y971139D03*
X1392896D03*
X1381003Y981269D03*
Y978969D03*
Y986421D03*
X1381243Y992971D03*
Y995271D03*
X1381003Y988721D03*
X1381369Y1007156D03*
X1381373Y1004848D03*
X1393716Y1000059D03*
X1391326D03*
X1381128Y1022427D03*
X1381140Y1026821D03*
X1384466Y1034270D03*
Y1031970D03*
X1393904Y1044544D03*
X1384653Y1041340D03*
X1380953Y1047749D03*
X1388353D03*
X1380953Y1060565D03*
X1393904Y1050952D03*
X1392053Y1060565D03*
Y1054157D03*
X1388353Y1060565D03*
X1386504Y1050952D03*
X1384653Y1054157D03*
X1380953Y1066974D03*
X1395753Y1073383D03*
X1392053Y1066974D03*
X1386504Y1076587D03*
Y1070178D03*
X1382803Y1076587D03*
X1380953Y1079791D03*
X1388353D03*
X1393903Y1089404D03*
Y1082995D03*
X1392053Y1092608D03*
X1392054Y1086200D03*
X1388353Y1092608D03*
X1384653Y1086200D03*
X1386504Y1095813D03*
X1382804D03*
X1380954Y1105426D03*
X1393904Y1102221D03*
X1392054Y1099017D03*
X1390204Y1108630D03*
X1388353Y1099017D03*
X1386504Y1102221D03*
X1382803Y1108630D03*
Y1102221D03*
X1380954Y1111834D03*
X1380953Y1118243D03*
X1386503Y1115039D03*
X1384653Y1118243D03*
X1382803Y1115039D03*
X1386503Y1127856D03*
X1380953Y1131060D03*
X1386503Y1140973D03*
X1384653Y1131060D03*
X1408269Y844971D03*
X1402721Y841467D03*
X1397171Y851380D03*
X1408271D03*
X1404571D03*
X1400871D03*
X1397171Y864197D03*
X1408271D03*
X1404571D03*
X1402721Y854584D03*
X1400871Y864197D03*
X1410121Y854584D03*
Y867401D03*
X1402721D03*
X1397171Y877014D03*
X1410121Y880219D03*
X1408271Y877014D03*
X1404571D03*
X1402721Y880219D03*
X1400871Y877014D03*
X1397171Y889832D03*
X1410121Y893036D03*
X1408271Y889832D03*
X1404571D03*
X1402721Y893036D03*
X1400871Y889832D03*
Y902649D03*
X1397171D03*
X1408271D03*
X1404571Y909057D03*
Y902649D03*
Y915466D03*
X1410121Y925079D03*
Y931488D03*
X1403016Y949498D03*
Y947198D03*
X1406420Y937896D03*
X1404016Y936469D03*
X1410120Y937896D03*
X1403046Y963634D03*
Y965934D03*
Y978035D03*
Y980335D03*
Y992421D03*
Y994721D03*
Y1009174D03*
Y1006874D03*
Y1021962D03*
Y1019662D03*
X1397604Y1063770D03*
Y1082995D03*
Y1095813D03*
X1428620Y848176D03*
X1415669Y844971D03*
X1421220Y848176D03*
X1417520D03*
X1423070Y851380D03*
X1419370D03*
X1415671D03*
X1413822Y860993D03*
X1426771Y864197D03*
X1424921Y854584D03*
X1423071Y864197D03*
X1419371D03*
X1417521Y854584D03*
X1415671Y864197D03*
Y857789D03*
X1424921Y867401D03*
X1417521D03*
X1424921Y880219D03*
X1423071Y877014D03*
X1419371D03*
X1417521Y880219D03*
X1415671Y877014D03*
X1413820Y886627D03*
X1426771Y889832D03*
X1424921Y893036D03*
X1423071Y889832D03*
X1419371D03*
X1417521Y893036D03*
X1415671Y896240D03*
Y889832D03*
X1413821Y899445D03*
Y905853D03*
X1426771Y902649D03*
X1423071Y909057D03*
Y902649D03*
X1419371D03*
X1415670D03*
X1423071Y915466D03*
Y928283D03*
X1417520Y925079D03*
Y931488D03*
X1413820Y918670D03*
X1423071Y921875D03*
X1424920Y937896D03*
X1421220D03*
X1417520D03*
X1413820D03*
X1427203Y1044544D03*
X1425353Y1047749D03*
X1429053Y1060565D03*
X1423503Y1057361D03*
Y1050952D03*
Y1063770D03*
X1425353Y1073383D03*
X1423503Y1076587D03*
Y1070178D03*
X1429053Y1079791D03*
X1425353D03*
X1425354Y1086200D03*
X1423503Y1082995D03*
X1437871Y851380D03*
X1434171D03*
X1430470D03*
X1432321Y841467D03*
X1439721D03*
X1445271Y851380D03*
X1441571D03*
X1439721Y854584D03*
X1432321D03*
X1437871Y864197D03*
X1434171D03*
X1430471D03*
X1445271D03*
X1441571D03*
X1432321Y867401D03*
X1439721D03*
X1437871Y877014D03*
X1434171D03*
X1432321Y880219D03*
X1430471Y877014D03*
X1445271D03*
X1441571D03*
X1439721Y880219D03*
X1437871Y889832D03*
X1434171D03*
X1432321Y893036D03*
X1430471Y889832D03*
X1445271Y896240D03*
X1439721Y893036D03*
X1445271Y889832D03*
X1441571D03*
X1437871Y902649D03*
X1434171D03*
X1432320Y905853D03*
X1430471Y902649D03*
X1441571D03*
Y909057D03*
Y915466D03*
X1430244Y931358D03*
Y933658D03*
X1432320Y918670D03*
X1430575Y1022185D03*
Y1019885D03*
X1443541Y1036914D03*
X1436453Y1041340D03*
X1442003Y1044544D03*
X1432753Y1047749D03*
X1440153D03*
X1432753Y1054157D03*
X1442004Y1057361D03*
X1438304Y1050952D03*
X1434604Y1063770D03*
X1442004D03*
X1432753Y1073383D03*
X1430903Y1076587D03*
X1430904Y1070178D03*
X1443853Y1073383D03*
Y1066974D03*
X1438304Y1070178D03*
X1432754Y1079791D03*
X1443853D03*
X1434603Y1082995D03*
X1432753Y1086200D03*
X1436453Y1092608D03*
X1443854Y1086200D03*
X1440153D03*
X1443854Y1092608D03*
X1442003Y1108630D03*
Y1102221D03*
X1440154Y1099017D03*
X1443853Y1105426D03*
Y1111834D03*
X1454521Y841467D03*
X1447121D03*
X1460071Y851380D03*
X1452671D03*
X1456371D03*
X1448971D03*
X1460071Y864197D03*
X1456371D03*
X1454521Y854584D03*
X1452671Y864197D03*
X1447121Y854584D03*
X1448971Y864197D03*
X1454521Y867401D03*
X1447121D03*
X1460071Y877014D03*
X1456371D03*
X1454521Y880219D03*
X1452671Y877014D03*
X1448971D03*
X1448970Y870606D03*
X1447121Y880219D03*
Y873810D03*
X1456370Y896240D03*
X1456371Y889832D03*
X1454521Y893036D03*
X1447121D03*
X1460071Y889832D03*
X1452671D03*
X1448971D03*
X1458220Y899445D03*
X1460071Y909057D03*
X1458221Y912262D03*
X1450820Y905853D03*
X1460070Y902649D03*
X1452426Y930125D03*
X1460071Y928283D03*
X1458220Y918670D03*
X1456371Y921875D03*
X1460070D03*
X1452670D03*
X1450820Y918670D03*
X1458220Y931488D03*
X1452426Y934725D03*
X1454520Y944304D03*
X1452321Y945354D03*
Y947654D03*
X1460070Y941100D03*
X1458221Y944304D03*
X1458220Y937896D03*
X1456371Y934691D03*
X1460070Y947509D03*
X1452426Y962325D03*
Y960025D03*
Y964625D03*
X1460070Y960326D03*
X1458220Y957122D03*
X1458221Y950713D03*
X1460071Y966735D03*
X1452426Y966925D03*
X1452333Y977669D03*
X1452476Y980736D03*
X1458221Y969939D03*
X1460070Y979552D03*
X1458220Y976347D03*
X1452426Y996825D03*
Y994525D03*
Y989925D03*
Y987625D03*
X1452436Y1010499D03*
X1452426Y1006025D03*
Y1003725D03*
Y1012925D03*
X1460503Y999684D03*
X1458654Y1009297D03*
X1458653Y1002888D03*
X1460504Y1012501D03*
X1452416Y1022635D03*
X1452426Y1017525D03*
X1458653Y1028523D03*
Y1022114D03*
X1460503Y1018910D03*
Y1031727D03*
X1447424Y1036526D03*
X1449649Y1035928D03*
X1458653Y1041340D03*
X1458654Y1034931D03*
X1451253Y1041340D03*
X1460503Y1038136D03*
X1458653Y1047749D03*
X1447553D03*
X1460503Y1057361D03*
X1458653Y1060565D03*
X1456804Y1050952D03*
X1451253Y1060565D03*
X1447553Y1054157D03*
X1460504Y1050952D03*
X1460503Y1076587D03*
X1451253Y1066974D03*
X1449404Y1070178D03*
X1460504D03*
X1458654Y1066974D03*
X1454953Y1073383D03*
X1458653Y1079791D03*
X1454954D03*
X1451253D03*
X1445703Y1089404D03*
X1458654Y1086200D03*
X1456804Y1082995D03*
X1453104Y1089404D03*
X1449404Y1082995D03*
X1460504Y1089404D03*
X1445704Y1095813D03*
X1460504D03*
X1456803D03*
X1445704Y1102221D03*
X1458653Y1105426D03*
X1456804Y1108630D03*
X1454953Y1099017D03*
X1449404Y1108630D03*
X1453104Y1102221D03*
X1451254Y1099017D03*
X1447553D03*
X1458653Y1111834D03*
X1460504Y1108630D03*
X1451253Y1111834D03*
X1447553D03*
X1454953Y1105426D03*
X1445704Y1108630D03*
X1449404Y1102221D03*
X1458653Y1099017D03*
X1454953Y1111834D03*
X1453104Y1108630D03*
X1447553Y1105426D03*
X1451253D03*
X1460504Y1102221D03*
X1458653Y1118243D03*
X1456803Y1115039D03*
X1454953Y1118243D03*
X1453103Y1115039D03*
X1451253Y1118243D03*
X1460503Y1127856D03*
X1453103D03*
X1460504Y1115039D03*
X1449404D03*
X1458653Y1131060D03*
X1454953D03*
X1453103Y1140973D03*
X1451253Y1131060D03*
X1449403Y1134264D03*
X1460503Y1140973D03*
X1469321Y841467D03*
X1461921D03*
X1476721D03*
X1474871Y851380D03*
X1471171D03*
X1467471D03*
X1463771D03*
X1461921Y854584D03*
X1474871Y864197D03*
X1471171D03*
X1469321Y854584D03*
X1467471Y864197D03*
X1463771D03*
X1476721Y854584D03*
X1461921Y867401D03*
X1476721D03*
X1469321D03*
X1461921Y880219D03*
X1471171Y877014D03*
X1476721Y880219D03*
X1474871Y877014D03*
X1469321Y880219D03*
X1467471Y877014D03*
X1463771D03*
X1474871Y889832D03*
X1465621Y893036D03*
X1476721D03*
X1474871Y896240D03*
X1471171Y889832D03*
X1467471D03*
X1463771D03*
X1473021Y899445D03*
X1465620D03*
X1461920Y905853D03*
X1473020Y912262D03*
X1471171Y909057D03*
X1465620Y905853D03*
X1471171Y902649D03*
X1469321Y905853D03*
X1474870Y915466D03*
X1461920Y925079D03*
X1471170Y928283D03*
X1469321Y925079D03*
X1465620D03*
Y918670D03*
X1473021D03*
X1471171Y921875D03*
X1473020Y931488D03*
X1465620D03*
X1461920Y944304D03*
X1474871Y934691D03*
X1473021Y937896D03*
X1471171Y941100D03*
X1469321Y944304D03*
X1465620D03*
Y937896D03*
X1471170Y947509D03*
X1474871Y953917D03*
X1473021Y957122D03*
X1471171Y960326D03*
X1465620Y957122D03*
Y950713D03*
X1473020D03*
X1461920Y963530D03*
X1476721D03*
X1471170Y966735D03*
X1469321Y963530D03*
X1465620D03*
X1473021Y976347D03*
X1473020Y969939D03*
X1465620Y976347D03*
Y969939D03*
X1474870Y973143D03*
X1471171Y979552D03*
X1461920Y982756D03*
X1469321D03*
X1465620D03*
X1475303Y1006093D03*
X1473453Y1009297D03*
X1473454Y1002888D03*
X1471604Y999684D03*
X1466053Y1009297D03*
X1466054Y1002888D03*
X1467903Y1006093D03*
X1464204D03*
X1471603Y1012501D03*
X1462353Y1015705D03*
X1473453Y1028523D03*
X1466053D03*
Y1022114D03*
Y1015705D03*
X1477154D03*
X1475303Y1025318D03*
X1473453Y1022114D03*
X1471604Y1018910D03*
X1469754Y1015705D03*
X1471603Y1031727D03*
X1462353Y1034931D03*
X1473454Y1041340D03*
X1466053D03*
Y1034931D03*
X1475303Y1044544D03*
X1471604Y1038136D03*
X1469754Y1034931D03*
X1466053Y1047749D03*
X1473453D03*
X1462353Y1054157D03*
X1473453Y1060565D03*
X1471604Y1057361D03*
X1466053Y1060565D03*
Y1054157D03*
X1471603Y1050952D03*
X1469753Y1054157D03*
X1475304Y1063770D03*
X1462353Y1073383D03*
X1471604Y1076587D03*
X1469754Y1073383D03*
X1466053Y1066974D03*
X1473453D03*
X1471603Y1070178D03*
X1466053Y1073383D03*
X1473454Y1079791D03*
X1466053D03*
X1462353Y1092608D03*
X1475303Y1082995D03*
X1473453Y1086200D03*
X1469754Y1092608D03*
X1466053D03*
Y1086200D03*
X1471603Y1089404D03*
X1475304Y1095813D03*
X1471604D03*
X1467904D03*
X1462353Y1105426D03*
X1462354Y1099017D03*
X1475303Y1108630D03*
Y1102221D03*
X1473454Y1105426D03*
X1469753D03*
X1467904Y1102221D03*
X1464203D03*
X1473454Y1111834D03*
X1466053D03*
Y1099017D03*
X1471604Y1102221D03*
X1477153Y1099017D03*
X1469753D03*
X1473453D03*
X1466053Y1105426D03*
X1462353Y1111834D03*
X1467904Y1108630D03*
X1464204D03*
X1462353Y1118243D03*
X1477153D03*
X1475303Y1115039D03*
X1473453Y1118243D03*
X1471604Y1121447D03*
X1469754Y1118243D03*
X1466053D03*
X1475303Y1127856D03*
X1467903D03*
X1467904Y1115039D03*
X1471604D03*
X1462353Y1131060D03*
X1477153D03*
X1475303Y1140973D03*
X1473453Y1131060D03*
X1469753D03*
X1466053D03*
X1467903Y1140973D03*
X1491521Y841467D03*
X1484121D03*
X1478571Y851380D03*
X1482271D03*
X1489671D03*
X1485971D03*
X1493371D03*
X1478571Y864197D03*
X1491521Y854584D03*
X1489671Y864197D03*
X1485971D03*
X1482271D03*
X1493371D03*
X1491521Y867401D03*
X1484121D03*
Y854584D03*
X1478571Y877014D03*
X1491521Y880219D03*
X1485971Y877014D03*
X1484121Y880219D03*
X1489671Y877014D03*
X1482271D03*
X1493371D03*
X1478570Y896240D03*
X1478571Y889832D03*
X1491521Y893036D03*
X1482271Y889832D03*
X1489671D03*
X1485971D03*
X1482270Y896240D03*
X1480421Y893036D03*
X1493371Y889832D03*
X1491520Y899445D03*
X1484120D03*
X1478571Y909057D03*
Y902649D03*
X1491520Y912262D03*
X1487820Y905853D03*
X1485971Y909057D03*
X1484121Y912262D03*
X1491520Y905853D03*
X1485970Y902649D03*
X1478571Y915466D03*
X1482271D03*
X1478571Y928283D03*
Y921875D03*
X1491520Y925079D03*
Y918670D03*
X1487820Y925079D03*
X1485971Y928283D03*
X1485970Y921875D03*
X1484120Y918670D03*
X1491520Y931488D03*
X1484121D03*
X1478571Y941100D03*
Y934691D03*
X1491520Y944304D03*
Y937896D03*
X1487820Y944304D03*
X1485970Y941100D03*
X1482271Y934691D03*
X1478571Y947509D03*
Y960326D03*
Y953917D03*
X1491520Y957122D03*
Y950713D03*
X1485970Y960326D03*
X1484120Y957122D03*
X1482271Y953917D03*
X1484121Y950713D03*
X1478570Y966735D03*
X1491520Y963530D03*
X1485971Y966735D03*
X1487820Y963530D03*
X1480420D03*
X1478571Y979552D03*
Y973143D03*
X1491521Y976347D03*
X1491520Y969939D03*
X1484120Y976347D03*
X1484121Y969939D03*
X1489671Y973143D03*
X1485970Y979552D03*
X1482271Y973143D03*
X1493370D03*
X1491520Y982756D03*
X1487820D03*
X1479004Y999684D03*
X1486403D03*
X1484553Y1002888D03*
X1482704Y1006093D03*
X1479003Y1012501D03*
X1486404D03*
X1491953Y1009297D03*
Y1002888D03*
X1484554Y1009297D03*
X1479004Y1025318D03*
Y1018910D03*
X1491953Y1028523D03*
Y1022114D03*
X1484553Y1028523D03*
X1486403Y1018910D03*
X1484553Y1022114D03*
X1482704Y1025318D03*
X1480853Y1015705D03*
X1479004Y1031727D03*
X1486404D03*
X1488253Y1015705D03*
X1491953D03*
X1479004Y1044544D03*
Y1038136D03*
X1491953Y1034931D03*
Y1041340D03*
X1488253Y1034931D03*
X1486403Y1038136D03*
X1484553Y1041340D03*
X1482704Y1044544D03*
X1491953Y1047749D03*
X1484553D03*
X1479004Y1057361D03*
Y1050952D03*
X1491953Y1054157D03*
X1486404Y1057361D03*
X1484553Y1060565D03*
X1488253Y1054157D03*
X1486404Y1050952D03*
X1491953Y1060565D03*
X1479004Y1063770D03*
X1482704D03*
X1479004Y1076587D03*
Y1070178D03*
X1486404Y1076587D03*
Y1070178D03*
X1488253Y1073383D03*
X1484553Y1066974D03*
X1491953Y1073383D03*
Y1066974D03*
X1484553Y1079791D03*
X1491953D03*
X1479004Y1089404D03*
Y1082995D03*
X1488254Y1092608D03*
X1486404Y1089404D03*
X1484554Y1086200D03*
X1482704Y1082995D03*
X1491954Y1092608D03*
X1479004Y1095813D03*
X1490103D03*
X1493804D03*
X1479004Y1102221D03*
X1490104Y1108630D03*
Y1102221D03*
X1488254Y1099017D03*
X1484553D03*
X1482704Y1108630D03*
X1480853Y1099017D03*
X1491953Y1105426D03*
Y1111834D03*
X1493804Y1108630D03*
X1490103Y1115039D03*
X1488253Y1118243D03*
X1484553D03*
X1480853D03*
X1486403Y1115039D03*
X1491953Y1118243D03*
X1490103Y1127856D03*
X1482703D03*
X1493804Y1115039D03*
X1490103Y1140973D03*
X1488253Y1131060D03*
X1484553D03*
X1480853D03*
X1482703Y1140973D03*
X1491953Y1131060D03*
X1504471Y844671D03*
X1498921Y841467D03*
X1508171Y851380D03*
X1504471D03*
X1500771D03*
X1497071D03*
X1504471Y864197D03*
X1500771D03*
X1508170Y857789D03*
X1497071Y864197D03*
X1506321Y860993D03*
Y854584D03*
X1498921D03*
X1510021Y860993D03*
X1506320Y867401D03*
X1498921D03*
X1510021D03*
X1504471Y877014D03*
X1498921Y880219D03*
X1508171Y877014D03*
X1497071D03*
X1506321Y880219D03*
X1500771Y877014D03*
X1510021Y880219D03*
Y873810D03*
X1508170Y883423D03*
X1508171Y889832D03*
X1504471Y896240D03*
Y889832D03*
X1500771D03*
X1508171Y896240D03*
X1502621Y893036D03*
X1500771Y896240D03*
X1497071Y889832D03*
X1510021Y893036D03*
X1498921Y899445D03*
X1510021D03*
X1495221Y905853D03*
X1504471Y902649D03*
X1498920Y912262D03*
X1497070Y909057D03*
X1497071Y902649D03*
X1508171Y915466D03*
X1504471D03*
X1500770D03*
X1504471Y909057D03*
X1510021Y912262D03*
X1495221Y925079D03*
X1504471Y921875D03*
X1497070Y928283D03*
X1498921Y918670D03*
X1497071Y921875D03*
X1498920Y931488D03*
X1504471Y928283D03*
X1510021Y918670D03*
X1510020Y931488D03*
X1495221Y944304D03*
X1504471Y941100D03*
Y934691D03*
X1500770D03*
X1498921Y937896D03*
X1497071Y941100D03*
X1497070Y947509D03*
X1508171Y934691D03*
X1510021Y937896D03*
X1504471Y947509D03*
Y960326D03*
Y953917D03*
X1500771D03*
X1498921Y957122D03*
X1497071Y960326D03*
X1498920Y950713D03*
X1495221Y963530D03*
X1497070Y966735D03*
X1502621Y963530D03*
X1510021Y957122D03*
X1508171Y953917D03*
X1510021Y950713D03*
X1506320Y963530D03*
X1504471Y966735D03*
Y979552D03*
Y973143D03*
X1498921Y976347D03*
X1498920Y969939D03*
X1500770Y973143D03*
X1497071Y979552D03*
X1510021Y976347D03*
X1495221Y982756D03*
X1510043Y980606D03*
X1510021Y969939D03*
X1508171Y973143D03*
X1497503Y1012501D03*
Y999684D03*
X1504904Y1006093D03*
Y999684D03*
X1501203Y1006093D03*
X1499353Y1009297D03*
X1499354Y1002888D03*
X1510453Y1009297D03*
Y1002888D03*
X1508603Y1006093D03*
X1504903Y1012501D03*
X1504904Y1025318D03*
X1499353Y1028523D03*
X1501203Y1025318D03*
X1504904Y1031727D03*
X1497503D03*
X1495654Y1015705D03*
X1497504Y1018910D03*
X1499353Y1022114D03*
X1503054Y1015705D03*
X1504904Y1018910D03*
X1506753Y1015705D03*
X1510453Y1028523D03*
X1510452Y1022114D03*
X1508603Y1025318D03*
X1504904Y1044544D03*
X1501203D03*
X1499354Y1041340D03*
X1497504Y1038136D03*
X1495654Y1034931D03*
X1508604Y1044544D03*
X1499353Y1047749D03*
X1504904Y1038136D03*
X1510453Y1041340D03*
Y1047749D03*
X1504904Y1057361D03*
Y1050952D03*
X1499354Y1060565D03*
X1497504Y1057361D03*
X1497503Y1050952D03*
X1495654Y1054157D03*
X1504904Y1063770D03*
X1501203D03*
X1510453Y1060565D03*
X1508604Y1063770D03*
X1504904Y1076587D03*
Y1070178D03*
X1497504Y1076587D03*
X1497503Y1070178D03*
X1495654Y1073383D03*
X1499353Y1066974D03*
X1499354Y1079791D03*
X1510453Y1066974D03*
Y1079791D03*
X1499353Y1086200D03*
X1497503Y1089404D03*
X1495653Y1092608D03*
X1504904Y1089404D03*
Y1082995D03*
X1501203D03*
X1508604Y1082996D03*
X1510453Y1086200D03*
X1504903Y1095813D03*
X1503053Y1105426D03*
X1497503Y1102221D03*
X1495653Y1105426D03*
X1495654Y1099017D03*
X1508603Y1108630D03*
X1506754Y1111834D03*
X1499353D03*
X1503053Y1099017D03*
X1510453D03*
X1508602Y1102221D03*
X1497504Y1108630D03*
X1501204D03*
X1510453Y1111834D03*
X1499353Y1105426D03*
X1510453D03*
X1504904Y1108630D03*
X1495653Y1111834D03*
X1503053D03*
X1506753Y1124651D03*
Y1118243D03*
X1504904Y1121447D03*
X1499353Y1118243D03*
X1497503Y1115039D03*
X1495653Y1118243D03*
X1508603Y1115039D03*
X1504904Y1127856D03*
X1497503D03*
X1501204Y1115039D03*
X1504904D03*
X1506754Y1137469D03*
X1506753Y1131060D03*
X1503053D03*
X1499353D03*
X1495653D03*
X1504904Y1134264D03*
X1497503Y1140973D03*
X1510453Y1131060D03*
X1511871Y844671D03*
X1513722Y848176D03*
X1511871Y851380D03*
X1521121Y860993D03*
Y854584D03*
X1515570Y864197D03*
X1513721Y854584D03*
Y860993D03*
X1521121Y867401D03*
X1517421D03*
X1513721D03*
X1511871Y870606D03*
X1522971D03*
X1517421Y873810D03*
X1511871Y883423D03*
X1517421Y880219D03*
X1522971Y883423D03*
X1511871Y889832D03*
X1513721Y893036D03*
X1517421Y886627D03*
X1521121D03*
X1513721D03*
X1526671Y889832D03*
X1513721Y899445D03*
X1524821Y912262D03*
X1511871Y909057D03*
Y902649D03*
X1513721Y912262D03*
X1515571Y909057D03*
X1524821Y905853D03*
X1513721D03*
X1519271Y909057D03*
X1511871Y921875D03*
X1513721Y918670D03*
X1524820Y931488D03*
X1513720D03*
X1511871Y941100D03*
X1513721Y937896D03*
X1511871Y947509D03*
X1519271D03*
X1515571D03*
X1511871Y960326D03*
X1513721Y957122D03*
Y950713D03*
X1511871Y966735D03*
X1513721Y963530D03*
X1515571Y979552D03*
X1513721Y982756D03*
X1511871Y973143D03*
X1517421Y969939D03*
X1515571Y973143D03*
X1516004Y1006092D03*
X1516003Y999684D03*
X1512303D03*
Y1006093D03*
X1519705Y1006092D03*
X1525396Y1000648D03*
X1512303Y1012501D03*
Y1025318D03*
X1516003Y1018910D03*
X1517854Y1015705D03*
X1525254D03*
X1521554D03*
X1514154D03*
X1512303Y1018910D03*
Y1031727D03*
X1525254Y1034931D03*
X1521554D03*
X1516004Y1044544D03*
X1516003Y1038136D03*
X1517853Y1034931D03*
X1514153D03*
X1512303Y1038136D03*
X1517853Y1054157D03*
X1514153D03*
X1512303Y1057361D03*
X1521553Y1054157D03*
X1514153Y1060565D03*
X1512303Y1050952D03*
X1525564Y1064850D03*
X1523404Y1070178D03*
X1514153Y1066974D03*
X1517853Y1073383D03*
X1521553Y1066974D03*
X1516003Y1076587D03*
X1512303D03*
X1512304Y1070178D03*
X1514153Y1073383D03*
X1523404Y1082996D03*
X1512304D03*
X1514153Y1092608D03*
X1512303Y1089404D03*
X1521553Y1092608D03*
X1523403Y1095813D03*
X1519703D03*
X1512303D03*
X1521554Y1105426D03*
X1517853D03*
X1516003Y1108630D03*
Y1102221D03*
X1512303D03*
X1517853Y1111834D03*
X1521553D03*
X1514153Y1105426D03*
X1512303Y1108630D03*
X1514153Y1111834D03*
X1519703Y1108630D03*
X1521553Y1124651D03*
Y1118243D03*
X1519704Y1115039D03*
X1516004D03*
X1514153Y1124651D03*
X1512303Y1115039D03*
X1517854Y1131560D03*
X1512304Y1134264D03*
X1527571Y979057D03*
X1526843Y972608D03*
X1527103Y1031726D03*
X1665141Y1051247D03*
X1724541D03*
G54D43*
X333834Y1062790D03*
X329632Y1092168D03*
X335344Y1097289D03*
X549719Y962436D03*
X548146Y965640D03*
X543729Y984866D03*
X1309976Y1062790D03*
X1305774Y1092168D03*
X1311486Y1097289D03*
X1337102Y206675D03*
X1525861Y962436D03*
X1524288Y965640D03*
X1519871Y984866D03*
X1879155Y468898D03*
Y716798D03*
X1889155Y468898D03*
Y716798D03*
X1900275Y840758D03*
X1910275D03*
X1921395Y-19332D03*
X1931395D03*
X1942395Y593048D03*
X1952395D03*
X1963362Y-19190D03*
X1973362D03*
X1984482Y593020D03*
X1994482D03*
X2005452Y-19180D03*
X2015452D03*
X2026452Y593200D03*
X2047419Y-19038D03*
X2036452Y593200D03*
X2057419Y-19038D03*
X2068539Y593172D03*
X2078539D03*
G54D52*
X717313Y-27626D03*
Y-21471D03*
Y-17597D03*
X717298Y-15082D03*
X717313Y-11442D03*
X717298Y-25111D03*
X717313Y-7568D03*
X717298Y-5053D03*
X834273Y2374D03*
X834258Y4889D03*
X834273Y22432D03*
Y8529D03*
Y12403D03*
X834258Y14918D03*
X834273Y18558D03*
X834258Y24947D03*
X1026705Y-27695D03*
Y-38224D03*
X1023437Y-38210D03*
X1026690Y-35709D03*
X1023422Y-35695D03*
X1026705Y-32069D03*
Y-17666D03*
X1026690Y-15151D03*
X1026705Y-11511D03*
X1026690Y-25180D03*
X1026705Y-21540D03*
X1026690Y4907D03*
X1026705Y2392D03*
X1026690Y-5122D03*
X1026705Y-7637D03*
Y-1482D03*
Y22450D03*
Y18576D03*
Y8547D03*
X1026690Y14936D03*
X1026705Y12421D03*
X1026690Y24965D03*
X1336024Y-27695D03*
Y-32069D03*
X1332741Y-35695D03*
X1336009Y-35709D03*
X1332756Y-38210D03*
X1336024Y-38224D03*
Y-11511D03*
X1336009Y-15151D03*
X1336024Y-17666D03*
Y-21540D03*
X1336009Y-25180D03*
X1336024Y2392D03*
X1336009Y4907D03*
X1336024Y-1482D03*
Y-7637D03*
X1336009Y-5122D03*
X1336024Y18576D03*
Y22450D03*
Y12421D03*
X1336009Y14936D03*
X1336024Y8547D03*
X1336009Y24965D03*
G54D62*
X918780Y1684890D03*
Y1694890D03*
Y1714890D03*
X928780Y1684890D03*
X938780D03*
X928780Y1694890D03*
X938780D03*
X928780Y1704890D03*
X938780D03*
X928780Y1714890D03*
X938780D03*
G54D72*
X1879155Y354948D03*
Y458898D03*
Y478898D03*
Y582848D03*
Y602848D03*
Y706798D03*
Y726798D03*
Y830748D03*
X1900275Y-9342D03*
X1889155Y354948D03*
Y458898D03*
Y478898D03*
X1900275Y582858D03*
X1889155Y582848D03*
Y602848D03*
Y706798D03*
X1900275Y726808D03*
X1889155Y726798D03*
X1900275Y830758D03*
X1889155Y830748D03*
X1900275Y850758D03*
Y954708D03*
X1910275Y-9342D03*
Y582858D03*
Y726808D03*
Y830758D03*
Y850758D03*
Y954708D03*
X1921395Y-9332D03*
X1931395D03*
Y582868D03*
X1921395D03*
X1931395Y602868D03*
X1921395D03*
Y1195068D03*
X1931395D03*
X1942395Y-9152D03*
Y583048D03*
Y603048D03*
Y1195248D03*
X1963362Y-9190D03*
X1952395Y-9152D03*
X1963362Y583010D03*
X1952395Y583048D03*
X1963362Y603010D03*
X1952395Y603048D03*
X1963362Y1195210D03*
X1952395Y1195248D03*
X1973362Y-9190D03*
Y583010D03*
Y603010D03*
Y1195210D03*
X1994482Y-9180D03*
X1984482D03*
Y583020D03*
X1994482D03*
X1984482Y603020D03*
X1994482D03*
Y1195220D03*
X1984482D03*
X2005452Y-9180D03*
X2015452D03*
Y583020D03*
X2005452D03*
X2015452Y603020D03*
X2005452D03*
Y1195220D03*
X2015452D03*
X2026452Y-9000D03*
Y583200D03*
Y603200D03*
Y1195400D03*
X2047419Y-9038D03*
X2036452Y-9000D03*
X2047419Y583162D03*
X2036452Y583200D03*
X2047419Y603162D03*
X2036452Y603200D03*
X2047419Y1195362D03*
X2036452Y1195400D03*
X2057419Y-9038D03*
Y583162D03*
Y603162D03*
Y1195362D03*
X2068539Y603172D03*
X2078539D03*
Y1195372D03*
X2068539D03*
G54D73*
X1879155Y468898D03*
Y716798D03*
X1889155Y468898D03*
X1900275Y592858D03*
X1889155Y716798D03*
X1900275Y840758D03*
X1910275Y592858D03*
Y840758D03*
X1921395Y1205068D03*
X1931395D03*
X1942395Y593048D03*
X1952395D03*
X1963362Y1205210D03*
X1984482Y593020D03*
X1973362Y1205210D03*
X1994482Y593020D03*
X2005452Y1205220D03*
X2015452D03*
X2026452Y593200D03*
X2036452D03*
X2047419Y1205362D03*
X2057419D03*
G54D49*
X676508Y224606D03*
G54D27*
X95799Y967585D03*
Y1054593D03*
X125499Y816995D03*
Y810302D03*
Y833727D03*
Y823688D03*
Y827034D03*
Y840420D03*
Y927428D03*
Y920735D03*
Y934121D03*
Y944160D03*
Y937467D03*
Y950853D03*
X111941Y964239D03*
X125499Y980971D03*
Y974278D03*
Y967585D03*
Y994357D03*
Y987664D03*
X111941Y1021129D03*
Y1024475D03*
X125499Y1027822D03*
Y1021129D03*
Y1047900D03*
Y1041207D03*
Y1034515D03*
X111941Y1051247D03*
X125499Y1054593D03*
Y1141601D03*
Y1148294D03*
Y1154987D03*
Y1158333D03*
Y1171719D03*
Y1165026D03*
Y1221916D03*
Y1215223D03*
Y1238648D03*
Y1228609D03*
Y1231955D03*
Y1245341D03*
X141641Y813648D03*
Y806955D03*
Y820341D03*
Y830381D03*
Y823688D03*
Y837074D03*
Y917389D03*
Y924081D03*
Y934121D03*
Y930774D03*
Y947507D03*
Y940814D03*
Y964239D03*
Y977625D03*
Y970932D03*
Y991011D03*
Y984318D03*
Y1021129D03*
Y1024475D03*
Y1031168D03*
Y1044554D03*
Y1037861D03*
Y1051247D03*
Y1144948D03*
Y1138255D03*
Y1161680D03*
Y1154987D03*
Y1151641D03*
Y1168373D03*
Y1218570D03*
Y1211877D03*
Y1225263D03*
Y1241995D03*
Y1235302D03*
Y1228609D03*
X155199Y967585D03*
Y1054593D03*
X171341Y964239D03*
Y1021129D03*
Y1024475D03*
Y1051247D03*
X184899Y780184D03*
Y773491D03*
Y786877D03*
Y803609D03*
Y796916D03*
Y790223D03*
Y816995D03*
Y810302D03*
Y833727D03*
Y823688D03*
Y827034D03*
Y847113D03*
Y840420D03*
Y853806D03*
Y860499D03*
Y863845D03*
Y883924D03*
Y877231D03*
Y870538D03*
Y890617D03*
Y897310D03*
Y900656D03*
Y914042D03*
Y907349D03*
Y927428D03*
Y920735D03*
Y934121D03*
Y944160D03*
Y937467D03*
Y950853D03*
Y980971D03*
Y974278D03*
Y967585D03*
Y994357D03*
Y987664D03*
Y1027822D03*
Y1021129D03*
Y1047900D03*
Y1041207D03*
Y1034515D03*
Y1054593D03*
Y1074672D03*
Y1067979D03*
Y1091404D03*
Y1081365D03*
Y1084711D03*
Y1098097D03*
Y1111483D03*
Y1104790D03*
Y1128215D03*
Y1118176D03*
Y1121522D03*
Y1141601D03*
Y1134908D03*
Y1148294D03*
Y1154987D03*
Y1158333D03*
Y1171719D03*
Y1165026D03*
Y1185105D03*
Y1178412D03*
Y1191798D03*
Y1208530D03*
Y1201837D03*
Y1195144D03*
Y1221916D03*
Y1215223D03*
Y1238648D03*
Y1228609D03*
Y1231955D03*
Y1245341D03*
X201041Y770144D03*
Y776837D03*
Y786877D03*
Y783530D03*
Y800263D03*
Y793570D03*
Y813648D03*
Y806955D03*
Y820341D03*
Y830381D03*
Y823688D03*
Y850459D03*
Y843766D03*
Y837074D03*
Y867192D03*
Y860499D03*
Y857152D03*
Y873885D03*
Y880577D03*
Y887270D03*
Y897310D03*
Y893963D03*
Y917389D03*
Y910696D03*
Y904003D03*
Y924081D03*
Y934121D03*
Y930774D03*
Y947507D03*
Y940814D03*
Y964239D03*
Y977625D03*
Y970932D03*
Y991011D03*
Y984318D03*
X201141Y1021129D03*
Y1024475D03*
Y1031168D03*
Y1044554D03*
Y1037861D03*
Y1051247D03*
Y1071326D03*
Y1064633D03*
Y1078018D03*
Y1094752D03*
Y1088059D03*
Y1081366D03*
Y1108137D03*
Y1101444D03*
X201041Y1124869D03*
X201141Y1118177D03*
Y1114830D03*
Y1144948D03*
Y1138255D03*
X201041Y1131562D03*
X201141Y1161680D03*
Y1154988D03*
Y1151641D03*
Y1175066D03*
Y1168373D03*
Y1181759D03*
Y1191799D03*
Y1188452D03*
Y1205184D03*
Y1198491D03*
Y1218570D03*
Y1211877D03*
Y1225263D03*
Y1241995D03*
Y1235302D03*
Y1228609D03*
X244299Y883924D03*
Y890617D03*
Y897310D03*
Y900656D03*
Y914042D03*
Y907349D03*
Y1185105D03*
Y1178412D03*
Y1191798D03*
Y1208530D03*
Y1201837D03*
Y1195144D03*
X260441Y880577D03*
Y887270D03*
Y897310D03*
Y893963D03*
Y910696D03*
Y904003D03*
Y1175066D03*
Y1181759D03*
Y1191798D03*
Y1188452D03*
Y1205184D03*
Y1198491D03*
X337779Y880219D03*
X335928Y883423D03*
X337779Y893036D03*
X335928Y889832D03*
X334079Y886627D03*
X337779D03*
X350729Y857789D03*
X352578Y860993D03*
X354429Y857789D03*
X341479Y880219D03*
X343329Y883423D03*
X348878Y899445D03*
Y893036D03*
X350729Y889832D03*
X354429D03*
X341478Y893036D03*
X343328Y889832D03*
X347029Y896240D03*
X354429D03*
X341479Y886627D03*
X350729Y896240D03*
X345179Y886627D03*
X348878Y912262D03*
X350729Y909057D03*
X354429D03*
X350729Y902649D03*
X354429D03*
X347029Y915466D03*
X354429D03*
X350729D03*
X348879Y931488D03*
X350729Y928283D03*
X354429D03*
Y921875D03*
X350729D03*
X348878Y918670D03*
X350729Y941100D03*
X348878Y937896D03*
X354429Y941100D03*
X347029Y934691D03*
X354429D03*
X350729D03*
Y947509D03*
X354429D03*
X348878Y950713D03*
X350729Y960326D03*
X348878Y957122D03*
X354429Y960326D03*
X350729Y966735D03*
X354429D03*
X350729Y953917D03*
X354429D03*
X347030D03*
X350729Y979552D03*
X354429D03*
X348878Y976347D03*
X347029Y973143D03*
X348878Y969939D03*
X347461Y1006093D03*
X349311Y1002888D03*
X351161Y999684D03*
X354861D03*
X351161Y1012501D03*
X349311Y1009297D03*
X354861Y1012501D03*
X351162Y1031727D03*
X349311Y1028523D03*
X354861Y1031727D03*
X349311Y1022114D03*
X351161Y1018910D03*
X354861D03*
X347461Y1025318D03*
X354862D03*
X351162D03*
X349311Y1047749D03*
Y1041340D03*
X351161Y1038136D03*
X354861D03*
X347461Y1044544D03*
X354861D03*
X351161D03*
X349311Y1060565D03*
X351161Y1057361D03*
X354861D03*
X347461Y1063770D03*
X351161D03*
X354861D03*
X351161Y1050952D03*
X354861D03*
Y1070178D03*
X351162D03*
X349311Y1066974D03*
Y1079791D03*
X351161Y1076587D03*
X354861D03*
X351161Y1089404D03*
X349311Y1086200D03*
X354861Y1089404D03*
X347461Y1082995D03*
X354861D03*
X351161D03*
X353011Y1124651D03*
X354861Y1127856D03*
X349312Y1137469D03*
X351161Y1134264D03*
X356278Y854584D03*
X358129Y857789D03*
X363678Y854584D03*
X365529Y857789D03*
X371078Y854584D03*
X359978Y860993D03*
X361829Y857789D03*
X367378Y860993D03*
X369229Y857789D03*
X356278Y899445D03*
Y893036D03*
X358129Y896240D03*
X363678Y899445D03*
X367378D03*
X356278Y912262D03*
X358129Y915466D03*
X363678Y912262D03*
X361829Y909057D03*
X367378Y912262D03*
X369229Y909057D03*
X361829Y902649D03*
X369229D03*
X359978Y905853D03*
X367378D03*
X363678D03*
X371078D03*
X356278Y931488D03*
X363678D03*
X356278Y918670D03*
X361829Y928283D03*
X367378Y931488D03*
X369229Y928283D03*
X361829Y921875D03*
X363678Y918670D03*
X369229Y921875D03*
X367378Y918670D03*
X359978Y925079D03*
X367378D03*
X363678D03*
X371078D03*
X356278Y937896D03*
X358129Y934691D03*
X361829Y941100D03*
X363678Y937896D03*
X369229Y941100D03*
X367378Y937896D03*
X361829Y947509D03*
X369229D03*
X367378Y944304D03*
X359978D03*
X371078D03*
X363678D03*
X356278Y950713D03*
Y957122D03*
X358129Y953917D03*
X361829Y966735D03*
X369229D03*
X359978Y963530D03*
X363678Y950713D03*
X367378D03*
X361829Y960326D03*
X363678Y957122D03*
X369229Y960326D03*
X367378Y957122D03*
X371078Y963530D03*
X359978Y982756D03*
X367378D03*
X363678D03*
X371078D03*
X369229Y979552D03*
X367378Y976347D03*
X361829Y979552D03*
X363678Y976347D03*
X356278D03*
Y969939D03*
X358129Y973143D03*
X363678Y969939D03*
X367378D03*
X358562Y1006093D03*
X356711Y1002888D03*
Y1009297D03*
X362262Y1012501D03*
X369662D03*
X364111Y1009297D03*
X367811D03*
X364111Y1002888D03*
X362262Y999684D03*
X371511Y1002888D03*
X369662Y999684D03*
X356711Y1028523D03*
Y1022114D03*
X362262Y1031727D03*
X364111Y1028523D03*
X369662Y1031727D03*
X367811Y1028523D03*
X358562Y1025318D03*
X360411Y1015705D03*
X371511D03*
X364111Y1022114D03*
X362262Y1018910D03*
X367811Y1022114D03*
X369662Y1018910D03*
X356711Y1047749D03*
Y1041340D03*
X364111D03*
X362262Y1038136D03*
X367811Y1041340D03*
X369662Y1038136D03*
X360411Y1034931D03*
X371511D03*
X364111D03*
X358562Y1044544D03*
X367811Y1034931D03*
X364111Y1047749D03*
X367811D03*
X356711Y1060565D03*
X358562Y1063770D03*
X364111Y1060565D03*
X362262Y1057361D03*
X367811Y1060565D03*
X369662Y1057361D03*
X362262Y1050952D03*
X369662D03*
X360411Y1054157D03*
X371511D03*
X364111D03*
X367811D03*
X356711Y1066974D03*
X367811Y1079791D03*
X369662Y1076587D03*
X362262Y1070178D03*
X364111Y1066974D03*
X369662Y1070178D03*
X367811Y1066974D03*
X356711Y1079791D03*
X364111D03*
X362262Y1076587D03*
X360411Y1073383D03*
X371511D03*
X364111D03*
X367811D03*
X356711Y1086200D03*
X358562Y1082995D03*
X362262Y1095813D03*
X369662D03*
X362262Y1089404D03*
X364111Y1086200D03*
X369662Y1089404D03*
X367811Y1086200D03*
X360411Y1092608D03*
X367811D03*
X364111D03*
X371511D03*
X364111Y1099017D03*
X367811D03*
X358561Y1121447D03*
X360412Y1124651D03*
X364111D03*
X367811D03*
X371511D03*
X356712D03*
X362262Y1127856D03*
X365962Y1121447D03*
X369662Y1127856D03*
X358561Y1134264D03*
X362261Y1140973D03*
X365962Y1134264D03*
X369661Y1140973D03*
X356712Y1137469D03*
X360412D03*
X364112D03*
X367812D03*
X371512D03*
X387729Y857789D03*
X372929D03*
X378478Y854584D03*
X380329Y857789D03*
X384029D03*
X374778Y860993D03*
X376629Y857789D03*
X382178Y860993D03*
X385878Y854584D03*
X373362Y1006093D03*
X380762D03*
X377062D03*
X384462D03*
X375211Y1124651D03*
X378911D03*
X382611D03*
X386311D03*
X373362Y1121447D03*
X377062Y1127856D03*
X380762Y1121447D03*
X384462Y1127856D03*
X373362Y1134264D03*
X377061Y1140973D03*
X380762Y1134264D03*
X384461Y1140973D03*
X375212Y1137469D03*
X378912D03*
X382612D03*
X386312D03*
X393278Y854584D03*
X395129Y857789D03*
X400678Y854584D03*
X402529Y857789D03*
X389578Y860993D03*
X391429Y857789D03*
X396978Y860993D03*
X398829Y857789D03*
X390011Y1124651D03*
X395562Y1121447D03*
X397411Y1124651D03*
X401111D03*
X391862Y1127856D03*
X393711Y1124651D03*
X399262Y1127856D03*
X402962Y1121447D03*
X388162D03*
X391861Y1140973D03*
X395562Y1134264D03*
X399261Y1140973D03*
X402962Y1134264D03*
X388162D03*
X390012Y1137469D03*
X393712D03*
X397412D03*
X401112D03*
X408078Y854584D03*
X409929Y857789D03*
X415478Y854584D03*
X417329Y857789D03*
X404378Y860993D03*
X406229Y857789D03*
X411778Y860993D03*
X413629Y857789D03*
X419178Y860993D03*
X417329Y883423D03*
X415478Y880219D03*
X413629Y883423D03*
X419178Y886627D03*
X404811Y1124651D03*
X408511D03*
X406662Y1127856D03*
X410362Y1121447D03*
X406661Y1140973D03*
X410362Y1134264D03*
X404812Y1137469D03*
X408512D03*
X422878Y854584D03*
X424729Y857789D03*
X430278Y854584D03*
X433979Y860993D03*
X421029Y857789D03*
X426578Y860993D03*
X428429Y857789D03*
X432129D03*
X435829D03*
X432129Y883423D03*
X430278Y880219D03*
X424729Y883423D03*
X422878Y880219D03*
X428429Y883423D03*
X421029D03*
X435829D03*
X433978Y886627D03*
X426578D03*
X437679Y854584D03*
X452478D03*
X450629Y857789D03*
X445078Y854584D03*
X443229Y857789D03*
X448779Y860993D03*
X446929Y857789D03*
X441378Y860993D03*
X452479Y880219D03*
X446929Y883423D03*
X445078Y880219D03*
X439529Y883423D03*
X437678Y880219D03*
X450629Y883423D03*
X443229D03*
X448778Y886627D03*
X441378D03*
X467278Y854584D03*
X465429Y857789D03*
X459878Y854584D03*
X458029Y857789D03*
X469129D03*
X463578Y860993D03*
X461729Y857789D03*
X456178Y860993D03*
X454329Y857789D03*
X469129Y883423D03*
X467278Y880219D03*
X461729Y883423D03*
X459878Y880219D03*
X454329Y883423D03*
X465429D03*
X458029D03*
X463578Y886627D03*
X456178D03*
X482078Y854584D03*
X480229Y857789D03*
X474678Y854584D03*
X472829Y857789D03*
X483929D03*
X478378Y860993D03*
X476529Y857789D03*
X470978Y860993D03*
Y886627D03*
X484362Y1121447D03*
X480662Y1127856D03*
X476962Y1121447D03*
X473262Y1127856D03*
X469562Y1121447D03*
X482511Y1124651D03*
X478811D03*
X475111D03*
X471411D03*
X484362Y1134264D03*
X482512Y1137469D03*
X476962Y1134264D03*
X475112Y1137469D03*
X480661Y1140973D03*
X478812Y1137469D03*
X473261Y1140973D03*
X489478Y854584D03*
X487629Y857789D03*
X500578Y860993D03*
X498729Y857789D03*
X495029D03*
X491329D03*
X485778Y860993D03*
X496878Y854584D03*
X493178Y860993D03*
X500578Y982756D03*
X496878D03*
X498729Y979552D03*
X500578Y976347D03*
X499162Y1012501D03*
X501011Y1009297D03*
X497311Y1015705D03*
X501011Y1022114D03*
X499162Y1018910D03*
X488062Y1127856D03*
X499162Y1121447D03*
X495462Y1127856D03*
X491762Y1121447D03*
X489911Y1124651D03*
X486211D03*
X501011D03*
X497311D03*
X493611D03*
X493612Y1137469D03*
X488061Y1140973D03*
X501012Y1137469D03*
X495461Y1140973D03*
X491762Y1134264D03*
X489912Y1137469D03*
X486212D03*
X499162Y1134264D03*
X497312Y1137469D03*
X517229Y857789D03*
X513529D03*
X509829D03*
X506129D03*
X515378Y860993D03*
X511678Y854584D03*
X507978Y860993D03*
X504278Y854584D03*
X502429Y857789D03*
X511678Y899445D03*
Y893036D03*
X507978D03*
X509829Y896240D03*
X517229D03*
X513529D03*
Y902649D03*
X517229D03*
X511678Y912262D03*
X513529Y909057D03*
X517229D03*
X513529Y915466D03*
X509829D03*
X517229D03*
X511678Y931488D03*
X513529Y928283D03*
X517229D03*
X513529Y921875D03*
X511678Y918670D03*
X517229Y921875D03*
X513529Y941100D03*
X511678Y937896D03*
X517229Y941100D03*
X513529Y934691D03*
X509829D03*
X517229D03*
X513529Y947509D03*
X517229D03*
X511678Y950713D03*
X513529Y960326D03*
X511678Y957122D03*
X517229Y960326D03*
Y966735D03*
X513529D03*
Y953917D03*
X517229D03*
X509829D03*
X507978Y982756D03*
X504278D03*
Y976347D03*
X506129Y979552D03*
X513529D03*
X517229D03*
X511678Y976347D03*
X509829Y973143D03*
X511678Y969939D03*
X517662Y1006093D03*
X513962D03*
X510262D03*
X517662Y1012501D03*
X513962D03*
X512111Y1009297D03*
X506562Y1012501D03*
X504711Y1009297D03*
X513962Y1031727D03*
X512111Y1028523D03*
X517662Y1031727D03*
X512111Y1022114D03*
X513962Y1018910D03*
X517662D03*
X513962Y1025318D03*
X510262D03*
X517662D03*
X508411Y1015705D03*
X504711Y1022114D03*
X506562Y1018910D03*
X512111Y1047749D03*
Y1041340D03*
X513962Y1038136D03*
X517662D03*
X510262Y1044544D03*
X513962D03*
X517662D03*
X512111Y1060565D03*
X513962Y1057361D03*
X517662D03*
X510262Y1063770D03*
X513962D03*
X517662D03*
X513962Y1050952D03*
X517662D03*
Y1070178D03*
X513962D03*
X512111Y1066974D03*
Y1079791D03*
X513962Y1076587D03*
X517662D03*
X513962Y1089404D03*
X512111Y1086200D03*
X517662Y1089404D03*
X513962Y1082995D03*
X510262D03*
X517662D03*
Y1127856D03*
X513962Y1121447D03*
X510262Y1127856D03*
X506562Y1121447D03*
X502862Y1127856D03*
X515811Y1124651D03*
X512111D03*
X508411D03*
X504711D03*
X517661Y1140973D03*
X513962Y1134264D03*
X512112Y1137469D03*
X506562Y1134264D03*
X504712Y1137469D03*
X515812D03*
X510261Y1140973D03*
X508412Y1137469D03*
X502861Y1140973D03*
X528329Y857789D03*
X522778Y860993D03*
X520929Y857789D03*
X526478Y854584D03*
X524629Y857789D03*
X519078Y854584D03*
X526479Y899445D03*
X530178D03*
X519078D03*
Y893036D03*
X522778D03*
X520929Y896240D03*
X530179Y912262D03*
X532029Y909057D03*
X524629Y902649D03*
X532029D03*
X526479Y912262D03*
X524629Y909057D03*
X526479Y905853D03*
X533879D03*
X522778D03*
X530179D03*
X519078Y912262D03*
X520929Y915466D03*
X526479Y931488D03*
X524629Y928283D03*
X530179Y931488D03*
X532029Y928283D03*
X524629Y921875D03*
X526479Y918670D03*
X532029Y921875D03*
X530179Y918670D03*
X526479Y925079D03*
X533879D03*
X522778D03*
X530179D03*
X519078Y931488D03*
Y918670D03*
X524629Y941100D03*
X526479Y937896D03*
X532029Y941100D03*
X530179Y937896D03*
X524629Y947509D03*
X532029D03*
X519078Y937896D03*
X533879Y944304D03*
X520929Y934691D03*
X526479Y944304D03*
X530178D03*
X522778D03*
X524629Y966735D03*
X532029D03*
X522778Y963530D03*
X526479Y950713D03*
X530178D03*
X532029Y960326D03*
X530178Y957122D03*
X524629Y960326D03*
X526479Y957122D03*
X533879Y963530D03*
X519078Y950713D03*
Y957122D03*
X520929Y953917D03*
X526479Y969939D03*
X530179D03*
X519078Y976347D03*
Y969939D03*
X520929Y973143D03*
X521362Y1006093D03*
X525062Y1012501D03*
X532461D03*
X526911Y1009297D03*
X530611D03*
X519511D03*
X523211Y1015705D03*
X534311D03*
X525062Y1031727D03*
X526911Y1028523D03*
X532461Y1031727D03*
X530611Y1028523D03*
Y1022114D03*
X532461Y1018910D03*
X526911Y1022114D03*
X525062Y1018910D03*
X519511Y1028523D03*
Y1022114D03*
X521362Y1025318D03*
X526911Y1041340D03*
X525062Y1038136D03*
X530611Y1041340D03*
X532461Y1038136D03*
X526911Y1047749D03*
X530611D03*
X526911Y1034931D03*
X534311D03*
X523211D03*
X530611D03*
X519511Y1047749D03*
Y1041340D03*
X521362Y1044544D03*
X519511Y1060565D03*
X526911D03*
X525062Y1057361D03*
X530611Y1060565D03*
X532462Y1057361D03*
X525061Y1050952D03*
X532462Y1050953D03*
X523211Y1054157D03*
X521362Y1063770D03*
X534311Y1054157D03*
X526911D03*
X530611D03*
Y1079791D03*
X532462Y1076587D03*
X525062Y1070178D03*
X526911Y1066974D03*
X532462Y1070178D03*
X530611Y1066974D03*
X526911Y1079791D03*
X525062Y1076587D03*
X523211Y1073383D03*
X534311D03*
X526911D03*
X530611D03*
X519511Y1066974D03*
Y1079791D03*
X521362Y1095813D03*
X532461D03*
X525062D03*
Y1089404D03*
X526911Y1086200D03*
X532462Y1089404D03*
X530611Y1086200D03*
X526911Y1092608D03*
X534310D03*
X523211D03*
X530611D03*
X519511Y1086200D03*
X521362Y1082995D03*
X530611Y1099017D03*
X526911Y1124651D03*
X521362Y1121447D03*
X525062Y1127856D03*
X523211Y1124651D03*
X519511D03*
X532462Y1134264D03*
X525061Y1140973D03*
X523212Y1137469D03*
X534312D03*
X526912D03*
X521362Y1134264D03*
X519512Y1137469D03*
X539429Y883423D03*
X537578Y880219D03*
X543129Y883423D03*
X544979Y880219D03*
X537578Y873810D03*
X539429Y870606D03*
X544979Y873810D03*
X543129Y870606D03*
X539428Y877014D03*
X546828D03*
X535729D03*
X543129D03*
X620799Y883924D03*
Y890617D03*
Y897310D03*
Y900656D03*
Y914042D03*
Y907349D03*
Y1185105D03*
Y1178412D03*
Y1191798D03*
Y1208530D03*
Y1201837D03*
Y1195144D03*
X636941Y880577D03*
Y887270D03*
Y897310D03*
Y893963D03*
Y910696D03*
Y904003D03*
Y1175066D03*
Y1181759D03*
Y1191798D03*
Y1188451D03*
Y1205184D03*
Y1198491D03*
X680299Y780184D03*
Y773491D03*
Y786877D03*
Y803609D03*
Y796916D03*
Y790223D03*
Y816995D03*
Y810302D03*
Y833727D03*
Y823688D03*
Y827034D03*
Y847113D03*
Y840420D03*
Y853806D03*
Y860499D03*
Y863845D03*
Y883924D03*
Y877231D03*
Y870538D03*
Y890617D03*
Y897310D03*
Y900656D03*
Y914042D03*
Y907349D03*
Y927428D03*
Y920735D03*
Y934121D03*
Y944160D03*
Y937467D03*
Y950853D03*
Y980971D03*
Y974278D03*
Y967585D03*
Y994357D03*
Y987664D03*
X679999Y1027822D03*
X680299Y1021129D03*
X679999Y1047900D03*
Y1041207D03*
Y1034514D03*
Y1054593D03*
X680299Y1074672D03*
Y1067979D03*
Y1091404D03*
Y1081365D03*
Y1084711D03*
Y1098097D03*
Y1111483D03*
Y1104790D03*
Y1128215D03*
Y1118176D03*
Y1121522D03*
Y1141601D03*
Y1134908D03*
Y1148294D03*
Y1154987D03*
Y1158333D03*
Y1171719D03*
Y1165026D03*
Y1185105D03*
Y1178412D03*
Y1191798D03*
Y1208530D03*
Y1201837D03*
Y1195144D03*
Y1221916D03*
Y1215223D03*
Y1238648D03*
Y1228609D03*
Y1231955D03*
Y1245341D03*
X696441Y770144D03*
Y776837D03*
Y786877D03*
Y783530D03*
Y800263D03*
Y793570D03*
Y813648D03*
Y806955D03*
Y820341D03*
Y830381D03*
Y823688D03*
Y850459D03*
Y843766D03*
Y837074D03*
Y867192D03*
Y860499D03*
Y857152D03*
Y873885D03*
Y880577D03*
Y887270D03*
Y897310D03*
Y893963D03*
Y917389D03*
Y910696D03*
Y904003D03*
Y924081D03*
Y934121D03*
Y930774D03*
Y947507D03*
Y940814D03*
Y964239D03*
Y977625D03*
Y970932D03*
Y991011D03*
Y984318D03*
Y1021129D03*
Y1024475D03*
Y1031168D03*
X696141Y1044554D03*
Y1037861D03*
X696441Y1051247D03*
Y1071325D03*
Y1064633D03*
Y1078018D03*
Y1094751D03*
Y1088058D03*
Y1081365D03*
Y1108136D03*
Y1101444D03*
Y1124869D03*
Y1118176D03*
Y1114829D03*
Y1144947D03*
Y1138255D03*
Y1131562D03*
Y1161680D03*
Y1154987D03*
Y1151640D03*
Y1175066D03*
Y1168373D03*
Y1181758D03*
Y1191798D03*
Y1188451D03*
Y1205184D03*
Y1198491D03*
Y1218569D03*
Y1211877D03*
Y1225262D03*
Y1241995D03*
Y1235302D03*
Y1228609D03*
X709999Y967585D03*
Y1054593D03*
X726141Y964239D03*
Y1021129D03*
Y1024475D03*
Y1051247D03*
X739699Y816995D03*
Y810302D03*
Y833727D03*
Y823688D03*
Y827034D03*
Y840420D03*
Y927428D03*
Y920735D03*
Y934121D03*
Y944160D03*
Y937467D03*
Y950853D03*
Y980971D03*
Y974278D03*
Y967585D03*
Y994357D03*
Y987664D03*
Y1027822D03*
Y1021129D03*
Y1047900D03*
Y1041207D03*
Y1034514D03*
Y1054593D03*
Y1141601D03*
Y1148294D03*
Y1154987D03*
Y1158333D03*
Y1171719D03*
Y1165026D03*
Y1221916D03*
Y1215223D03*
Y1238648D03*
Y1228609D03*
Y1231955D03*
Y1245341D03*
X755841Y813648D03*
Y806955D03*
Y820341D03*
Y830381D03*
Y823688D03*
Y837074D03*
Y917389D03*
Y924081D03*
Y934121D03*
Y930774D03*
Y947507D03*
Y940814D03*
Y964239D03*
Y977625D03*
X755741Y970932D03*
X755841Y991011D03*
Y984318D03*
Y1021129D03*
Y1024475D03*
Y1031168D03*
X755541Y1044554D03*
Y1037861D03*
X755841Y1051247D03*
Y1144947D03*
Y1138255D03*
Y1161680D03*
Y1154987D03*
Y1151640D03*
Y1168373D03*
Y1218569D03*
Y1211877D03*
Y1225262D03*
Y1241995D03*
Y1235302D03*
Y1228609D03*
X769399Y967585D03*
Y1054593D03*
X785541Y964239D03*
Y1021129D03*
Y1024475D03*
Y1051247D03*
X1071941Y967585D03*
Y1054593D03*
X1101641Y816995D03*
Y810302D03*
Y833727D03*
Y823688D03*
Y827034D03*
Y840420D03*
Y927428D03*
Y920735D03*
Y934121D03*
Y944160D03*
Y937467D03*
Y950853D03*
X1088083Y964239D03*
X1101641Y980971D03*
Y974278D03*
Y967585D03*
Y994357D03*
Y987664D03*
X1088083Y1021129D03*
Y1024475D03*
X1101641Y1027822D03*
Y1021129D03*
Y1047900D03*
Y1041207D03*
Y1034515D03*
X1088083Y1051247D03*
X1101641Y1054593D03*
Y1141601D03*
Y1148294D03*
Y1154987D03*
Y1158333D03*
Y1171719D03*
Y1165026D03*
Y1221916D03*
Y1215223D03*
Y1238648D03*
Y1228609D03*
Y1231955D03*
Y1245341D03*
X1117783Y813648D03*
Y806955D03*
Y820341D03*
Y830381D03*
Y823688D03*
Y837074D03*
Y917389D03*
Y924081D03*
Y934121D03*
Y930774D03*
Y947507D03*
Y940814D03*
Y964239D03*
Y977625D03*
Y970932D03*
Y991011D03*
Y984318D03*
Y1021129D03*
Y1024475D03*
Y1031168D03*
Y1044554D03*
Y1037861D03*
Y1051247D03*
Y1144948D03*
Y1138255D03*
Y1161680D03*
Y1154987D03*
Y1151641D03*
Y1168373D03*
Y1218570D03*
Y1211877D03*
Y1225263D03*
Y1241995D03*
Y1235302D03*
Y1228609D03*
X1131341Y967585D03*
Y1054593D03*
X1147483Y964239D03*
Y1021129D03*
Y1024475D03*
Y1051247D03*
X1161041Y780184D03*
Y773491D03*
Y786877D03*
Y803609D03*
Y796916D03*
Y790223D03*
Y816995D03*
Y810302D03*
Y833727D03*
Y823688D03*
Y827034D03*
Y847113D03*
Y840420D03*
Y853806D03*
Y860499D03*
Y863845D03*
Y883924D03*
Y877231D03*
Y870538D03*
Y890617D03*
Y897310D03*
Y900656D03*
Y914042D03*
Y907349D03*
Y927428D03*
Y920735D03*
Y934121D03*
Y944160D03*
Y937467D03*
Y950853D03*
Y980971D03*
Y974278D03*
Y967585D03*
Y994357D03*
Y987664D03*
Y1027822D03*
Y1021129D03*
Y1047900D03*
Y1041207D03*
Y1034515D03*
Y1054593D03*
Y1074672D03*
Y1067979D03*
Y1091404D03*
Y1081365D03*
Y1084711D03*
Y1098097D03*
Y1111483D03*
Y1104790D03*
Y1128215D03*
Y1118176D03*
Y1121522D03*
Y1141601D03*
Y1134908D03*
Y1148294D03*
Y1154987D03*
Y1158333D03*
Y1171719D03*
Y1165026D03*
Y1185105D03*
Y1178412D03*
Y1191798D03*
Y1208530D03*
Y1201837D03*
Y1195144D03*
Y1221916D03*
Y1215223D03*
Y1238648D03*
Y1228609D03*
Y1231955D03*
Y1245341D03*
X1177183Y770144D03*
Y776837D03*
Y786877D03*
Y783530D03*
Y800263D03*
Y793570D03*
Y813648D03*
Y806955D03*
Y820341D03*
Y830381D03*
Y823688D03*
Y850459D03*
Y843766D03*
Y837074D03*
Y867192D03*
Y860499D03*
Y857152D03*
Y873885D03*
Y880577D03*
Y887270D03*
Y897310D03*
Y893963D03*
Y917389D03*
Y910696D03*
Y904003D03*
Y924081D03*
Y934121D03*
Y930774D03*
Y947507D03*
Y940814D03*
Y964239D03*
Y977625D03*
Y970932D03*
Y991011D03*
Y984318D03*
X1177283Y1021129D03*
Y1024475D03*
Y1031168D03*
Y1044554D03*
Y1037861D03*
Y1051247D03*
Y1071326D03*
Y1064633D03*
Y1078018D03*
Y1094752D03*
Y1088059D03*
Y1081366D03*
Y1108137D03*
Y1101444D03*
X1177183Y1124869D03*
X1177283Y1118177D03*
Y1114830D03*
Y1144948D03*
Y1138255D03*
X1177183Y1131562D03*
X1177283Y1161680D03*
Y1154988D03*
Y1151641D03*
Y1175066D03*
Y1168373D03*
Y1181759D03*
Y1191799D03*
Y1188452D03*
Y1205184D03*
Y1198491D03*
Y1218570D03*
Y1211877D03*
Y1225263D03*
X1177250Y1241995D03*
X1177283Y1235302D03*
Y1228609D03*
X1220441Y883924D03*
Y890617D03*
Y897310D03*
Y900656D03*
Y914042D03*
Y907349D03*
Y1185105D03*
Y1178412D03*
Y1191798D03*
Y1208530D03*
Y1201837D03*
Y1195144D03*
X1236583Y880577D03*
Y887270D03*
Y897310D03*
Y893963D03*
Y910696D03*
Y904003D03*
Y1175066D03*
Y1181759D03*
Y1191798D03*
Y1188452D03*
Y1205184D03*
Y1198491D03*
X1313921Y880219D03*
X1312070Y883423D03*
X1313921Y893036D03*
X1312070Y889832D03*
X1310221Y886627D03*
X1313921D03*
X1326871Y857789D03*
X1328720Y860993D03*
X1330571Y857789D03*
X1317621Y880219D03*
X1319471Y883423D03*
X1325020Y899445D03*
Y893036D03*
X1326871Y889832D03*
X1330571D03*
X1317620Y893036D03*
X1319470Y889832D03*
X1323171Y896240D03*
X1330571D03*
X1317621Y886627D03*
X1326871Y896240D03*
X1321321Y886627D03*
X1325020Y912262D03*
X1326871Y909057D03*
X1330571D03*
X1326871Y902649D03*
X1330571D03*
X1323171Y915466D03*
X1330571D03*
X1326871D03*
X1325021Y931488D03*
X1326871Y928283D03*
X1330571D03*
Y921875D03*
X1326871D03*
X1325020Y918670D03*
X1326871Y941100D03*
X1325020Y937896D03*
X1330571Y941100D03*
X1323171Y934691D03*
X1330571D03*
X1326871D03*
Y947509D03*
X1330571D03*
X1325020Y950713D03*
X1326871Y960326D03*
X1325020Y957122D03*
X1330571Y960326D03*
X1326871Y966735D03*
X1330571D03*
X1326871Y953917D03*
X1330571D03*
X1323172D03*
X1326871Y979552D03*
X1330571D03*
X1325020Y976347D03*
X1323171Y973143D03*
X1325020Y969939D03*
X1323603Y1006093D03*
X1325453Y1002888D03*
X1327303Y999684D03*
X1331003D03*
X1327303Y1012501D03*
X1325453Y1009297D03*
X1331003Y1012501D03*
X1327304Y1031727D03*
X1325453Y1028523D03*
X1331003Y1031727D03*
X1325453Y1022114D03*
X1327303Y1018910D03*
X1331003D03*
X1323603Y1025318D03*
X1331004D03*
X1327304D03*
X1325453Y1047749D03*
Y1041340D03*
X1327303Y1038136D03*
X1331003D03*
X1323603Y1044544D03*
X1331003D03*
X1327303D03*
X1325453Y1060565D03*
X1327303Y1057361D03*
X1331003D03*
X1323603Y1063770D03*
X1327303D03*
X1331003D03*
X1327303Y1050952D03*
X1331003D03*
Y1070178D03*
X1327304D03*
X1325453Y1066974D03*
Y1079791D03*
X1327303Y1076587D03*
X1331003D03*
X1327303Y1089404D03*
X1325453Y1086200D03*
X1331003Y1089404D03*
X1323603Y1082995D03*
X1331003D03*
X1327303D03*
X1329153Y1124651D03*
X1331003Y1127856D03*
X1325452Y1137469D03*
X1327303Y1134264D03*
X1346137Y179649D03*
X1332420Y854584D03*
X1334271Y857789D03*
X1337971D03*
X1341671D03*
X1345371D03*
X1336120Y860993D03*
X1339820Y854584D03*
X1343520Y860993D03*
X1347220Y854584D03*
X1332420Y899445D03*
Y893036D03*
X1334271Y896240D03*
X1339820Y899445D03*
X1343520D03*
X1332420Y912262D03*
X1334271Y915466D03*
X1339820Y912262D03*
X1337971Y909057D03*
X1343520Y912262D03*
X1345371Y909057D03*
X1337971Y902649D03*
X1345371D03*
X1336120Y905853D03*
X1343520D03*
X1339820D03*
X1347220D03*
X1332420Y931488D03*
X1339820D03*
X1332420Y918670D03*
X1337971Y928283D03*
X1343520Y931488D03*
X1345371Y928283D03*
X1337971Y921875D03*
X1339820Y918670D03*
X1345371Y921875D03*
X1343520Y918670D03*
X1336120Y925079D03*
X1343520D03*
X1339820D03*
X1347220D03*
X1332420Y937896D03*
X1334271Y934691D03*
X1337971Y941100D03*
X1339820Y937896D03*
X1345371Y941100D03*
X1343520Y937896D03*
X1337971Y947509D03*
X1345371D03*
X1343520Y944304D03*
X1336120D03*
X1347220D03*
X1339820D03*
X1332420Y950713D03*
Y957122D03*
X1334271Y953917D03*
X1337971Y966735D03*
X1345371D03*
X1336120Y963530D03*
X1339820Y950713D03*
X1343520D03*
X1337971Y960326D03*
X1339820Y957122D03*
X1345371Y960326D03*
X1343520Y957122D03*
X1347220Y963530D03*
X1336120Y982756D03*
X1343520D03*
X1339820D03*
X1347220D03*
X1345371Y979552D03*
X1343520Y976347D03*
X1337971Y979552D03*
X1339820Y976347D03*
X1332420D03*
Y969939D03*
X1334271Y973143D03*
X1339820Y969939D03*
X1343520D03*
X1334704Y1006093D03*
X1332853Y1002888D03*
Y1009297D03*
X1338404Y1012501D03*
X1345804D03*
X1340253Y1009297D03*
X1343953D03*
X1340253Y1002888D03*
X1338404Y999684D03*
X1347653Y1002888D03*
X1345804Y999684D03*
X1332853Y1028523D03*
Y1022114D03*
X1338404Y1031727D03*
X1340253Y1028523D03*
X1345804Y1031727D03*
X1343953Y1028523D03*
X1334704Y1025318D03*
X1336553Y1015705D03*
X1347653D03*
X1340253Y1022114D03*
X1338404Y1018910D03*
X1343953Y1022114D03*
X1345804Y1018910D03*
X1332853Y1047749D03*
Y1041340D03*
X1340253D03*
X1338404Y1038136D03*
X1343953Y1041340D03*
X1345804Y1038136D03*
X1336553Y1034931D03*
X1347653D03*
X1340253D03*
X1334704Y1044544D03*
X1343953Y1034931D03*
X1340253Y1047749D03*
X1343953D03*
X1332853Y1060565D03*
X1334704Y1063770D03*
X1340253Y1060565D03*
X1338404Y1057361D03*
X1343953Y1060565D03*
X1345804Y1057361D03*
X1338404Y1050952D03*
X1345804D03*
X1336553Y1054157D03*
X1347653D03*
X1340253D03*
X1343953D03*
X1332853Y1066974D03*
X1343953Y1079791D03*
X1345804Y1076587D03*
X1338404Y1070178D03*
X1340253Y1066974D03*
X1345804Y1070178D03*
X1343953Y1066974D03*
X1332853Y1079791D03*
X1340253D03*
X1338404Y1076587D03*
X1336553Y1073383D03*
X1347653D03*
X1340253D03*
X1343953D03*
X1332853Y1086200D03*
X1334704Y1082995D03*
X1338404Y1095813D03*
X1345804D03*
X1338404Y1089404D03*
X1340253Y1086200D03*
X1345804Y1089404D03*
X1343953Y1086200D03*
X1336553Y1092608D03*
X1343953D03*
X1340253D03*
X1347653D03*
X1340253Y1099017D03*
X1343953D03*
X1334703Y1121447D03*
X1336554Y1124651D03*
X1340253D03*
X1343953D03*
X1347653D03*
X1332854D03*
X1338404Y1127856D03*
X1342104Y1121447D03*
X1345804Y1127856D03*
X1334703Y1134264D03*
X1338403Y1140973D03*
X1342104Y1134264D03*
X1345803Y1140973D03*
X1332854Y1137469D03*
X1336554D03*
X1340254D03*
X1343954D03*
X1347654D03*
X1352557Y175948D03*
X1349351Y181498D03*
X1355761Y185198D03*
X1349351D03*
X1355761Y174098D03*
Y181498D03*
X1352557Y183348D03*
X1352561Y198148D03*
X1355771Y196298D03*
X1355765Y199999D03*
Y203699D03*
X1349071Y857789D03*
X1354620Y854584D03*
X1356471Y857789D03*
X1360171D03*
X1363871D03*
X1350920Y860993D03*
X1352771Y857789D03*
X1358320Y860993D03*
X1362020Y854584D03*
X1349504Y1006093D03*
X1356904D03*
X1353204D03*
X1360604D03*
X1351353Y1124651D03*
X1355053D03*
X1358753D03*
X1362453D03*
X1349504Y1121447D03*
X1353204Y1127856D03*
X1356904Y1121447D03*
X1360604Y1127856D03*
X1349504Y1134264D03*
X1353203Y1140973D03*
X1356904Y1134264D03*
X1360603Y1140973D03*
X1351354Y1137469D03*
X1355054D03*
X1358754D03*
X1362454D03*
X1365720Y860993D03*
X1367571Y857789D03*
X1373120Y860993D03*
X1374971Y857789D03*
X1369420Y854584D03*
X1371271Y857789D03*
X1376820Y854584D03*
X1378671Y857789D03*
X1366153Y1124651D03*
X1371704Y1121447D03*
X1373553Y1124651D03*
X1377253D03*
X1368004Y1127856D03*
X1369853Y1124651D03*
X1375404Y1127856D03*
X1379104Y1121447D03*
X1364304D03*
X1368003Y1140973D03*
X1371704Y1134264D03*
X1375403Y1140973D03*
X1379104Y1134264D03*
X1364304D03*
X1366154Y1137469D03*
X1369854D03*
X1373554D03*
X1377254D03*
X1380520Y860993D03*
X1382371Y857789D03*
X1387920Y860993D03*
X1389771Y857789D03*
X1395320Y860993D03*
X1384220Y854584D03*
X1386071Y857789D03*
X1391620Y854584D03*
X1393471Y857789D03*
Y883423D03*
X1391620Y880219D03*
X1389771Y883423D03*
X1395320Y886627D03*
X1380953Y1124651D03*
X1384653D03*
X1382804Y1127856D03*
X1386504Y1121447D03*
X1382803Y1140973D03*
X1386504Y1134264D03*
X1380954Y1137469D03*
X1384654D03*
X1397171Y857789D03*
X1402720Y860993D03*
X1404571Y857789D03*
X1410121Y860993D03*
X1411971Y857789D03*
X1399020Y854584D03*
X1400871Y857789D03*
X1406420Y854584D03*
X1408271Y857789D03*
Y883423D03*
X1406420Y880219D03*
X1400871Y883423D03*
X1399020Y880219D03*
X1404571Y883423D03*
X1397171D03*
X1411971D03*
X1410120Y886627D03*
X1402720D03*
X1424921Y860993D03*
X1421220Y854584D03*
X1417520Y860993D03*
X1428620Y854584D03*
X1426771Y857789D03*
X1423071D03*
X1419371D03*
X1413821Y854584D03*
X1428621Y880219D03*
X1423071Y883423D03*
X1421220Y880219D03*
X1415671Y883423D03*
X1413820Y880219D03*
X1426771Y883423D03*
X1419371D03*
X1424920Y886627D03*
X1417520D03*
X1445271Y857789D03*
X1439720Y860993D03*
X1437871Y857789D03*
X1432320Y860993D03*
X1430471Y857789D03*
X1443420Y854584D03*
X1441571Y857789D03*
X1436020Y854584D03*
X1434171Y857789D03*
X1445271Y883423D03*
X1443420Y880219D03*
X1437871Y883423D03*
X1436020Y880219D03*
X1430471Y883423D03*
X1441571D03*
X1434171D03*
X1439720Y886627D03*
X1432320D03*
X1460071Y857789D03*
X1454520Y860993D03*
X1452671Y857789D03*
X1447120Y860993D03*
X1458220Y854584D03*
X1456371Y857789D03*
X1450820Y854584D03*
X1448971Y857789D03*
X1447120Y886627D03*
X1460504Y1121447D03*
X1456804Y1127856D03*
X1453104Y1121447D03*
X1449404Y1127856D03*
X1445704Y1121447D03*
X1458653Y1124651D03*
X1454953D03*
X1451253D03*
X1447553D03*
X1460504Y1134264D03*
X1458654Y1137469D03*
X1453104Y1134264D03*
X1451254Y1137469D03*
X1456803Y1140973D03*
X1454954Y1137469D03*
X1449403Y1140973D03*
X1467471Y857789D03*
X1461920Y860993D03*
X1476720D03*
X1474871Y857789D03*
X1471171D03*
X1465620Y854584D03*
X1463771Y857789D03*
X1473020Y854584D03*
X1469320Y860993D03*
X1476720Y982756D03*
X1473020D03*
X1474871Y979552D03*
X1476720Y976347D03*
X1475304Y1012501D03*
X1477153Y1009297D03*
X1473453Y1015705D03*
X1477153Y1022114D03*
X1475304Y1018910D03*
X1464204Y1127856D03*
X1475304Y1121447D03*
X1471604Y1127856D03*
X1467904Y1121447D03*
X1466053Y1124651D03*
X1462353D03*
X1477153D03*
X1473453D03*
X1469753D03*
X1469754Y1137469D03*
X1464203Y1140973D03*
X1477154Y1137469D03*
X1471603Y1140973D03*
X1467904Y1134264D03*
X1466054Y1137469D03*
X1462354D03*
X1475304Y1134264D03*
X1473454Y1137469D03*
X1491520Y860993D03*
X1489671Y857789D03*
X1484120Y860993D03*
X1482271Y857789D03*
X1493371D03*
X1487820Y854584D03*
X1485971Y857789D03*
X1480420Y854584D03*
X1478571Y857789D03*
X1487820Y899445D03*
Y893036D03*
X1484120D03*
X1485971Y896240D03*
X1493371D03*
X1489671D03*
Y902649D03*
X1493371D03*
X1487820Y912262D03*
X1489671Y909057D03*
X1493371D03*
X1489671Y915466D03*
X1485971D03*
X1493371D03*
X1487820Y931488D03*
X1489671Y928283D03*
X1493371D03*
X1489671Y921875D03*
X1487820Y918670D03*
X1493371Y921875D03*
X1489671Y941100D03*
X1487820Y937896D03*
X1493371Y941100D03*
X1489671Y934691D03*
X1485971D03*
X1493371D03*
X1489671Y947509D03*
X1493371D03*
X1487820Y950713D03*
X1489671Y960326D03*
X1487820Y957122D03*
X1493371Y960326D03*
Y966735D03*
X1489671D03*
Y953917D03*
X1493371D03*
X1485971D03*
X1484120Y982756D03*
X1480420D03*
Y976347D03*
X1482271Y979552D03*
X1489671D03*
X1493371D03*
X1487820Y976347D03*
X1485971Y973143D03*
X1487820Y969939D03*
X1493804Y1006093D03*
X1490104D03*
X1486404D03*
X1493804Y1012501D03*
X1490104D03*
X1488253Y1009297D03*
X1482704Y1012501D03*
X1480853Y1009297D03*
X1490104Y1031727D03*
X1488253Y1028523D03*
X1493804Y1031727D03*
X1488253Y1022114D03*
X1490104Y1018910D03*
X1493804D03*
X1490104Y1025318D03*
X1486404D03*
X1493804D03*
X1484553Y1015705D03*
X1480853Y1022114D03*
X1482704Y1018910D03*
X1488253Y1047749D03*
Y1041340D03*
X1490104Y1038136D03*
X1493804D03*
X1486404Y1044544D03*
X1490104D03*
X1493804D03*
X1488253Y1060565D03*
X1490104Y1057361D03*
X1493804D03*
X1486404Y1063770D03*
X1490104D03*
X1493804D03*
X1490104Y1050952D03*
X1493804D03*
Y1070178D03*
X1490104D03*
X1488253Y1066974D03*
Y1079791D03*
X1490104Y1076587D03*
X1493804D03*
X1490104Y1089404D03*
X1488253Y1086200D03*
X1493804Y1089404D03*
X1490104Y1082995D03*
X1486404D03*
X1493804D03*
Y1127856D03*
X1490104Y1121447D03*
X1486404Y1127856D03*
X1482704Y1121447D03*
X1479004Y1127856D03*
X1491953Y1124651D03*
X1488253D03*
X1484553D03*
X1480853D03*
X1493803Y1140973D03*
X1490104Y1134264D03*
X1488254Y1137469D03*
X1482704Y1134264D03*
X1480854Y1137469D03*
X1491954D03*
X1486403Y1140973D03*
X1484554Y1137469D03*
X1479003Y1140973D03*
X1504471Y857789D03*
X1498920Y860993D03*
X1497071Y857789D03*
X1502620Y854584D03*
X1500771Y857789D03*
X1495220Y854584D03*
X1502621Y899445D03*
X1506320D03*
X1495220D03*
Y893036D03*
X1498920D03*
X1497071Y896240D03*
X1506321Y912262D03*
X1508171Y909057D03*
X1500771Y902649D03*
X1508171D03*
X1502621Y912262D03*
X1500771Y909057D03*
X1502621Y905853D03*
X1510021D03*
X1498920D03*
X1506321D03*
X1495220Y912262D03*
X1497071Y915466D03*
X1502621Y931488D03*
X1500771Y928283D03*
X1506321Y931488D03*
X1508171Y928283D03*
X1500771Y921875D03*
X1502621Y918670D03*
X1508171Y921875D03*
X1506321Y918670D03*
X1502621Y925079D03*
X1510021D03*
X1498920D03*
X1506321D03*
X1495220Y931488D03*
Y918670D03*
X1500771Y941100D03*
X1502621Y937896D03*
X1508171Y941100D03*
X1506321Y937896D03*
X1500771Y947509D03*
X1508171D03*
X1495220Y937896D03*
X1510021Y944304D03*
X1497071Y934691D03*
X1502621Y944304D03*
X1506320D03*
X1498920D03*
X1500771Y966735D03*
X1508171D03*
X1498920Y963530D03*
X1502621Y950713D03*
X1506320D03*
X1508171Y960326D03*
X1506320Y957122D03*
X1500771Y960326D03*
X1502621Y957122D03*
X1510021Y963530D03*
X1495220Y950713D03*
Y957122D03*
X1497071Y953917D03*
X1502621Y969939D03*
X1506321D03*
X1495220Y976347D03*
Y969939D03*
X1497071Y973143D03*
X1497504Y1006093D03*
X1501204Y1012501D03*
X1508603D03*
X1503053Y1009297D03*
X1506753D03*
X1495653D03*
X1499353Y1015705D03*
X1510453D03*
X1501204Y1031727D03*
X1503053Y1028523D03*
X1508603Y1031727D03*
X1506753Y1028523D03*
Y1022114D03*
X1508603Y1018910D03*
X1503053Y1022114D03*
X1501204Y1018910D03*
X1495653Y1028523D03*
Y1022114D03*
X1497504Y1025318D03*
X1503053Y1041340D03*
X1501204Y1038136D03*
X1506753Y1041340D03*
X1508603Y1038136D03*
X1503053Y1047749D03*
X1506753D03*
X1503053Y1034931D03*
X1510453D03*
X1499353D03*
X1506753D03*
X1495653Y1047749D03*
Y1041340D03*
X1497504Y1044544D03*
X1495653Y1060565D03*
X1503053D03*
X1501204Y1057361D03*
X1506753Y1060565D03*
X1508604Y1057361D03*
X1501203Y1050952D03*
X1508604Y1050953D03*
X1499353Y1054157D03*
X1497504Y1063770D03*
X1510453Y1054157D03*
X1503053D03*
X1506753D03*
Y1079791D03*
X1508604Y1076587D03*
X1501204Y1070178D03*
X1503053Y1066974D03*
X1508604Y1070178D03*
X1506753Y1066974D03*
X1503053Y1079791D03*
X1501204Y1076587D03*
X1499353Y1073383D03*
X1510453D03*
X1503053D03*
X1506753D03*
X1495653Y1066974D03*
Y1079791D03*
X1497504Y1095813D03*
X1508603D03*
X1501204D03*
Y1089404D03*
X1503053Y1086200D03*
X1508604Y1089404D03*
X1506753Y1086200D03*
X1503053Y1092608D03*
X1510452D03*
X1499353D03*
X1506753D03*
X1495653Y1086200D03*
X1497504Y1082995D03*
X1506753Y1099017D03*
X1503053Y1124651D03*
X1497504Y1121447D03*
X1501204Y1127856D03*
X1499353Y1124651D03*
X1495653D03*
X1508604Y1134264D03*
X1501203Y1140973D03*
X1499354Y1137469D03*
X1510454D03*
X1503054D03*
X1497504Y1134264D03*
X1495654Y1137469D03*
X1515571Y883423D03*
X1513720Y880219D03*
X1519271Y883423D03*
X1521121Y880219D03*
X1513720Y873810D03*
X1515571Y870606D03*
X1521121Y873810D03*
X1519271Y870606D03*
X1515570Y877014D03*
X1522970D03*
X1511871D03*
X1519271D03*
X1596941Y883924D03*
Y890617D03*
Y897310D03*
Y900656D03*
Y914042D03*
Y907349D03*
Y1185105D03*
Y1178412D03*
Y1191798D03*
Y1208530D03*
Y1201837D03*
Y1195144D03*
X1613083Y880577D03*
Y887270D03*
Y897310D03*
Y893963D03*
Y910696D03*
Y904003D03*
Y1175066D03*
Y1181759D03*
Y1191798D03*
Y1188451D03*
Y1205184D03*
Y1198491D03*
X1656441Y780184D03*
Y773491D03*
Y786877D03*
Y803609D03*
Y796916D03*
Y790223D03*
Y816995D03*
Y810302D03*
Y833727D03*
Y823688D03*
Y827034D03*
Y847113D03*
Y840420D03*
Y853806D03*
Y860499D03*
Y863845D03*
Y883924D03*
Y877231D03*
Y870538D03*
Y890617D03*
Y897310D03*
Y900656D03*
Y914042D03*
Y907349D03*
Y927428D03*
Y920735D03*
Y934121D03*
Y944160D03*
Y937467D03*
Y950853D03*
Y980971D03*
Y974278D03*
Y967585D03*
Y994357D03*
Y987664D03*
X1656141Y1027822D03*
X1656441Y1021129D03*
X1656141Y1047900D03*
Y1041207D03*
Y1034514D03*
Y1054593D03*
X1656441Y1074672D03*
Y1067979D03*
Y1091404D03*
Y1081365D03*
Y1084711D03*
Y1098097D03*
Y1111483D03*
Y1104790D03*
Y1128215D03*
Y1118176D03*
Y1121522D03*
Y1141601D03*
Y1134908D03*
Y1148294D03*
Y1154987D03*
Y1158333D03*
Y1171719D03*
Y1165026D03*
Y1185105D03*
Y1178412D03*
Y1191798D03*
Y1208530D03*
Y1201837D03*
Y1195144D03*
Y1221916D03*
Y1215223D03*
Y1238648D03*
Y1228609D03*
Y1231955D03*
Y1245341D03*
X1672583Y770144D03*
Y776837D03*
Y786877D03*
Y783530D03*
Y800263D03*
Y793570D03*
Y813648D03*
Y806955D03*
Y820341D03*
Y830381D03*
Y823688D03*
Y850459D03*
Y843766D03*
Y837074D03*
Y867192D03*
Y860499D03*
Y857152D03*
Y873885D03*
Y880577D03*
Y887270D03*
Y897310D03*
Y893963D03*
Y917389D03*
Y910696D03*
Y904003D03*
Y924081D03*
Y934121D03*
Y930774D03*
Y947507D03*
Y940814D03*
Y964239D03*
Y977625D03*
Y970932D03*
Y991011D03*
Y984318D03*
Y1021129D03*
Y1024475D03*
Y1031168D03*
X1672283Y1044554D03*
Y1037861D03*
X1672583Y1051247D03*
Y1071325D03*
Y1064633D03*
Y1078018D03*
Y1094751D03*
Y1088058D03*
Y1081365D03*
Y1108136D03*
Y1101444D03*
Y1124869D03*
Y1118176D03*
Y1114829D03*
Y1144947D03*
Y1138255D03*
Y1131562D03*
Y1161680D03*
Y1154987D03*
Y1151640D03*
Y1175066D03*
Y1168373D03*
Y1181758D03*
Y1191798D03*
Y1188451D03*
Y1205184D03*
Y1198491D03*
Y1218569D03*
Y1211877D03*
Y1225262D03*
Y1241995D03*
Y1235302D03*
Y1228609D03*
X1686141Y967585D03*
Y1054593D03*
X1702283Y964239D03*
Y1021129D03*
Y1024475D03*
Y1051247D03*
X1715841Y816995D03*
Y810302D03*
Y833727D03*
Y823688D03*
Y827034D03*
Y840420D03*
Y927428D03*
Y920735D03*
Y934121D03*
Y944160D03*
Y937467D03*
Y950853D03*
Y980971D03*
Y974278D03*
Y967585D03*
Y994357D03*
Y987664D03*
Y1027822D03*
Y1021129D03*
Y1047900D03*
Y1041207D03*
Y1034514D03*
Y1054593D03*
Y1141601D03*
Y1148294D03*
Y1154987D03*
Y1158333D03*
Y1171719D03*
Y1165026D03*
Y1221916D03*
Y1215223D03*
Y1238648D03*
Y1228609D03*
Y1231955D03*
Y1245341D03*
X1731983Y813648D03*
Y806955D03*
Y820341D03*
Y830381D03*
Y823688D03*
Y837074D03*
Y917389D03*
Y924081D03*
Y934121D03*
Y930774D03*
Y947507D03*
Y940814D03*
Y964239D03*
Y977625D03*
X1731883Y970932D03*
X1731983Y991011D03*
Y984318D03*
Y1021129D03*
Y1024475D03*
Y1031168D03*
X1731683Y1044554D03*
Y1037861D03*
X1731983Y1051247D03*
Y1144947D03*
Y1138255D03*
Y1161680D03*
Y1154987D03*
Y1151640D03*
Y1168373D03*
Y1218569D03*
Y1211877D03*
Y1225262D03*
Y1241995D03*
Y1235302D03*
Y1228609D03*
X1745541Y967585D03*
Y1054593D03*
X1761683Y964239D03*
Y1021129D03*
Y1024475D03*
Y1051247D03*
G54D48*
X676508Y145866D03*
G54D35*
X238780Y1643661D03*
X230906Y1649173D03*
X238780Y1653110D03*
Y1657834D03*
X230906Y1653897D03*
Y1663346D03*
X238780Y1667283D03*
Y1672007D03*
Y1681456D03*
X230906Y1668070D03*
Y1677519D03*
Y1682244D03*
X238780Y1686180D03*
Y1695629D03*
X230906Y1691692D03*
Y1696417D03*
X238780Y1700354D03*
Y1709803D03*
Y1714527D03*
X230906Y1705866D03*
Y1710590D03*
X238780Y1723976D03*
Y1728700D03*
X230906Y1720039D03*
Y1724763D03*
Y1734212D03*
X254528Y1643661D03*
X246654Y1649173D03*
X254528Y1653110D03*
Y1657834D03*
X246654Y1653897D03*
Y1663346D03*
X254528Y1667283D03*
Y1672007D03*
Y1681456D03*
X246654Y1668070D03*
Y1677519D03*
Y1682244D03*
X254528Y1686180D03*
Y1695629D03*
X246654Y1691692D03*
Y1696417D03*
X254528Y1700354D03*
Y1709803D03*
Y1714527D03*
X246654Y1705866D03*
Y1710590D03*
X254528Y1723976D03*
Y1728700D03*
X246654Y1720039D03*
Y1724763D03*
Y1734212D03*
X270276Y1643661D03*
X262402Y1649173D03*
X270276Y1653110D03*
Y1657834D03*
X262402Y1653897D03*
Y1663346D03*
X270276Y1667283D03*
Y1672007D03*
Y1681456D03*
X262402Y1668070D03*
Y1677519D03*
Y1682244D03*
X270276Y1686180D03*
Y1695629D03*
X262402Y1691692D03*
Y1696417D03*
X270276Y1700354D03*
Y1709803D03*
Y1714527D03*
X262402Y1705866D03*
Y1710590D03*
X270276Y1723976D03*
Y1728700D03*
X262402Y1720039D03*
Y1724763D03*
Y1734212D03*
X286024Y1643661D03*
X278150Y1649173D03*
X286024Y1653110D03*
Y1657834D03*
X278150Y1653897D03*
Y1663346D03*
X286024Y1667283D03*
Y1672007D03*
Y1681456D03*
X278150Y1668070D03*
Y1677519D03*
Y1682244D03*
X286024Y1686180D03*
Y1695629D03*
X278150Y1691692D03*
Y1696417D03*
X286024Y1700354D03*
Y1709803D03*
Y1714527D03*
X278150Y1705866D03*
Y1710590D03*
X286024Y1723976D03*
Y1728700D03*
X278150Y1720039D03*
Y1724763D03*
Y1734212D03*
X305709Y1672007D03*
X297835Y1677519D03*
Y1682244D03*
X305709Y1681456D03*
Y1686180D03*
X297835Y1691692D03*
Y1696417D03*
X305709Y1695629D03*
Y1700354D03*
X297835Y1705866D03*
Y1710590D03*
X305709Y1709803D03*
Y1714527D03*
X297835Y1720039D03*
Y1724763D03*
X305709Y1723976D03*
Y1728700D03*
X297835Y1734212D03*
X321457Y1672007D03*
X313583Y1677519D03*
Y1682244D03*
X321457Y1681456D03*
Y1686180D03*
X313583Y1691692D03*
Y1696417D03*
X321457Y1695629D03*
Y1700354D03*
X313583Y1705866D03*
Y1710590D03*
X321457Y1709803D03*
Y1714527D03*
X313583Y1720039D03*
Y1724763D03*
X321457Y1723976D03*
Y1728700D03*
X313583Y1734212D03*
X337205Y1672007D03*
X329331Y1677519D03*
Y1682244D03*
X337205Y1681456D03*
Y1686180D03*
X329331Y1691692D03*
Y1696417D03*
X337205Y1695629D03*
Y1700354D03*
X329331Y1705866D03*
Y1710590D03*
X337205Y1709803D03*
Y1714527D03*
X329331Y1720039D03*
Y1724763D03*
X337205Y1723976D03*
Y1728700D03*
X329331Y1734212D03*
X352953Y1672007D03*
X345079Y1677519D03*
Y1682244D03*
X352953Y1681456D03*
Y1686180D03*
X345079Y1691692D03*
Y1696417D03*
X352953Y1695629D03*
Y1700354D03*
X345079Y1705866D03*
Y1710590D03*
X352953Y1709803D03*
Y1714527D03*
X345079Y1720039D03*
Y1724763D03*
X352953Y1723976D03*
Y1728700D03*
X345079Y1734212D03*
X495079Y1677519D03*
Y1682244D03*
Y1691692D03*
Y1696417D03*
Y1705866D03*
Y1710590D03*
Y1720039D03*
Y1724763D03*
Y1734212D03*
X502953Y1672007D03*
X510827Y1677519D03*
X502953Y1681456D03*
X510827Y1682244D03*
X502953Y1686180D03*
X510827Y1691692D03*
X502953Y1695629D03*
X510827Y1696417D03*
X502953Y1700354D03*
X510827Y1705866D03*
X502953Y1709803D03*
X510827Y1710590D03*
X502953Y1714527D03*
X510827Y1720039D03*
X502953Y1723976D03*
X510827Y1724763D03*
X502953Y1728700D03*
X510827Y1734212D03*
X518701Y1672007D03*
X534449D03*
X526575Y1677519D03*
X518701Y1681456D03*
X526575Y1682244D03*
X534449Y1681456D03*
X518701Y1686180D03*
X534449D03*
X526575Y1691692D03*
X518701Y1695629D03*
X526575Y1696417D03*
X534449Y1695629D03*
X518701Y1700354D03*
X534449D03*
X526575Y1705866D03*
X518701Y1709803D03*
X526575Y1710590D03*
X534449Y1709803D03*
X518701Y1714527D03*
X534449D03*
X526575Y1720039D03*
X518701Y1723976D03*
X526575Y1724763D03*
X534449Y1723976D03*
X518701Y1728700D03*
X534449D03*
X526575Y1734212D03*
X550197Y1672007D03*
X542323Y1677519D03*
Y1682244D03*
X550197Y1681456D03*
Y1686180D03*
X542323Y1691692D03*
Y1696417D03*
X550197Y1695629D03*
Y1700354D03*
X542323Y1705866D03*
Y1710590D03*
X550197Y1709803D03*
Y1714527D03*
X542323Y1720039D03*
Y1724763D03*
X550197Y1723976D03*
Y1728700D03*
X542323Y1734212D03*
X562008Y1677519D03*
Y1682244D03*
Y1691692D03*
Y1696417D03*
Y1705866D03*
Y1710590D03*
Y1720039D03*
Y1724763D03*
Y1734212D03*
X569882Y1672007D03*
X577756Y1677519D03*
X569882Y1681456D03*
X577756Y1682244D03*
X569882Y1686180D03*
X577756Y1691692D03*
X569882Y1695629D03*
X577756Y1696417D03*
X569882Y1700354D03*
X577756Y1705866D03*
X569882Y1709803D03*
X577756Y1710590D03*
X569882Y1714527D03*
X577756Y1720039D03*
X569882Y1723976D03*
X577756Y1724763D03*
X569882Y1728700D03*
X577756Y1734212D03*
X585630Y1672007D03*
X593504Y1677519D03*
X585630Y1681456D03*
X593504Y1682244D03*
X585630Y1686180D03*
X593504Y1691692D03*
X585630Y1695629D03*
X593504Y1696417D03*
X585630Y1700354D03*
X593504Y1705866D03*
X585630Y1709803D03*
X593504Y1710590D03*
X585630Y1714527D03*
X593504Y1720039D03*
X585630Y1723976D03*
X593504Y1724763D03*
X585630Y1728700D03*
X593504Y1734212D03*
X601378Y1672007D03*
X609252Y1677519D03*
X601378Y1681456D03*
X609252Y1682244D03*
X601378Y1686180D03*
X609252Y1691692D03*
X601378Y1695629D03*
X609252Y1696417D03*
X601378Y1700354D03*
X609252Y1705866D03*
X601378Y1709803D03*
X609252Y1710590D03*
X601378Y1714527D03*
X609252Y1720039D03*
X601378Y1723976D03*
X609252Y1724763D03*
X601378Y1728700D03*
X609252Y1734212D03*
X617126Y1672007D03*
Y1681456D03*
Y1686180D03*
Y1695629D03*
Y1700354D03*
Y1709803D03*
Y1714527D03*
Y1723976D03*
Y1728700D03*
X1246654Y1672007D03*
X1238780Y1677519D03*
Y1682244D03*
X1246654Y1681456D03*
Y1686180D03*
X1238780Y1691692D03*
Y1696417D03*
X1246654Y1695629D03*
Y1700354D03*
X1238780Y1705866D03*
Y1710590D03*
X1246654Y1709803D03*
Y1714527D03*
X1238780Y1720039D03*
Y1724763D03*
X1246654Y1723976D03*
Y1728700D03*
X1238780Y1734212D03*
X1262402Y1672007D03*
X1254528Y1677519D03*
Y1682244D03*
X1262402Y1681456D03*
Y1686180D03*
X1254528Y1691692D03*
Y1696417D03*
X1262402Y1695629D03*
Y1700354D03*
X1254528Y1705866D03*
Y1710590D03*
X1262402Y1709803D03*
Y1714527D03*
X1254528Y1720039D03*
Y1724763D03*
X1262402Y1723976D03*
Y1728700D03*
X1254528Y1734212D03*
X1278150Y1672007D03*
X1270276Y1677519D03*
Y1682244D03*
X1278150Y1681456D03*
Y1686180D03*
X1270276Y1691692D03*
Y1696417D03*
X1278150Y1695629D03*
Y1700354D03*
X1270276Y1705866D03*
Y1710590D03*
X1278150Y1709803D03*
Y1714527D03*
X1270276Y1720039D03*
Y1724763D03*
X1278150Y1723976D03*
Y1728700D03*
X1270276Y1734212D03*
X1293898Y1672007D03*
X1286024Y1677519D03*
Y1682244D03*
X1293898Y1681456D03*
Y1686180D03*
X1286024Y1691692D03*
Y1696417D03*
X1293898Y1695629D03*
Y1700354D03*
X1286024Y1705866D03*
Y1710590D03*
X1293898Y1709803D03*
Y1714527D03*
X1286024Y1720039D03*
Y1724763D03*
X1293898Y1723976D03*
Y1728700D03*
X1286024Y1734212D03*
X1313583Y1672007D03*
X1305709Y1677519D03*
Y1682244D03*
X1313583Y1681456D03*
Y1686180D03*
X1305709Y1691692D03*
Y1696417D03*
X1313583Y1695629D03*
Y1700354D03*
X1305709Y1705866D03*
Y1710590D03*
X1313583Y1709803D03*
Y1714527D03*
X1305709Y1720039D03*
Y1724763D03*
X1313583Y1723976D03*
Y1728700D03*
X1305709Y1734212D03*
X1329331Y1672007D03*
X1321457Y1677519D03*
Y1682244D03*
X1329331Y1681456D03*
Y1686180D03*
X1321457Y1691692D03*
Y1696417D03*
X1329331Y1695629D03*
Y1700354D03*
X1321457Y1705866D03*
Y1710590D03*
X1329331Y1709803D03*
Y1714527D03*
X1321457Y1720039D03*
Y1724763D03*
X1329331Y1723976D03*
Y1728700D03*
X1321457Y1734212D03*
X1345079Y1672007D03*
X1337205Y1677519D03*
Y1682244D03*
X1345079Y1681456D03*
Y1686180D03*
X1337205Y1691692D03*
Y1696417D03*
X1345079Y1695629D03*
Y1700354D03*
X1337205Y1705866D03*
Y1710590D03*
X1345079Y1709803D03*
Y1714527D03*
X1337205Y1720039D03*
Y1724763D03*
X1345079Y1723976D03*
Y1728700D03*
X1337205Y1734212D03*
X1360827Y1672007D03*
X1352953Y1677519D03*
Y1682244D03*
X1360827Y1681456D03*
Y1686180D03*
X1352953Y1691692D03*
Y1696417D03*
X1360827Y1695629D03*
Y1700354D03*
X1352953Y1705866D03*
Y1710590D03*
X1360827Y1709803D03*
Y1714527D03*
X1352953Y1720039D03*
Y1724763D03*
X1360827Y1723976D03*
Y1728700D03*
X1352953Y1734212D03*
X1510827Y1672007D03*
X1502953Y1677519D03*
Y1682244D03*
X1510827Y1681456D03*
Y1686180D03*
X1502953Y1691692D03*
Y1696417D03*
X1510827Y1695629D03*
Y1700354D03*
X1502953Y1705866D03*
Y1710590D03*
X1510827Y1709803D03*
Y1714527D03*
X1502953Y1720039D03*
Y1724763D03*
X1510827Y1723976D03*
Y1728700D03*
X1502953Y1734212D03*
X1526575Y1672007D03*
X1518701Y1677519D03*
Y1682244D03*
X1526575Y1681456D03*
Y1686180D03*
X1518701Y1691692D03*
Y1696417D03*
X1526575Y1695629D03*
Y1700354D03*
X1518701Y1705866D03*
Y1710590D03*
X1526575Y1709803D03*
Y1714527D03*
X1518701Y1720039D03*
Y1724763D03*
X1526575Y1723976D03*
Y1728700D03*
X1518701Y1734212D03*
X1542323Y1672007D03*
X1534449Y1677519D03*
Y1682244D03*
X1542323Y1681456D03*
Y1686180D03*
X1534449Y1691692D03*
Y1696417D03*
X1542323Y1695629D03*
Y1700354D03*
X1534449Y1705866D03*
Y1710590D03*
X1542323Y1709803D03*
Y1714527D03*
X1534449Y1720039D03*
Y1724763D03*
X1542323Y1723976D03*
Y1728700D03*
X1534449Y1734212D03*
X1558071Y1672007D03*
X1550197Y1677519D03*
Y1682244D03*
X1558071Y1681456D03*
Y1686180D03*
X1550197Y1691692D03*
Y1696417D03*
X1558071Y1695629D03*
Y1700354D03*
X1550197Y1705866D03*
Y1710590D03*
X1558071Y1709803D03*
Y1714527D03*
X1550197Y1720039D03*
Y1724763D03*
X1558071Y1723976D03*
Y1728700D03*
X1550197Y1734212D03*
X1569882Y1677519D03*
Y1682244D03*
Y1691692D03*
Y1696417D03*
Y1705866D03*
Y1710590D03*
Y1720039D03*
Y1724763D03*
Y1734212D03*
X1577756Y1672007D03*
X1585630Y1677519D03*
X1577756Y1681456D03*
X1585630Y1682244D03*
X1577756Y1686180D03*
X1585630Y1691692D03*
X1577756Y1695629D03*
X1585630Y1696417D03*
X1577756Y1700354D03*
X1585630Y1705866D03*
X1577756Y1709803D03*
X1585630Y1710590D03*
X1577756Y1714527D03*
X1585630Y1720039D03*
X1577756Y1723976D03*
X1585630Y1724763D03*
X1577756Y1728700D03*
X1585630Y1734212D03*
X1593504Y1672007D03*
X1601378Y1677519D03*
X1593504Y1681456D03*
X1601378Y1682244D03*
X1593504Y1686180D03*
X1601378Y1691692D03*
X1593504Y1695629D03*
X1601378Y1696417D03*
X1593504Y1700354D03*
X1601378Y1705866D03*
X1593504Y1709803D03*
X1601378Y1710590D03*
X1593504Y1714527D03*
X1601378Y1720039D03*
X1593504Y1723976D03*
X1601378Y1724763D03*
X1593504Y1728700D03*
X1601378Y1734212D03*
X1609252Y1672007D03*
X1617126Y1677519D03*
X1609252Y1681456D03*
X1617126Y1682244D03*
X1609252Y1686180D03*
X1617126Y1691692D03*
X1609252Y1695629D03*
X1617126Y1696417D03*
X1609252Y1700354D03*
X1617126Y1705866D03*
X1609252Y1709803D03*
X1617126Y1710590D03*
X1609252Y1714527D03*
X1617126Y1720039D03*
X1609252Y1723976D03*
X1617126Y1724763D03*
X1609252Y1728700D03*
X1617126Y1734212D03*
X1625000Y1672007D03*
Y1681456D03*
Y1686180D03*
Y1695629D03*
Y1700354D03*
Y1709803D03*
Y1714527D03*
Y1723976D03*
Y1728700D03*
G54D75*
X1886720Y1001463D03*
X1876720D03*
X1875836Y1303980D03*
X1885836D03*
X1886211Y1364167D03*
X1876211D03*
X1876165Y1669023D03*
X1886165D03*
X1897608Y1001506D03*
X1898086Y1305044D03*
X1897682Y1364479D03*
X1897402Y1670072D03*
X1907608Y1001506D03*
X1908086Y1305044D03*
X1907682Y1364479D03*
X1907402Y1670072D03*
X1935200Y1362732D03*
X1925200D03*
X1924695Y1670036D03*
X1934695D03*
X1946178Y1362781D03*
X1945484Y1670313D03*
X1967697Y1362790D03*
X1956178Y1362781D03*
X1966555Y1669946D03*
X1955484Y1670313D03*
X1977697Y1362790D03*
X1976555Y1669946D03*
X1988618Y1363081D03*
X1998618D03*
X1998147Y1669691D03*
X1988147D03*
G54D22*
X45812Y451602D03*
X61157Y69340D03*
X61470Y84622D03*
X49212Y451602D03*
X64557Y69340D03*
X72157Y75340D03*
X75557D03*
X64870Y84622D03*
X78120Y1515436D03*
Y1518836D03*
X64410Y1599102D03*
Y1602502D03*
X86557Y69340D03*
X83157D03*
X94157Y75340D03*
X90998Y1518937D03*
Y1515537D03*
X108557Y69340D03*
X105157D03*
X97557Y75340D03*
X127157Y69340D03*
X116157Y75340D03*
X119557D03*
X130557Y69340D03*
X138157Y75340D03*
X141557D03*
X152557Y69340D03*
X149157D03*
X175761D03*
X172361D03*
X161361Y75340D03*
X164761D03*
X183361D03*
X186761D03*
X197761Y69340D03*
X194361D03*
X205495Y75340D03*
X208895D03*
X194197Y1602380D03*
X197597D03*
X206257D03*
X219895Y69340D03*
X216495D03*
X209657Y1602380D03*
X218317D03*
X221717D03*
X227495Y75340D03*
X230895D03*
X230377Y1602380D03*
X233777D03*
X242437D03*
X254497D03*
X245837D03*
X266557D03*
X257897D03*
X269957D03*
X278617D03*
X282017D03*
X290677D03*
X302737D03*
X294077D03*
X306137D03*
X314797D03*
X318197D03*
X330257D03*
X338917D03*
X326857D03*
X350977D03*
X342317D03*
X354377D03*
X363037D03*
X366437D03*
X375097D03*
X378497D03*
X478351D03*
X481751D03*
X490411D03*
X493811D03*
X514531D03*
X502471D03*
X517931D03*
X505871D03*
X519764Y40328D03*
X523164D03*
X519742Y71436D03*
X523142D03*
X526591Y1602380D03*
X529991D03*
X538651D03*
X542051D03*
X562771D03*
X550711D03*
X566171D03*
X554111D03*
X574831D03*
X578231D03*
X598951D03*
X586891D03*
X590291D03*
X611011D03*
X614411D03*
X602351D03*
X623071D03*
X626471D03*
X647191D03*
X635131D03*
X638531D03*
X662651D03*
X659251D03*
X650591D03*
X723041Y-19800D03*
Y-23200D03*
X840001Y6800D03*
Y10200D03*
X953970Y208275D03*
X947496Y215397D03*
X953970Y204875D03*
X947496Y211997D03*
X957156Y227163D03*
X947496Y226135D03*
X957156Y230563D03*
X947496Y229535D03*
X980899Y-19800D03*
Y-23200D03*
Y6800D03*
Y10200D03*
X1032433Y-29811D03*
Y-33211D03*
Y-23211D03*
Y-19811D03*
Y-13211D03*
Y-9811D03*
Y-3211D03*
Y189D03*
X1156770Y638192D03*
X1153370D03*
X1161860Y642112D03*
X1165260D03*
X1173220Y636052D03*
X1169820D03*
X1183360Y642062D03*
X1186760D03*
X1196772Y1578182D03*
X1200172D03*
X1212232D03*
X1208832D03*
X1220892D03*
X1232952D03*
X1224292D03*
X1245012D03*
X1236352D03*
X1248412D03*
X1257072D03*
X1260472D03*
X1269132D03*
X1281192D03*
X1272532D03*
X1290291Y-29811D03*
Y-33211D03*
Y-23211D03*
Y-19811D03*
Y-13211D03*
Y-9811D03*
Y-3211D03*
Y189D03*
X1293252Y1578182D03*
X1284592D03*
X1296652D03*
X1307677Y322996D03*
X1311077D03*
X1305312Y1578182D03*
X1308712D03*
X1319618Y318073D03*
X1325080Y323902D03*
X1316218Y318073D03*
X1328480Y323902D03*
X1317372Y1578182D03*
X1320772D03*
X1329432D03*
X1341752Y-29811D03*
Y-33211D03*
Y-19811D03*
Y-23211D03*
Y-9811D03*
Y-13211D03*
Y189D03*
Y-3211D03*
X1335145Y332616D03*
X1341431Y322693D03*
X1331745Y332616D03*
X1338031Y322693D03*
X1345424Y328981D03*
X1332832Y1578182D03*
X1341492D03*
X1344892D03*
X1348824Y328981D03*
X1358371Y332275D03*
X1361771D03*
X1355200Y337843D03*
X1351800D03*
X1353552Y1578182D03*
X1356952D03*
X1365612D03*
X1377672D03*
X1369012D03*
X1381072D03*
X1412284Y171696D03*
X1407420Y220018D03*
X1410820D03*
X1404385Y240929D03*
X1400985D03*
X1415684Y171696D03*
X1467595Y1602380D03*
X1470995D03*
X1482650Y-29811D03*
Y-33211D03*
Y-19811D03*
Y-23211D03*
Y-9811D03*
Y-13211D03*
Y189D03*
Y-3211D03*
X1491715Y1602380D03*
X1479655D03*
X1483055D03*
X1503775D03*
X1507175D03*
X1495115D03*
X1515835D03*
X1519235D03*
X1538996Y69297D03*
X1535596D03*
X1527895Y1602380D03*
X1539955D03*
X1531295D03*
X1557596Y69297D03*
X1546596Y75297D03*
X1549996D03*
X1552015Y1602380D03*
X1555415D03*
X1543355D03*
X1560996Y69297D03*
X1568596Y75297D03*
X1571996D03*
X1564075Y1602380D03*
X1567475D03*
X1582996Y69297D03*
X1579596D03*
X1590596Y75297D03*
X1588195Y1602380D03*
X1576135D03*
X1591595D03*
X1579535D03*
X1604996Y69297D03*
X1601596D03*
X1593996Y75297D03*
X1600255Y1602380D03*
X1603655D03*
X1623596Y69297D03*
X1612596Y75297D03*
X1615996D03*
X1612315Y1602380D03*
X1615715D03*
X1626996Y69297D03*
X1635800Y75297D03*
X1639200D03*
X1636435Y1602380D03*
X1624375D03*
X1639835D03*
X1627775D03*
X1650200Y69297D03*
X1646800D03*
X1651895Y1602380D03*
X1648495D03*
X1672200Y69297D03*
X1668800D03*
X1657800Y75297D03*
X1661200D03*
X1679934D03*
X1683334D03*
X1694334Y69297D03*
X1690934D03*
X1705334Y75297D03*
X1701934D03*
G54D40*
X338042Y849978D03*
X331284Y978814D03*
X338211Y1118243D03*
X336361Y1121447D03*
X338211Y1131060D03*
X345178Y854584D03*
X350727Y851380D03*
X354427Y844971D03*
X348878Y848176D03*
X352578D03*
X348879Y860993D03*
X350729Y870606D03*
X354429D03*
X352578Y873810D03*
X354429Y883423D03*
X348879Y873810D03*
X347029Y877014D03*
X348878Y880219D03*
X343761Y999684D03*
X349311Y1105426D03*
X341911D03*
X343762Y1108630D03*
X345611Y1111834D03*
X351161Y1102221D03*
X349312Y1111834D03*
X353011Y1105426D03*
X345611D03*
X341912Y1111834D03*
X354861Y1102221D03*
X353012Y1111834D03*
X351162Y1108630D03*
Y1127856D03*
X353011Y1118243D03*
X354861Y1121447D03*
X347461Y1115039D03*
X341912Y1118243D03*
X340061Y1127856D03*
X343761D03*
X347461Y1121447D03*
X340061D03*
X343761D03*
X347461Y1127856D03*
X345611Y1124651D03*
X347461Y1134264D03*
X354861D03*
X341911Y1131060D03*
X356278Y848176D03*
X371078D03*
X363678D03*
X356279Y841467D03*
X361827Y844971D03*
X363679Y841467D03*
X369227Y844971D03*
X371079Y841467D03*
X358127Y844971D03*
X359978Y848176D03*
X365527Y844971D03*
X367378Y848176D03*
X371078Y867401D03*
X356278D03*
X363678D03*
X356278Y860993D03*
X371078D03*
X363678D03*
X358129Y870606D03*
X361829D03*
X365529D03*
X359978Y873810D03*
X367378D03*
X369229Y870606D03*
X356278Y880219D03*
X358129Y883423D03*
X363678Y880219D03*
X365529Y883423D03*
X371078Y880219D03*
X361829Y883423D03*
X369229D03*
X371078Y873810D03*
X356278D03*
X363678D03*
X371078Y893036D03*
X363679D03*
X367379D03*
X359978Y886627D03*
X367378D03*
X363678D03*
X371078D03*
X367811Y1002888D03*
Y1105426D03*
X369661Y1102221D03*
X358562D03*
X360412Y1105426D03*
X358561Y1108630D03*
X360412Y1111834D03*
X364112Y1105426D03*
X369661Y1108630D03*
X362261D03*
X365961D03*
X367812Y1111834D03*
X369662Y1121447D03*
X362261D03*
X365961Y1115039D03*
X358561D03*
X369661D03*
X369662Y1134264D03*
X362262D03*
X385878Y848176D03*
X378478D03*
X387727Y844971D03*
X376627D03*
X380327D03*
X384027D03*
X385879Y841467D03*
X372927Y844971D03*
X374778Y848176D03*
X378479Y841467D03*
X382178Y848176D03*
X378478Y867401D03*
X385878D03*
X378478Y860993D03*
X385878D03*
X387729Y870606D03*
X372929D03*
X380329D03*
X374778Y873810D03*
X376629Y870606D03*
X382178Y873810D03*
X384029Y870606D03*
X372929Y883423D03*
X378478Y880219D03*
X380329Y883423D03*
X385878Y880219D03*
X387729Y883423D03*
X376629D03*
X384029D03*
X378478Y873810D03*
X385878D03*
X374778Y899445D03*
X382178D03*
Y893036D03*
X374778D03*
X385878D03*
X372929Y896240D03*
X380329D03*
X376629D03*
X384029D03*
X374778Y886627D03*
X382178D03*
X378478D03*
X385878D03*
X376629Y902649D03*
X380329D03*
X374778Y912262D03*
X376629Y909057D03*
X382178Y912262D03*
X380329Y909057D03*
X387729D03*
Y902649D03*
X372929Y915466D03*
X385878Y905853D03*
X380329Y915466D03*
X376629D03*
X384029D03*
X374778Y931488D03*
X376629Y928283D03*
X382178Y931488D03*
X380329Y928283D03*
X387729Y921875D03*
X376629D03*
X374778Y918670D03*
X380329Y921875D03*
X382178Y918670D03*
X387729Y928283D03*
X385878Y925079D03*
X380329Y941100D03*
X382178Y937896D03*
X376629Y947509D03*
X380329D03*
X376629Y941100D03*
X374778Y937896D03*
X372929Y934691D03*
X380329D03*
X376629D03*
X384029D03*
X387729Y947509D03*
Y941100D03*
X385878Y944304D03*
X376629Y960326D03*
X374778Y957122D03*
X380329Y960326D03*
X382178Y957122D03*
X374778Y950713D03*
X382178D03*
X372929Y953917D03*
X380329D03*
X376629D03*
X384029D03*
X387729Y960326D03*
Y966735D03*
X380329D03*
X376629D03*
X385878Y963530D03*
Y982756D03*
X387729Y979552D03*
X376629D03*
X380329D03*
X374778Y976347D03*
X382178D03*
X372929Y973143D03*
X374778Y969939D03*
X382178D03*
X384029Y973143D03*
X375211Y1002888D03*
X377062Y999684D03*
X382611Y1002888D03*
X380762Y999684D03*
X377062Y1012501D03*
X375211Y1009297D03*
X380762Y1012501D03*
X382611Y1009297D03*
X377062Y1031727D03*
X375211Y1028523D03*
X380762Y1031727D03*
X382611Y1028523D03*
X375211Y1022114D03*
X377062Y1018910D03*
X382611Y1022114D03*
X380762Y1018910D03*
X377062Y1025318D03*
X384462D03*
X373360D03*
X380760D03*
X386311Y1015705D03*
X375211Y1047749D03*
X382611D03*
X375211Y1041340D03*
X377062Y1038136D03*
X382611Y1041340D03*
X380762Y1038136D03*
X373362Y1044544D03*
X380762D03*
X377062D03*
X384462D03*
X386311Y1034931D03*
X375211Y1060565D03*
X377062Y1057361D03*
X382611Y1060565D03*
X380762Y1057361D03*
X377062Y1050952D03*
X380762D03*
X373362Y1063770D03*
X384462D03*
X377062D03*
X380762D03*
X386311Y1054157D03*
X380762Y1070178D03*
X382611Y1066974D03*
X377062Y1070178D03*
X375211Y1066974D03*
Y1079791D03*
X377062Y1076587D03*
X382611Y1079791D03*
X380762Y1076587D03*
X386311Y1073383D03*
X377062Y1089404D03*
X375211Y1086200D03*
X380762Y1089404D03*
X382611Y1086200D03*
X373362Y1082995D03*
X386311Y1092608D03*
X384462Y1082995D03*
X377062D03*
X380762D03*
X375211Y1099017D03*
X380762Y1095813D03*
X382611Y1099017D03*
X386311Y1105426D03*
X382611Y1111834D03*
X375211Y1105426D03*
X377062Y1108630D03*
X380762Y1102221D03*
X378911Y1111834D03*
X384462Y1108630D03*
X386311Y1111834D03*
X378912Y1105426D03*
X375211Y1111834D03*
X382611Y1105426D03*
X384462Y1121447D03*
X377062D03*
X380762Y1115039D03*
X384462Y1134264D03*
X377062D03*
X400678Y848176D03*
X393278D03*
X391427Y844971D03*
X395127D03*
X398827D03*
X400679Y841467D03*
X389578Y848176D03*
X393279Y841467D03*
X396978Y848176D03*
X402527Y844971D03*
X400678Y867401D03*
X393278D03*
X400678Y860993D03*
X393278D03*
X391429Y870606D03*
X395129D03*
X402529D03*
X389578Y873810D03*
X396978D03*
X398829Y870606D03*
X393278Y880219D03*
X395129Y883423D03*
X400678Y880219D03*
X402529Y883423D03*
X391429D03*
X398829D03*
X393278Y873810D03*
X400678D03*
X402529Y896240D03*
X400678Y899445D03*
X389578D03*
X393278D03*
X393279Y893036D03*
X396979D03*
X396978Y886627D03*
X389578D03*
X398829Y896240D03*
X400678Y893036D03*
X393278Y886627D03*
X400678D03*
X404378Y899445D03*
X400678Y905853D03*
X402529Y915466D03*
Y909057D03*
X389578Y912262D03*
X393278D03*
X395129Y909057D03*
Y902649D03*
X393278Y905853D03*
X389578D03*
X396978D03*
X406229Y915466D03*
X400678Y912262D03*
X402529Y902649D03*
X400678Y931488D03*
X402529Y928283D03*
Y921875D03*
X393278Y931488D03*
X395129Y928283D03*
X389578Y918670D03*
X395129Y921875D03*
X393278Y918670D03*
X389578Y931488D03*
X393278Y925079D03*
X389578D03*
X396978D03*
X398829Y934691D03*
X402529D03*
X395129Y947509D03*
X389578Y937896D03*
X395129Y941100D03*
X393278Y937896D03*
Y944304D03*
X389578D03*
X396978D03*
X402529Y941100D03*
X400679Y944304D03*
X402529Y947509D03*
X389578Y957122D03*
X395129Y960326D03*
X393278Y957122D03*
X395129Y966735D03*
X389578Y950713D03*
X393278D03*
X396978Y963530D03*
X393278D03*
X389578D03*
X402529Y966735D03*
Y960326D03*
X398829Y953917D03*
X402529D03*
X400680Y950713D03*
X398829Y973143D03*
X400678Y976347D03*
X402529Y979552D03*
Y973143D03*
X393278Y982756D03*
X389578D03*
X396978D03*
X393278Y976347D03*
X395129Y979552D03*
X389579Y976347D03*
X389578Y969939D03*
X393278D03*
X399262Y1006093D03*
X402962D03*
X390011Y1002888D03*
X388162Y999684D03*
X393711Y1002888D03*
X395562Y999684D03*
X399262D03*
X402962D03*
X388162Y1012501D03*
X395562D03*
X390011Y1009297D03*
X393711D03*
X401111D03*
X402962Y1012501D03*
Y1031727D03*
X397411Y1015705D03*
X388162Y1031727D03*
X390011Y1028523D03*
X395562Y1031727D03*
X393711Y1028523D03*
X390011Y1022114D03*
X388162Y1018910D03*
X393711Y1022114D03*
X395562Y1018910D03*
X401111Y1028523D03*
Y1022114D03*
X402960Y1018910D03*
X402962Y1025318D03*
X399262D03*
X401111Y1015705D03*
X390011Y1041340D03*
X388162Y1038136D03*
X393711Y1041340D03*
X395562Y1038136D03*
X390011Y1047749D03*
X393711D03*
Y1034931D03*
X390011D03*
X397411D03*
X401111Y1047749D03*
X399262Y1044544D03*
X402962D03*
X401111Y1041340D03*
X402962Y1038136D03*
X406662Y1057361D03*
X390011Y1060565D03*
X388162Y1057361D03*
X393711Y1060565D03*
X395562Y1057361D03*
X388162Y1050952D03*
X395562D03*
X393711Y1054157D03*
X390011D03*
X397411D03*
X402962Y1057361D03*
Y1063770D03*
X401113Y1060565D03*
X399262Y1063770D03*
X401111Y1054157D03*
X402962Y1050952D03*
Y1076587D03*
Y1070178D03*
X390011Y1079791D03*
X388162Y1076587D03*
X393711Y1079791D03*
X395562Y1076587D03*
X388162Y1070178D03*
X390011Y1066974D03*
X395562Y1070178D03*
X393711Y1066974D03*
Y1073383D03*
X390011D03*
X397411D03*
X401112Y1066974D03*
X395562Y1095813D03*
X388162Y1089404D03*
X390011Y1086200D03*
X395562Y1089404D03*
X393711Y1086200D03*
X388162Y1095813D03*
X393711Y1092608D03*
X390011D03*
X397411D03*
X399262Y1082995D03*
X402962D03*
X402961Y1089404D03*
X393711Y1099017D03*
X390011D03*
X391862Y1102221D03*
X393711Y1105426D03*
X401111Y1099017D03*
X391862Y1108630D03*
X393711Y1111834D03*
X397411Y1105426D03*
X402962Y1108630D03*
Y1102221D03*
X395562Y1108630D03*
X399262D03*
X401111Y1111834D03*
X391862Y1121447D03*
X399262Y1115039D03*
X391862D03*
X402962D03*
X399262Y1121447D03*
X391862Y1134264D03*
X399262D03*
X408078Y848176D03*
X415478D03*
X406227Y844971D03*
X409927D03*
X413627D03*
X417327D03*
X404378Y848176D03*
X408079Y841467D03*
X411778Y848176D03*
X415479Y841467D03*
X419178Y848176D03*
X408078Y867401D03*
X415478D03*
Y860993D03*
X408078D03*
X404378Y873810D03*
X406229Y870606D03*
X408078Y880219D03*
X409929Y883423D03*
X406229D03*
X419178Y873810D03*
X417329Y870606D03*
X411778Y873810D03*
X413629Y870606D03*
X415478Y873810D03*
X408078D03*
X404378Y886627D03*
X411778D03*
X404378Y893036D03*
X415478Y886627D03*
X408078D03*
X406229Y896240D03*
X408078Y899445D03*
X415478D03*
X409929Y896240D03*
X415478Y893036D03*
X417329Y896240D03*
X422878Y893036D03*
X411778Y899445D03*
X413629Y896240D03*
X419178Y899445D03*
X422878Y912262D03*
X417329Y909057D03*
X406229D03*
X413629D03*
Y915466D03*
X411778Y905853D03*
X408078D03*
Y912262D03*
X406229Y902649D03*
X415478Y905853D03*
X411778Y912262D03*
X415478D03*
X417329Y915466D03*
X411779Y918670D03*
X406229Y921875D03*
X408078Y918670D03*
X408569Y929108D03*
X406308Y928626D03*
X417329Y921875D03*
X411872Y925264D03*
X415479Y918670D03*
X407589Y942164D03*
X405289D03*
X409889D03*
X415185Y956620D03*
X411685D03*
X409385D03*
X417685D03*
X404785Y971100D03*
X407085D03*
X409385D03*
X411685D03*
X420205D03*
X412365Y985610D03*
X410065D03*
X420145Y985550D03*
X409385Y1014540D03*
X407085D03*
X411685D03*
X412385Y1000080D03*
X410085D03*
X420215Y1000040D03*
X420405Y1014470D03*
X414461Y1028855D03*
X411961D03*
X416961D03*
X419461D03*
X415911Y1047749D03*
X419611D03*
X406662Y1044544D03*
X410362D03*
X408511Y1047749D03*
X414062Y1044544D03*
X404811Y1041340D03*
X412211D03*
X415911D03*
X419611D03*
X406662Y1050952D03*
X414060D03*
X417762Y1057361D03*
X421462Y1050952D03*
X419611Y1054157D03*
X406662Y1063770D03*
X408511Y1060565D03*
X410362Y1063770D03*
X412211Y1054157D03*
X404811D03*
X414062Y1057361D03*
X410362D03*
X417762Y1063770D03*
X414062D03*
X419611Y1060565D03*
Y1079791D03*
X408511Y1073383D03*
X406662Y1070178D03*
X404811Y1073383D03*
X417762Y1076587D03*
X408511Y1066974D03*
X415911Y1079791D03*
X412211Y1073383D03*
X415911D03*
X414062Y1070178D03*
X417762D03*
X412211Y1066974D03*
X419611D03*
X408511Y1079791D03*
X419612Y1099017D03*
X404811Y1092608D03*
X417762Y1095813D03*
X414061D03*
X406662Y1089404D03*
X410362D03*
X404811Y1086200D03*
X419611D03*
X414062Y1082995D03*
X410362D03*
X406662D03*
X408511Y1092608D03*
X414062Y1089404D03*
X419611Y1092608D03*
X412211Y1086200D03*
X404811Y1099017D03*
X408511Y1105426D03*
X412211Y1111834D03*
X415911D03*
X414062Y1102221D03*
X417762Y1108630D03*
X419611Y1105426D03*
X408511Y1099017D03*
X410362Y1108630D03*
X408511Y1111834D03*
X412211Y1105426D03*
X419611Y1111834D03*
X415911Y1105426D03*
X415912Y1124651D03*
X419612D03*
Y1118243D03*
X417761Y1121447D03*
Y1127856D03*
X414062Y1115039D03*
X406661Y1121447D03*
X414062Y1127856D03*
X406662Y1134264D03*
X415912Y1137469D03*
Y1131060D03*
X414061Y1140973D03*
X419612Y1137469D03*
Y1131060D03*
X417761Y1134264D03*
Y1140973D03*
X412212Y1137469D03*
X422878Y848176D03*
X421027Y844971D03*
X424727D03*
X428427D03*
X433978Y848176D03*
X435829Y844671D03*
X422879Y841467D03*
X426578Y848176D03*
X430278D03*
Y867401D03*
X422878D03*
X430278Y860993D03*
X422878D03*
X432129Y870606D03*
X426578Y873810D03*
X424729Y870606D03*
X433979Y873810D03*
X428429Y870606D03*
X421029D03*
X435829D03*
X422878Y873810D03*
X430278D03*
X422878Y886627D03*
X430278D03*
Y899445D03*
X422878D03*
X424729Y896240D03*
X430278Y893036D03*
X432129Y896240D03*
X437678Y893036D03*
X421029Y896240D03*
X426578Y899445D03*
X428429Y896240D03*
X433978Y899445D03*
X435829Y896240D03*
X424729Y915466D03*
X426578Y912262D03*
X430278D03*
X432129Y915466D03*
X421029Y909057D03*
X435829D03*
Y915466D03*
X432128Y909057D03*
X433978Y905853D03*
X424728Y909057D03*
X422878Y905853D03*
X430278D03*
X426578D03*
X421029Y915466D03*
X433979Y912262D03*
X430278Y918670D03*
X432129Y921875D03*
X433979Y918670D03*
X435829Y921875D03*
X424927Y927255D03*
X423176Y929465D03*
X422427Y927255D03*
X425676Y929465D03*
X424729Y921875D03*
X422878Y918670D03*
X421029Y921875D03*
X426578Y918670D03*
X430279Y925079D03*
X432130Y928283D03*
X430279Y931487D03*
X432130Y934692D03*
X435830Y928283D03*
X427875Y941930D03*
Y944230D03*
X430280Y944305D03*
X432130Y941101D03*
X435830D03*
X432129Y947510D03*
X435830D03*
Y934692D03*
X427875Y956373D03*
Y954073D03*
X422685Y956620D03*
X425185D03*
X430280Y957123D03*
X432129Y960327D03*
Y953918D03*
X430280Y950714D03*
X435830Y960327D03*
Y953918D03*
X432129Y966736D03*
X430280Y963531D03*
X435830Y966736D03*
X430268Y976348D03*
X432129Y973144D03*
X430280Y969940D03*
X427875Y971267D03*
X422685Y971100D03*
X427875Y968967D03*
X435830Y973144D03*
X430280Y982757D03*
X432129Y979553D03*
X427875Y983111D03*
X435830Y979553D03*
X422685Y985580D03*
X427875Y985411D03*
Y997521D03*
X430712Y1009298D03*
X427875Y1012152D03*
X430712Y1002889D03*
X427875Y999821D03*
X422685Y1000060D03*
X436263Y1006094D03*
Y999685D03*
X432562Y1006094D03*
Y999685D03*
X427875Y1014452D03*
X423015Y1014470D03*
X436263Y1012502D03*
X432562D03*
X421961Y1028855D03*
X430712Y1022115D03*
Y1015706D03*
X427875Y1026704D03*
X430712Y1028524D03*
X436263Y1018911D03*
X432562D03*
Y1025319D03*
X436263D03*
X427875Y1029004D03*
Y1031304D03*
X436263Y1031728D03*
X432562D03*
X427011Y1047749D03*
X427012Y1041340D03*
X423312D03*
X425162Y1044544D03*
X423285Y1036884D03*
X430711Y1041340D03*
X430712Y1034932D03*
X427875Y1033604D03*
X423285Y1032284D03*
Y1034584D03*
X436262Y1038137D03*
X436261Y1044544D03*
X432562Y1038137D03*
X434412Y1041340D03*
X432561Y1044544D03*
X434412Y1047749D03*
X421462Y1044544D03*
X427011Y1054157D03*
X430711D03*
X428861Y1057361D03*
X432561D03*
X421462D03*
X425162Y1050952D03*
X423311Y1054157D03*
X428862Y1050952D03*
X436262Y1057361D03*
Y1050952D03*
Y1063770D03*
X425162D03*
X423311Y1060565D03*
X427011D03*
X428861Y1063770D03*
X430711Y1060565D03*
X423311Y1073383D03*
X432560Y1070178D03*
X421462Y1076587D03*
X423311Y1079791D03*
X436262Y1070178D03*
Y1076587D03*
X421462Y1070178D03*
X425162D03*
X428862D03*
X430711Y1066974D03*
X428861Y1076587D03*
X430711Y1079791D03*
X436262Y1082995D03*
Y1089404D03*
X436261Y1095813D03*
X421462Y1089404D03*
X423311Y1092608D03*
X427011D03*
X430710Y1086200D03*
X425162Y1082995D03*
Y1095813D03*
X430711Y1092608D03*
X423311Y1086200D03*
X428861Y1089404D03*
X427012Y1086200D03*
X421462Y1102221D03*
X423311Y1099017D03*
X428861Y1108630D03*
X427012Y1105426D03*
X425162Y1108630D03*
X430711Y1105426D03*
Y1099017D03*
X428861Y1102221D03*
X436262Y1108630D03*
Y1102221D03*
X432561Y1108630D03*
Y1102221D03*
X434412Y1099017D03*
X430711Y1111834D03*
X427012D03*
X430711Y1124651D03*
X428861Y1121447D03*
X427012Y1124651D03*
X425162Y1121447D03*
X421461D03*
X430711Y1118243D03*
X428861Y1115039D03*
X427012Y1118243D03*
X425162Y1115039D03*
X436262Y1121447D03*
Y1115039D03*
X432561Y1121447D03*
Y1115039D03*
X428861Y1127856D03*
X425162D03*
X421461D03*
X436262D03*
X432561D03*
X430711Y1137769D03*
X427012Y1137569D03*
X430711Y1131060D03*
X428861Y1134264D03*
X427012Y1131060D03*
X425162Y1134264D03*
X421461D03*
X428861Y1140973D03*
X425161D03*
X421461D03*
X436261Y1134264D03*
X432561D03*
X450628Y844971D03*
X446927Y844671D03*
X452479Y841467D03*
X448778Y848176D03*
X443227Y844671D03*
X437678Y848176D03*
X452478Y867401D03*
X445078D03*
X437678D03*
X445078Y860993D03*
X452479D03*
X448779Y873810D03*
X446929Y870606D03*
X441378Y873810D03*
X439529Y870606D03*
X450629D03*
X443229D03*
X437679Y873810D03*
X452479D03*
X445078D03*
X452478Y886627D03*
X445078D03*
X452478Y899445D03*
X441378D03*
X445078Y893036D03*
X446929Y896240D03*
X452479Y893036D03*
X445078Y899445D03*
X443229Y896240D03*
X448778Y899445D03*
X450630Y896240D03*
X443229Y909057D03*
X439529Y915466D03*
X445079Y905853D03*
X441379D03*
X450630Y909057D03*
X452479Y905853D03*
X448779D03*
X448780Y912262D03*
X441380D03*
X439529Y909057D03*
X445080Y912262D03*
X443229Y915466D03*
X450629D03*
X452478Y912262D03*
X448779Y918670D03*
X454329Y915466D03*
X439529Y921875D03*
X441378Y918670D03*
X450629Y921875D03*
X445078Y918670D03*
X443229Y921875D03*
X452478Y918670D03*
X446930Y934692D03*
X443230Y928283D03*
X448780Y931487D03*
X437679D03*
X450630Y928283D03*
X448780Y925079D03*
X445079Y931487D03*
X439530Y934692D03*
X445079Y925079D03*
X439530Y928283D03*
X437679Y925079D03*
X437680Y944305D03*
X441380D03*
X443230Y941101D03*
X445079Y944305D03*
X439530Y941101D03*
X450630D03*
X448780Y944305D03*
X443229Y947510D03*
X439529D03*
X450630D03*
X443230Y934692D03*
X445079Y957123D03*
X437680D03*
X441380D03*
X439529Y960327D03*
X443229D03*
Y953918D03*
X439529D03*
X437680Y950714D03*
X441380D03*
X445079D03*
X448780Y957123D03*
X450630Y953918D03*
Y960327D03*
X448780Y950714D03*
X445079Y963531D03*
X437680D03*
X441380D03*
X439529Y966736D03*
X443229D03*
X448780Y963531D03*
X450630Y966736D03*
X445079Y976348D03*
Y969940D03*
X439529Y973144D03*
X443229D03*
X437680Y976348D03*
X441380D03*
X437680Y969940D03*
X441380D03*
X450630Y973144D03*
X448780Y976348D03*
Y969940D03*
X445079Y982757D03*
X437680D03*
X441380D03*
X439529Y979553D03*
X443229D03*
X448780Y982757D03*
X450630Y979553D03*
X439962Y1006094D03*
X443662D03*
X445511Y1009298D03*
X438113D03*
X441813D03*
X445512Y1002889D03*
X438113D03*
X441813D03*
X439962Y999685D03*
X443662D03*
X451062Y1006094D03*
X449213Y1009298D03*
Y1002889D03*
X451062Y999685D03*
X439962Y1012502D03*
X443662D03*
X451062D03*
X445511Y1022115D03*
X438113D03*
X441813D03*
X445512Y1015706D03*
X438113D03*
X439962Y1018911D03*
X441813Y1015706D03*
X443662Y1018911D03*
Y1025319D03*
X439962D03*
X445511Y1028524D03*
X441813D03*
X438113D03*
X449213Y1022115D03*
X451062Y1018911D03*
X449213Y1015706D03*
X451062Y1025319D03*
X449213Y1028524D03*
X439962Y1031728D03*
X443662D03*
X451062D03*
X452911Y1047749D03*
X439962Y1038137D03*
X443662D03*
X438112Y1041340D03*
X439961Y1044544D03*
X441812Y1041340D03*
X443661Y1044544D03*
X447361D03*
X445511Y1041340D03*
X445512Y1034932D03*
X438113D03*
X441813D03*
X451062Y1038137D03*
X449211Y1041340D03*
X449213Y1034932D03*
X445510Y1047749D03*
X441812D03*
X438112D03*
X449211Y1054157D03*
X449213Y1060565D03*
X438112D03*
Y1054157D03*
X439961Y1057361D03*
X441812Y1054157D03*
Y1060565D03*
X443661Y1057361D03*
X445511Y1060565D03*
Y1054157D03*
X439961Y1050952D03*
X443661D03*
X439961Y1063770D03*
X443661D03*
X451061D03*
X452911Y1054157D03*
X451062Y1050952D03*
X454762D03*
Y1057361D03*
X451062D03*
X451061Y1076587D03*
X452911Y1073383D03*
X439961Y1076587D03*
Y1070178D03*
X441812Y1073383D03*
X438112D03*
X443661Y1070178D03*
Y1076587D03*
X445511Y1073383D03*
X441812Y1066974D03*
X438112D03*
X445511D03*
X441812Y1079791D03*
X438112D03*
X445511D03*
X452911Y1066974D03*
X449211D03*
X451062Y1070178D03*
X452911Y1086200D03*
X443661Y1082995D03*
X439961D03*
X441812Y1086200D03*
X445511D03*
X439961Y1089404D03*
X441812Y1092608D03*
X438112D03*
X443661Y1089404D03*
X445511Y1092608D03*
X447361Y1089404D03*
X438112Y1086200D03*
X449211Y1092608D03*
X439961Y1095813D03*
X443661D03*
X447361D03*
X451060Y1082995D03*
X441812Y1105426D03*
X438112D03*
X439961Y1108630D03*
X443661D03*
X445511Y1105426D03*
X439961Y1102221D03*
X441812Y1099017D03*
X438112D03*
X443661Y1102221D03*
X445511Y1099017D03*
X452912Y1105426D03*
X451061Y1108630D03*
X449212Y1105426D03*
X451061Y1102221D03*
X449212Y1099017D03*
X441812Y1111834D03*
X438112D03*
X445511D03*
X452912D03*
X449212D03*
X438112Y1124651D03*
X439961Y1121447D03*
X441812Y1124651D03*
X445511D03*
X443661Y1121447D03*
X438112Y1118243D03*
X441812D03*
X439961Y1115039D03*
X445511Y1118243D03*
X443661Y1115039D03*
X452912Y1124651D03*
Y1118243D03*
X451061Y1121447D03*
X449212Y1124651D03*
Y1118243D03*
X451061Y1115039D03*
X439961Y1127856D03*
X443661D03*
X451061D03*
X441812Y1137769D03*
X438112D03*
X445511D03*
X443661Y1134264D03*
X441812Y1131060D03*
X439961Y1134264D03*
X438112Y1131060D03*
X445511D03*
X452912Y1137769D03*
Y1131060D03*
X449212Y1137769D03*
Y1131060D03*
X451061Y1134264D03*
X459878Y848176D03*
X467278D03*
X467279Y841467D03*
X463578Y848176D03*
X459879Y841467D03*
X458027Y844971D03*
X454327D03*
X469127D03*
X465427D03*
X461727D03*
X456178Y848176D03*
X467278Y867401D03*
X459878D03*
Y860993D03*
X467278D03*
X469129Y870606D03*
X463578Y873810D03*
X461729Y870606D03*
X456178Y873810D03*
X454329Y870606D03*
X465429D03*
X458029D03*
X467278Y873810D03*
X459878D03*
Y886627D03*
X467278D03*
X459878Y899445D03*
X467278D03*
X454329Y896240D03*
X459878Y893036D03*
X461729Y896240D03*
X467278Y893036D03*
X456178Y899445D03*
X458029Y896240D03*
X463578Y899445D03*
X465429Y896240D03*
X470978Y899445D03*
X463578Y905853D03*
X470980Y912262D03*
X469129Y902649D03*
X454329Y909057D03*
X470978Y918670D03*
X467278Y912262D03*
X469129Y915466D03*
X458029Y909057D03*
X459878Y905853D03*
X461729Y915466D03*
X467278Y905853D03*
X461729Y909057D03*
X458029Y915466D03*
X459878Y918670D03*
X463578Y912262D03*
X459878D03*
X469129Y909057D03*
X467278Y918670D03*
X454329Y921875D03*
X468236Y928349D03*
X465936D03*
X463636D03*
X461336D03*
X459036D03*
X469129Y921875D03*
X463578Y918670D03*
X465429Y921875D03*
X458029D03*
X469251Y942246D03*
X453585Y942238D03*
Y939938D03*
Y944538D03*
X453403Y956999D03*
X461424Y956620D03*
X458404D03*
X453403Y959299D03*
X468904Y956620D03*
Y971100D03*
X458404D03*
X461424Y971140D03*
X453403Y973099D03*
Y970799D03*
Y986899D03*
X461424Y985580D03*
X458404D03*
X453403Y984599D03*
X468904Y985580D03*
X453403Y998399D03*
Y1012199D03*
X458404Y1000080D03*
X461424D03*
X453403Y1000699D03*
X468904Y1000080D03*
X458404Y1014540D03*
X461295Y1014510D03*
X453403Y1014499D03*
X465680Y1028855D03*
X463180D03*
X460680D03*
X458180D03*
X457942Y1031909D03*
X467711Y1047750D03*
X460311D03*
X471411Y1041340D03*
X467711D03*
X454762Y1044544D03*
Y1038136D03*
X460971Y1037069D03*
X463271D03*
X458671D03*
X457942Y1034409D03*
X456611Y1041340D03*
X464011D03*
X462162Y1044544D03*
X458462D03*
X464011Y1054157D03*
X465860Y1050952D03*
X456611Y1060565D03*
X462161Y1057361D03*
Y1063770D03*
X460312Y1054157D03*
X458462Y1057361D03*
X467712Y1054157D03*
Y1060565D03*
X454761Y1063770D03*
X464012Y1060565D03*
X458460Y1050952D03*
X460311Y1060565D03*
Y1073383D03*
X458460Y1070178D03*
X460311Y1066974D03*
X464011D03*
X465860Y1070178D03*
X469560D03*
X464012Y1079791D03*
X460312D03*
X462162Y1076587D03*
X456611Y1066974D03*
X465862Y1076587D03*
X464011Y1073383D03*
X458462Y1076587D03*
X465862Y1082995D03*
X462162D03*
X462161Y1095812D03*
X458461D03*
X465861Y1089403D03*
X456612Y1092607D03*
X454761Y1089403D03*
X460311Y1086200D03*
X454760Y1082995D03*
X465861Y1095812D03*
X464012Y1092607D03*
X454761Y1095812D03*
X458461Y1089403D03*
X462161D03*
X467711Y1099017D03*
X462162Y1102221D03*
X458461Y1108630D03*
X456612Y1105426D03*
X454761Y1108630D03*
Y1102221D03*
X460312Y1111834D03*
X456611D03*
X460312Y1099016D03*
X464012Y1124651D03*
X462161Y1121447D03*
X460312Y1124651D03*
X456611D03*
X454761Y1121447D03*
X464011Y1118243D03*
X462161Y1115039D03*
X460312Y1118243D03*
X456611D03*
X454761Y1115039D03*
X462161Y1127856D03*
X454761D03*
X465861D03*
X464012Y1137469D03*
X460312D03*
X456612D03*
X464012Y1131060D03*
X462161Y1134264D03*
X460312Y1131060D03*
X456611D03*
X454761Y1134264D03*
X462161Y1140973D03*
X458461D03*
X454761D03*
X467712Y1137469D03*
X465861Y1134264D03*
X467712Y1131060D03*
X465861Y1140973D03*
X474678Y848176D03*
X482078D03*
X483927Y844971D03*
X480227D03*
X476527D03*
X470978Y848176D03*
X482079Y841467D03*
X478378Y848176D03*
X474679Y841467D03*
X472827Y844971D03*
X474678Y867401D03*
X482078D03*
X474678Y860993D03*
X482078D03*
X480229Y870606D03*
X476529D03*
X478378Y873810D03*
X483929Y870606D03*
X474678Y880219D03*
X476529Y883423D03*
X482078Y880219D03*
X483929Y883423D03*
X472829D03*
X480229D03*
X474678Y873810D03*
X482078D03*
X474678Y893036D03*
X472829Y896240D03*
X482078Y893036D03*
X483929Y896240D03*
X478378Y886627D03*
Y899445D03*
X474678Y886627D03*
X482078D03*
X476529Y896240D03*
Y915466D03*
X478380Y912262D03*
X478379Y918670D03*
X480229Y902649D03*
X483929Y915466D03*
X480229D03*
X472828D03*
X472829Y902649D03*
X480228Y909057D03*
X482078Y905853D03*
X476529Y902649D03*
X470978Y905853D03*
X478378D03*
X472829Y909057D03*
X476529D03*
X480229Y928283D03*
X478378Y931488D03*
Y925079D03*
X482078D03*
X472829Y921875D03*
X470536Y928349D03*
X478378Y937896D03*
X480229Y941100D03*
X483929Y934691D03*
X480229Y947509D03*
X471550Y942152D03*
X473851Y942246D03*
X478378Y963530D03*
X483929Y953917D03*
X480228Y960326D03*
X478378Y950713D03*
X480229Y953917D03*
X478378Y957122D03*
X471404Y956620D03*
X480229Y966735D03*
X482078Y963529D03*
X483929Y973143D03*
X482078Y982756D03*
X478379Y969939D03*
X476285Y973826D03*
Y971526D03*
X471404Y971100D03*
X473904D03*
X480229Y979552D03*
X478378Y982756D03*
X480229Y973143D03*
X478378Y976347D03*
X471404Y985580D03*
X480662Y999684D03*
X478811Y1002888D03*
Y1009297D03*
X480662Y1012501D03*
X484362Y1006093D03*
X471404Y1000080D03*
X484362Y1025318D03*
X480662Y1031727D03*
X482511Y1015705D03*
X480661Y1018910D03*
X478811Y1022114D03*
Y1028523D03*
Y1015705D03*
X476325Y1031795D03*
Y1027195D03*
Y1029495D03*
X470724Y1028827D03*
X480662Y1025318D03*
X484362Y1044544D03*
X475111Y1047749D03*
X469562Y1044544D03*
X478811Y1034931D03*
X480662Y1038136D03*
X478811Y1041340D03*
X480662Y1044544D03*
X473262D03*
X476962D03*
X478811Y1047749D03*
X484362Y1063770D03*
X473261Y1057361D03*
X471412Y1060565D03*
X475112Y1054157D03*
X469562Y1063770D03*
X469561Y1057361D03*
X473262Y1063770D03*
X469561Y1050952D03*
X473262D03*
X482511Y1054157D03*
X480662Y1063770D03*
X480661Y1057361D03*
X478812Y1060565D03*
X476962Y1063770D03*
Y1057361D03*
X478812Y1054157D03*
X476961Y1050952D03*
X478811Y1066974D03*
X471411D03*
X476962Y1076587D03*
X480662D03*
Y1070178D03*
X476962D03*
X473262Y1076587D03*
X469562D03*
X471411Y1073383D03*
Y1079791D03*
X475111Y1073383D03*
X482511D03*
X484362Y1082995D03*
X473262Y1095813D03*
X469562Y1082995D03*
X480662Y1089404D03*
X478812Y1092607D03*
X475112D03*
X473261Y1089403D03*
X471412Y1086199D03*
X476961Y1082994D03*
X482512Y1092607D03*
X476961Y1095812D03*
X471412Y1092607D03*
X475112Y1086199D03*
X478812D03*
X480662Y1102221D03*
X473262Y1121447D03*
X480662D03*
Y1134264D03*
X469561D03*
X489478Y848176D03*
X496878D03*
X493178D03*
X489478Y841467D03*
X487627Y844971D03*
X500578Y848176D03*
X496878Y841467D03*
X495027Y844971D03*
X491327D03*
X485778Y848176D03*
X498727Y844971D03*
X489478Y867401D03*
X496878D03*
X489478Y860993D03*
X496878D03*
X487629Y870606D03*
X495029D03*
X485778Y873810D03*
X491329Y870606D03*
X493178Y873810D03*
X498729Y870606D03*
X500578Y873810D03*
X489478Y880219D03*
X491329Y883423D03*
X496878Y880219D03*
X498729Y883423D03*
X487629D03*
X495029D03*
X496878Y873810D03*
X489478D03*
X500578Y899445D03*
X485778D03*
X493178D03*
Y893036D03*
X496878D03*
X485778D03*
X491329Y896240D03*
X487629D03*
X495029D03*
X485778Y886627D03*
X493178D03*
X500578D03*
X489478D03*
X496878D03*
X485778Y912262D03*
X487629Y909057D03*
X493178Y912262D03*
X491329Y909057D03*
X500578Y912262D03*
X498729Y909057D03*
Y902649D03*
X487629D03*
X491329D03*
X487629Y915466D03*
X500578Y905853D03*
X495029Y915466D03*
X496878Y905853D03*
X491329Y915466D03*
X500578Y931488D03*
X498729Y921875D03*
X500578Y918670D03*
X498729Y928283D03*
X496878Y925079D03*
X500578D03*
X491329Y921875D03*
X493178Y918670D03*
X485778Y931488D03*
X491329Y928283D03*
X493178Y931488D03*
X487629Y928283D03*
Y921875D03*
X485778Y918670D03*
X498729Y947509D03*
Y941100D03*
X500578Y937896D03*
X496878Y944304D03*
X500578D03*
X487629Y947509D03*
X491329D03*
X487629Y941100D03*
X485778Y937896D03*
X491329Y941100D03*
X493178Y937896D03*
X487629Y934691D03*
X495029D03*
X491329D03*
X500578Y950713D03*
X487629Y966735D03*
X491329D03*
X498729D03*
X496878Y963530D03*
X485778Y950713D03*
X493178D03*
X491329Y960326D03*
X493178Y957122D03*
X487629Y960326D03*
X485778Y957122D03*
X500578D03*
X498729Y960326D03*
X495029Y953917D03*
X487629D03*
X491329D03*
X487629Y979552D03*
X485778Y976347D03*
X491329Y979552D03*
X493178Y976347D03*
X495029Y973143D03*
X487629D03*
X491329D03*
X485778Y969939D03*
X493178D03*
X500578D03*
X501011Y1002888D03*
X499162Y999684D03*
X495462Y1006093D03*
X486211Y1002888D03*
X493611D03*
X488062Y999684D03*
X491762D03*
X491761Y1012501D03*
X493611Y1009297D03*
X488062Y1012501D03*
X486211Y1009297D03*
X499162Y1031727D03*
X501011Y1028523D03*
X488062Y1031727D03*
X486211Y1028523D03*
X491762Y1031727D03*
X493611Y1028523D03*
X486211Y1022114D03*
X488062Y1018910D03*
X493611Y1022114D03*
X491762Y1018910D03*
X488062Y1025318D03*
X495462D03*
X491762D03*
X501011Y1041340D03*
X499162Y1038136D03*
X501011Y1047749D03*
Y1034931D03*
X497311D03*
X486211Y1047749D03*
X493611D03*
X486211Y1041340D03*
X488062Y1038136D03*
X493611Y1041340D03*
X491762Y1038136D03*
X488062Y1044544D03*
X495462D03*
X491762D03*
X501011Y1060565D03*
X499162Y1057361D03*
Y1050952D03*
X501011Y1054157D03*
X497311D03*
X486211Y1060565D03*
X488062Y1057361D03*
X493611Y1060565D03*
X491762Y1057361D03*
X488062Y1050952D03*
X491762D03*
X488062Y1063770D03*
X495462D03*
X491762D03*
X499162Y1070178D03*
X501011Y1066974D03*
Y1079791D03*
X499162Y1076587D03*
X497311Y1073383D03*
X501011D03*
X486211Y1079791D03*
X488062Y1076587D03*
X493611Y1079791D03*
X491762Y1076587D03*
X488062Y1070178D03*
X486211Y1066974D03*
X491762Y1070178D03*
X493611Y1066974D03*
X491762Y1089404D03*
X493611Y1086200D03*
X499162Y1089404D03*
X501011Y1086200D03*
X488062Y1089404D03*
X486211Y1086200D03*
X497311Y1092608D03*
X495462Y1082995D03*
X501011Y1092608D03*
X488062Y1082995D03*
X491762D03*
X488062Y1095813D03*
X501012Y1105426D03*
Y1111833D03*
X488062Y1115039D03*
Y1121447D03*
X495462Y1134264D03*
X488062D03*
X511678Y848176D03*
X504278D03*
X517227Y844971D03*
X511679Y841467D03*
X509827Y844971D03*
X504279Y841467D03*
X515378Y848176D03*
X513527Y844971D03*
X507978Y848176D03*
X506127Y844971D03*
X502427D03*
X511678Y867401D03*
X504278D03*
X511678Y860993D03*
X504278D03*
X517229Y870606D03*
X502429D03*
X509829D03*
X513529D03*
X515378Y873810D03*
X506129Y870606D03*
X507978Y873810D03*
X511678Y880219D03*
X513529Y883423D03*
X504278Y880219D03*
X506129Y883423D03*
X509829D03*
X517229D03*
X502429D03*
X511678Y873810D03*
X504278D03*
Y899445D03*
X515378Y886627D03*
X507978D03*
X511678D03*
X504278D03*
Y912262D03*
X506129Y909057D03*
Y902649D03*
X507978Y905853D03*
X504278D03*
X506129Y928283D03*
Y921875D03*
X504278Y918670D03*
Y931488D03*
Y925079D03*
X507978D03*
X506129Y947509D03*
Y941100D03*
X504278Y937896D03*
X507978Y944304D03*
X504278D03*
Y950713D03*
X506129Y966735D03*
X504278Y957122D03*
X506129Y960326D03*
X507978Y963530D03*
X504278Y969939D03*
X502862Y1006093D03*
X504711Y1002888D03*
X506561Y999684D03*
X517661D03*
X512111Y1002888D03*
X513962Y999684D03*
X506562Y1031727D03*
X504711Y1028523D03*
Y1041340D03*
X506562Y1038136D03*
X504711Y1047749D03*
X508411Y1034931D03*
X504711D03*
Y1060565D03*
X506562Y1057361D03*
Y1050952D03*
X508411Y1054157D03*
X504711D03*
Y1079791D03*
X506562Y1076587D03*
Y1070178D03*
X504711Y1066974D03*
X508411Y1073383D03*
X504711D03*
X510262Y1095813D03*
X506561D03*
X506562Y1089404D03*
X504711Y1086200D03*
X508411Y1092608D03*
X504711D03*
X517662Y1102221D03*
X515811Y1099017D03*
X510262Y1102221D03*
X502861Y1108629D03*
X512112Y1105426D03*
X508412Y1111833D03*
X506561Y1102220D03*
X504712Y1111833D03*
Y1105426D03*
X510261Y1108630D03*
X512112Y1111833D03*
X508412Y1105426D03*
X502862Y1115039D03*
X510262Y1121447D03*
X502862D03*
X517662D03*
X506561Y1115038D03*
X510262Y1134264D03*
X502862D03*
X517662D03*
X519078Y848176D03*
X532028Y844671D03*
X526478Y848176D03*
X524627Y844971D03*
X519079Y841467D03*
X533878Y848176D03*
X530178D03*
X522778D03*
X520927Y844971D03*
X532029Y864197D03*
X533879Y854584D03*
X519078Y867401D03*
X526479D03*
Y860993D03*
X519078D03*
X524629Y870606D03*
X532029D03*
X520929D03*
X522778Y873810D03*
X528329Y870606D03*
X530178Y873810D03*
X519078Y880219D03*
X520929Y883423D03*
X526479Y880219D03*
X528329Y883423D03*
X524629D03*
X526479Y873810D03*
X519078D03*
X530178Y893036D03*
X522778Y886627D03*
X530179D03*
X526479D03*
X519078D03*
X533879D03*
X519513Y1002888D03*
X530611D03*
X532461Y999684D03*
X526911Y1002888D03*
X525062Y999684D03*
X528762Y1102221D03*
X525062D03*
X523212Y1099017D03*
X530611Y1105426D03*
X526911Y1118243D03*
X525062Y1121447D03*
X534311Y1118243D03*
X532461Y1121446D03*
X534311Y1124650D03*
X532461Y1127855D03*
X525062Y1134264D03*
X528761Y1140973D03*
X532461D03*
X543129Y851380D03*
X539429D03*
X535729Y864197D03*
X543128D03*
X546828D03*
X535729Y857789D03*
X543130D03*
X539429D03*
X541279Y860993D03*
Y854584D03*
X541711Y1118243D03*
X538010Y1118242D03*
X543561Y1121446D03*
X539861Y1127855D03*
X536161D03*
Y1121446D03*
X539861D03*
X541711Y1124650D03*
X543561Y1127855D03*
X538012Y1131059D03*
X650599Y766798D03*
X918264Y506011D03*
X1030780Y1266532D03*
X1074480Y1263742D03*
X1181941Y766798D03*
X1297012Y157449D03*
X1293802Y159299D03*
Y166699D03*
X1293511Y179048D03*
X1296999Y183349D03*
X1297007Y172249D03*
X1296999Y175949D03*
X1293802Y170399D03*
X1294163Y175865D03*
X1296999Y179649D03*
Y194449D03*
Y198149D03*
Y190749D03*
Y187049D03*
Y201849D03*
X1293805Y211099D03*
X1293798Y205833D03*
X1296999Y216649D03*
X1293807Y218499D03*
Y214799D03*
X1296999Y212949D03*
Y205549D03*
X1294357Y224688D03*
X1296999Y224049D03*
X1293807Y222199D03*
X1300393Y235762D03*
X1303417Y164849D03*
X1300213Y162999D03*
X1300212Y166699D03*
X1306622D03*
X1309832Y157449D03*
X1306626Y162999D03*
Y159299D03*
X1313037Y162999D03*
X1309832Y164849D03*
X1313037Y159299D03*
X1303417Y157449D03*
X1300217Y159299D03*
X1313033Y166699D03*
X1300212Y170399D03*
X1306626D03*
X1303407Y183349D03*
X1309817Y175949D03*
X1300212Y174099D03*
X1313037Y170399D03*
X1306617Y185199D03*
X1309832Y172249D03*
X1313027Y181499D03*
Y185199D03*
X1303407Y175949D03*
Y179649D03*
X1306617Y177799D03*
X1309817Y179649D03*
X1300204Y181499D03*
X1309817Y194449D03*
X1306617Y188899D03*
X1303407Y194449D03*
X1306617Y196299D03*
X1300207D03*
X1303407Y190749D03*
Y187049D03*
X1300204Y188899D03*
X1313027Y192599D03*
X1309817Y190749D03*
X1313025Y188899D03*
X1309817Y198149D03*
X1303407D03*
X1300207Y203699D03*
Y207399D03*
X1309832Y209249D03*
X1313027Y203699D03*
X1300220Y218499D03*
X1309833Y220349D03*
X1303416Y205549D03*
X1306614Y203699D03*
X1306627Y214799D03*
X1316242Y209249D03*
X1300207Y211099D03*
X1303422Y220349D03*
X1300220Y222199D03*
X1313033D03*
X1303425Y224049D03*
X1300493Y238062D03*
X1314184Y849978D03*
X1307426Y978814D03*
X1314353Y1118243D03*
X1312503Y1121447D03*
X1314353Y1131060D03*
X1319452Y162999D03*
X1316242Y168549D03*
X1319442Y159299D03*
X1316241Y157449D03*
X1316242Y164849D03*
X1322652D03*
X1329062D03*
X1326918Y161161D03*
X1329062Y157449D03*
X1322652D03*
X1325853Y174099D03*
X1331102Y179724D03*
Y182874D03*
Y186024D03*
X1325085Y176402D03*
X1324802Y179724D03*
Y186024D03*
Y182874D03*
X1315352Y186024D03*
Y179724D03*
X1319442Y174099D03*
X1332268D03*
X1324802Y195474D03*
X1327952D03*
X1318502D03*
X1321652D03*
X1327952Y201774D03*
X1321652D03*
X1331102Y189174D03*
X1315405Y189227D03*
X1329062Y212949D03*
X1325852Y211099D03*
X1319442D03*
X1324802Y204924D03*
X1327952D03*
X1318502D03*
X1315352D03*
X1322652Y209249D03*
X1325857Y218499D03*
X1322652Y216649D03*
X1329062Y220349D03*
X1325856Y222199D03*
X1322652Y224049D03*
Y220349D03*
X1321320Y854584D03*
X1326869Y851380D03*
X1330569Y844971D03*
X1325020Y848176D03*
X1328720D03*
X1325021Y860993D03*
X1326871Y870606D03*
X1330571D03*
X1328720Y873810D03*
X1330571Y883423D03*
X1325020Y873810D03*
X1323171Y877014D03*
X1325020Y880219D03*
X1319903Y999684D03*
X1325453Y1105426D03*
X1329153D03*
X1325454Y1111834D03*
X1327303Y1102221D03*
X1321753Y1111834D03*
X1318054D03*
X1318053Y1105426D03*
X1327304Y1108630D03*
X1329154Y1111834D03*
X1331003Y1102221D03*
X1319904Y1108630D03*
X1321753Y1105426D03*
X1327304Y1127856D03*
X1329153Y1118243D03*
X1331003Y1121447D03*
X1323603D03*
X1319903Y1127856D03*
X1316203D03*
X1318054Y1118243D03*
X1321753Y1124651D03*
X1323603Y1127856D03*
X1319903Y1121447D03*
X1316203D03*
X1323603Y1115039D03*
X1331003Y1134264D03*
X1323603D03*
X1318053Y1131060D03*
X1339727Y161149D03*
X1341992Y156897D03*
X1332268Y162999D03*
X1342903Y170399D03*
X1339727Y168549D03*
X1335472Y164849D03*
X1346140Y161149D03*
X1342937Y162999D03*
X1335472Y157449D03*
X1346140D03*
X1339727D03*
X1332268Y170399D03*
X1334252Y176574D03*
X1339727Y183349D03*
X1346137Y175949D03*
X1342937Y177799D03*
X1346137Y183349D03*
X1337901Y196035D03*
X1339727Y187049D03*
X1337345Y201831D03*
X1339727Y201849D03*
X1337402Y198624D03*
X1342937Y192599D03*
X1346137Y187049D03*
X1346147Y201849D03*
Y198149D03*
X1336527Y214799D03*
X1339727Y216649D03*
X1346147Y212949D03*
Y216649D03*
X1336527Y218499D03*
X1342937D03*
Y214799D03*
X1332262Y211099D03*
X1339686Y205478D03*
X1332262Y207399D03*
X1339727Y209249D03*
Y220349D03*
X1336527Y222199D03*
X1346147Y220349D03*
X1347220Y848176D03*
X1339820D03*
X1332420D03*
X1332421Y841467D03*
X1337969Y844971D03*
X1339821Y841467D03*
X1345369Y844971D03*
X1347221Y841467D03*
X1334269Y844971D03*
X1336120Y848176D03*
X1341669Y844971D03*
X1343520Y848176D03*
X1347220Y867401D03*
X1332420D03*
X1339820D03*
Y860993D03*
X1347220D03*
X1332420D03*
X1334271Y870606D03*
X1337971D03*
X1341671D03*
X1336120Y873810D03*
X1343520D03*
X1345371Y870606D03*
X1332420Y880219D03*
X1334271Y883423D03*
X1339820Y880219D03*
X1341671Y883423D03*
X1347220Y880219D03*
X1337971Y883423D03*
X1345371D03*
X1339820Y873810D03*
X1332420D03*
X1347220D03*
Y893036D03*
X1339821D03*
X1343521D03*
X1336120Y886627D03*
X1343520D03*
X1347220D03*
X1339820D03*
X1343953Y1002888D03*
X1334704Y1102221D03*
X1345803D03*
X1343953Y1105426D03*
X1336554D03*
X1345803Y1108630D03*
X1340254Y1105426D03*
X1336554Y1111834D03*
X1334703Y1108630D03*
X1343954Y1111834D03*
X1342103Y1108630D03*
X1338403D03*
X1345804Y1121447D03*
X1338403D03*
X1342103Y1115039D03*
X1345803D03*
X1334703D03*
X1338404Y1134264D03*
X1345804D03*
X1352550Y157449D03*
X1355961Y155458D03*
X1352557Y168548D03*
X1355762Y166698D03*
X1349344Y162999D03*
X1348386Y156646D03*
X1352551Y161148D03*
X1352557Y172248D03*
X1349351Y177798D03*
Y170398D03*
Y174098D03*
Y192598D03*
X1352551Y187048D03*
X1355761Y188898D03*
X1349361Y199998D03*
X1352561Y201848D03*
X1355766Y214798D03*
X1349351Y218498D03*
X1352561Y216648D03*
X1355766Y218498D03*
X1352561Y220348D03*
X1355766Y222198D03*
X1360186Y226264D03*
X1362020Y848176D03*
X1354620D03*
X1363869Y844971D03*
X1352769D03*
X1356469D03*
X1360169D03*
X1362021Y841467D03*
X1349069Y844971D03*
X1350920Y848176D03*
X1354621Y841467D03*
X1358320Y848176D03*
X1354620Y867401D03*
X1362020D03*
Y860993D03*
X1354620D03*
X1363871Y870606D03*
X1349071D03*
X1356471D03*
X1350920Y873810D03*
X1352771Y870606D03*
X1358320Y873810D03*
X1360171Y870606D03*
X1349071Y883423D03*
X1354620Y880219D03*
X1356471Y883423D03*
X1362020Y880219D03*
X1363871Y883423D03*
X1352771D03*
X1360171D03*
X1354620Y873810D03*
X1362020D03*
X1350920Y899445D03*
X1358320D03*
Y893036D03*
X1350920D03*
X1362020D03*
X1349071Y896240D03*
X1356471D03*
X1352771D03*
X1360171D03*
X1350920Y886627D03*
X1358320D03*
X1354620D03*
X1362020D03*
X1352771Y902649D03*
X1356471D03*
X1350920Y912262D03*
X1352771Y909057D03*
X1358320Y912262D03*
X1356471Y909057D03*
X1363871D03*
Y902649D03*
X1349071Y915466D03*
X1362020Y905853D03*
X1356471Y915466D03*
X1352771D03*
X1360171D03*
X1350920Y931488D03*
X1352771Y928283D03*
X1358320Y931488D03*
X1356471Y928283D03*
X1363871Y921875D03*
X1352771D03*
X1350920Y918670D03*
X1356471Y921875D03*
X1358320Y918670D03*
X1363871Y928283D03*
X1362020Y925079D03*
X1356471Y941100D03*
X1358320Y937896D03*
X1352771Y947509D03*
X1356471D03*
X1352771Y941100D03*
X1350920Y937896D03*
X1349071Y934691D03*
X1356471D03*
X1352771D03*
X1360171D03*
X1363871Y947509D03*
Y941100D03*
X1362020Y944304D03*
X1352771Y960326D03*
X1350920Y957122D03*
X1356471Y960326D03*
X1358320Y957122D03*
X1350920Y950713D03*
X1358320D03*
X1349071Y953917D03*
X1356471D03*
X1352771D03*
X1360171D03*
X1363871Y960326D03*
Y966735D03*
X1356471D03*
X1352771D03*
X1362020Y963530D03*
Y982756D03*
X1363871Y979552D03*
X1352771D03*
X1356471D03*
X1350920Y976347D03*
X1358320D03*
X1349071Y973143D03*
X1350920Y969939D03*
X1358320D03*
X1360171Y973143D03*
X1351353Y1002888D03*
X1353204Y999684D03*
X1358753Y1002888D03*
X1356904Y999684D03*
X1353204Y1012501D03*
X1351353Y1009297D03*
X1356904Y1012501D03*
X1358753Y1009297D03*
X1353204Y1031727D03*
X1351353Y1028523D03*
X1356904Y1031727D03*
X1358753Y1028523D03*
X1351353Y1022114D03*
X1353204Y1018910D03*
X1358753Y1022114D03*
X1356904Y1018910D03*
X1353204Y1025318D03*
X1360604D03*
X1349502D03*
X1356902D03*
X1362453Y1015705D03*
X1351353Y1047749D03*
X1358753D03*
X1351353Y1041340D03*
X1353204Y1038136D03*
X1358753Y1041340D03*
X1356904Y1038136D03*
X1349504Y1044544D03*
X1356904D03*
X1353204D03*
X1360604D03*
X1362453Y1034931D03*
X1351353Y1060565D03*
X1353204Y1057361D03*
X1358753Y1060565D03*
X1356904Y1057361D03*
X1353204Y1050952D03*
X1356904D03*
X1349504Y1063770D03*
X1360604D03*
X1353204D03*
X1356904D03*
X1362453Y1054157D03*
X1356904Y1070178D03*
X1358753Y1066974D03*
X1353204Y1070178D03*
X1351353Y1066974D03*
Y1079791D03*
X1353204Y1076587D03*
X1358753Y1079791D03*
X1356904Y1076587D03*
X1362453Y1073383D03*
X1353204Y1089404D03*
X1351353Y1086200D03*
X1356904Y1089404D03*
X1358753Y1086200D03*
X1349504Y1082995D03*
X1362453Y1092608D03*
X1360604Y1082995D03*
X1353204D03*
X1356904D03*
X1351354Y1099017D03*
X1356904Y1095813D03*
X1358753Y1099017D03*
X1362453Y1111834D03*
Y1105426D03*
X1358753D03*
X1351353Y1111834D03*
Y1105426D03*
X1358753Y1111834D03*
X1360604Y1108630D03*
X1355053Y1111834D03*
X1356904Y1102221D03*
X1353204Y1108630D03*
X1355054Y1105426D03*
X1360604Y1121447D03*
X1353204D03*
X1356904Y1115039D03*
X1353204Y1134264D03*
X1360604D03*
X1376820Y848176D03*
X1369420D03*
X1367569Y844971D03*
X1369421Y841467D03*
X1373120Y848176D03*
X1376821Y841467D03*
X1365720Y848176D03*
X1371269Y844971D03*
X1374969D03*
X1378669D03*
X1376820Y867401D03*
X1369420D03*
X1376820Y860993D03*
X1369420D03*
X1367571Y870606D03*
X1371271D03*
X1378671D03*
X1365720Y873810D03*
X1373120D03*
X1374971Y870606D03*
X1369420Y880219D03*
X1371271Y883423D03*
X1376820Y880219D03*
X1378671Y883423D03*
X1367571D03*
X1374971D03*
X1369420Y873810D03*
X1376820D03*
X1378671Y896240D03*
X1376820Y899445D03*
X1365720D03*
X1369420D03*
X1369421Y893036D03*
X1373121D03*
X1373120Y886627D03*
X1365720D03*
X1374971Y896240D03*
X1376820Y893036D03*
X1369420Y886627D03*
X1376820D03*
X1380520Y899445D03*
X1376820Y905853D03*
X1378671Y915466D03*
Y909057D03*
X1365720Y912262D03*
X1369420D03*
X1371271Y909057D03*
Y902649D03*
X1369420Y905853D03*
X1365720D03*
X1373120D03*
X1376820Y912262D03*
X1378671Y902649D03*
X1376820Y931488D03*
X1378671Y928283D03*
X1369420Y931488D03*
X1371271Y928283D03*
X1365720Y918670D03*
X1371271Y921875D03*
X1369420Y918670D03*
X1365720Y931488D03*
X1369420Y925079D03*
X1365720D03*
X1373120D03*
X1378671Y921875D03*
X1374971Y934691D03*
X1378671D03*
X1371271Y947509D03*
X1365720Y937896D03*
X1371271Y941100D03*
X1369420Y937896D03*
Y944304D03*
X1365720D03*
X1373120D03*
X1378671Y947509D03*
X1365720Y957122D03*
X1371271Y960326D03*
X1369420Y957122D03*
X1371271Y966735D03*
X1365720Y950713D03*
X1369420D03*
X1373120Y963530D03*
X1369420D03*
X1365720D03*
X1378671Y966735D03*
Y960326D03*
Y953917D03*
X1374971D03*
X1376822Y950713D03*
X1374971Y973143D03*
X1376820Y976347D03*
X1378671Y979552D03*
Y973143D03*
X1369420Y982756D03*
X1365720D03*
X1373120D03*
X1369420Y976347D03*
X1371271Y979552D03*
X1365721Y976347D03*
X1365720Y969939D03*
X1369420D03*
X1375404Y1006093D03*
X1379104D03*
X1366153Y1002888D03*
X1364304Y999684D03*
X1369853Y1002888D03*
X1371704Y999684D03*
X1375404D03*
X1379104D03*
X1364304Y1012501D03*
X1371704D03*
X1366153Y1009297D03*
X1369853D03*
X1377253D03*
X1379104Y1012501D03*
Y1031727D03*
X1373553Y1015705D03*
X1364304Y1031727D03*
X1366153Y1028523D03*
X1371704Y1031727D03*
X1369853Y1028523D03*
X1366153Y1022114D03*
X1364304Y1018910D03*
X1369853Y1022114D03*
X1371704Y1018910D03*
X1377253Y1028523D03*
X1375404Y1025318D03*
X1377253Y1022114D03*
X1379102Y1018910D03*
X1379104Y1025318D03*
X1377253Y1015705D03*
X1366153Y1041340D03*
X1364304Y1038136D03*
X1369853Y1041340D03*
X1371704Y1038136D03*
X1366153Y1047749D03*
X1369853D03*
Y1034931D03*
X1366153D03*
X1373553D03*
X1375404Y1044544D03*
X1377253Y1041340D03*
X1379104Y1044544D03*
Y1038136D03*
X1377253Y1047749D03*
X1366153Y1060565D03*
X1364304Y1057361D03*
X1369853Y1060565D03*
X1371704Y1057361D03*
X1364304Y1050952D03*
X1371704D03*
X1369853Y1054157D03*
X1366153D03*
X1373553D03*
X1379104Y1057361D03*
Y1063770D03*
X1377255Y1060565D03*
X1375404Y1063770D03*
X1377253Y1054157D03*
X1379104Y1050952D03*
X1380953Y1054157D03*
X1379104Y1076587D03*
Y1070178D03*
X1366153Y1079791D03*
X1364304Y1076587D03*
X1369853Y1079791D03*
X1371704Y1076587D03*
X1364304Y1070178D03*
X1366153Y1066974D03*
X1371704Y1070178D03*
X1369853Y1066974D03*
Y1073383D03*
X1366153D03*
X1373553D03*
X1377254Y1066974D03*
X1371704Y1095813D03*
X1364304Y1089404D03*
X1366153Y1086200D03*
X1371704Y1089404D03*
X1369853Y1086200D03*
X1364304Y1095813D03*
X1369853Y1092608D03*
X1366153D03*
X1373553D03*
X1375404Y1082995D03*
X1379104D03*
X1379103Y1089404D03*
X1369853Y1099017D03*
X1366153D03*
X1368004Y1102221D03*
X1369853Y1105426D03*
Y1111834D03*
X1368004Y1108630D03*
X1377253Y1099017D03*
X1379104Y1108630D03*
X1373553Y1105426D03*
X1371704Y1108630D03*
X1379104Y1102221D03*
X1377253Y1111834D03*
X1375404Y1108630D03*
X1368004Y1121447D03*
X1375404Y1115039D03*
X1368004D03*
X1379104D03*
X1375404Y1121447D03*
X1368004Y1134264D03*
X1375404D03*
X1374847Y1153069D03*
X1391620Y848176D03*
X1384220D03*
X1380520D03*
X1386069Y844971D03*
X1389769D03*
X1393469D03*
X1382369D03*
X1384221Y841467D03*
X1387920Y848176D03*
X1391621Y841467D03*
X1395320Y848176D03*
X1384220Y867401D03*
X1391620D03*
X1384220Y860993D03*
X1391620D03*
X1380520Y873810D03*
X1382371Y870606D03*
X1384220Y880219D03*
X1386071Y883423D03*
X1382371D03*
X1395320Y873810D03*
X1393471Y870606D03*
X1387920Y873810D03*
X1389771Y870606D03*
X1391620Y873810D03*
X1384220D03*
X1386071Y896240D03*
X1389771D03*
X1393471D03*
X1387920Y899445D03*
X1391620Y893036D03*
X1395320Y899445D03*
X1380520Y886627D03*
X1387920D03*
X1380520Y893036D03*
X1382371Y896240D03*
X1384220Y886627D03*
X1391620D03*
Y899445D03*
X1384221Y899446D03*
X1393471Y909057D03*
X1382371D03*
X1389771D03*
Y915466D03*
X1399020Y905853D03*
X1382371Y915466D03*
X1384220Y918670D03*
X1387920Y905853D03*
X1384220D03*
Y912262D03*
X1382371Y902649D03*
X1391620Y905853D03*
X1387920Y912262D03*
X1391620D03*
X1393471Y915466D03*
X1391621Y918670D03*
X1382371Y921875D03*
X1382809Y927986D03*
X1385070Y928468D03*
X1393471Y921875D03*
X1391550Y925219D03*
X1387921Y918670D03*
X1386030Y942163D03*
X1383730D03*
X1381430D03*
X1392534Y942097D03*
X1394834D03*
X1393826Y956619D03*
X1387826D03*
X1391326D03*
X1385526D03*
X1380926Y971099D03*
X1383226D03*
X1387826D03*
X1385526D03*
X1396346D03*
X1396286Y985549D03*
X1388506Y985609D03*
X1386206D03*
X1385526Y1014539D03*
X1387826D03*
X1383226D03*
X1386226Y1000079D03*
X1396356Y1000039D03*
X1388526Y1000079D03*
X1396546Y1014469D03*
X1388102Y1028854D03*
X1390602D03*
X1393102D03*
X1395602D03*
X1380953Y1041340D03*
X1388353D03*
X1392053D03*
X1395753D03*
Y1047749D03*
X1392053D03*
X1382804Y1044544D03*
X1386504D03*
X1384653Y1047749D03*
X1390204Y1044544D03*
X1382804Y1050952D03*
Y1057361D03*
X1386504D03*
X1390204Y1050952D03*
X1393904Y1057361D03*
X1395753Y1054157D03*
X1382804Y1063770D03*
X1384653Y1060565D03*
X1386504Y1063770D03*
X1388353Y1054157D03*
X1390204Y1057361D03*
X1393904Y1063770D03*
X1390204D03*
X1395753Y1060565D03*
Y1079791D03*
X1384653Y1073383D03*
X1382804Y1070178D03*
X1380953Y1073383D03*
X1393904Y1076587D03*
X1392053Y1079791D03*
X1384653Y1066974D03*
X1388353Y1073383D03*
X1392053D03*
X1390204Y1070178D03*
X1393904D03*
X1388353Y1066974D03*
X1395753D03*
X1384653Y1079791D03*
X1395754Y1099017D03*
X1380953Y1092608D03*
X1393904Y1095813D03*
X1390203D03*
X1388353Y1086200D03*
X1386504Y1082995D03*
X1390204Y1089404D03*
X1382804D03*
X1390204Y1082995D03*
X1382804D03*
X1395753Y1086200D03*
Y1092608D03*
X1380953Y1086200D03*
X1386504Y1089404D03*
X1384653Y1092608D03*
X1380953Y1099017D03*
X1395753Y1105426D03*
X1393904Y1108630D03*
X1390204Y1102221D03*
X1392053Y1111834D03*
X1388353D03*
X1384653Y1105426D03*
Y1099017D03*
X1392053Y1105426D03*
X1395753Y1111834D03*
X1388353Y1105426D03*
X1384653Y1111834D03*
X1386504Y1108630D03*
X1392054Y1124651D03*
X1393903Y1121447D03*
Y1127856D03*
X1395754Y1118243D03*
Y1124651D03*
X1390204Y1115039D03*
X1382803Y1121447D03*
X1390204Y1127856D03*
X1382804Y1134264D03*
X1390203Y1140973D03*
X1392054Y1131060D03*
Y1137469D03*
X1393903Y1134264D03*
Y1140973D03*
X1395754Y1131060D03*
Y1137469D03*
X1388354D03*
X1399020Y848176D03*
X1397169Y844971D03*
X1399021Y841467D03*
X1402720Y848176D03*
X1406420D03*
X1411969Y844971D03*
X1400869D03*
X1404569D03*
X1410120Y848176D03*
X1406420Y867401D03*
X1399020D03*
X1406420Y860993D03*
X1399020D03*
X1408271Y870606D03*
X1402720Y873810D03*
X1400871Y870606D03*
X1410121Y873810D03*
X1404571Y870606D03*
X1397171D03*
X1411971D03*
X1399020Y873810D03*
X1406420D03*
X1397171Y896240D03*
X1402720Y899445D03*
X1404571Y896240D03*
X1410120Y899445D03*
X1399020Y893036D03*
X1400871Y896240D03*
X1406420Y893036D03*
X1408271Y896240D03*
X1411971D03*
X1406420Y886627D03*
X1399020D03*
X1406420Y899445D03*
X1399020D03*
Y912262D03*
X1400871Y915466D03*
X1402720Y912262D03*
X1406420D03*
X1408271Y915466D03*
X1397171Y909057D03*
X1411971D03*
Y915466D03*
X1408270Y909057D03*
X1410120Y905853D03*
X1400870Y909057D03*
X1406420Y905853D03*
X1402720D03*
X1397171Y915466D03*
X1410121Y912262D03*
X1406420Y918670D03*
X1408271Y921875D03*
X1410121Y918670D03*
X1411971Y921875D03*
X1401528Y927155D03*
X1399028D03*
X1401817Y929464D03*
X1399317D03*
X1400871Y921875D03*
X1399020Y918670D03*
X1397171Y921875D03*
X1402720Y918670D03*
X1411971Y934691D03*
X1406420Y925079D03*
X1408271Y928283D03*
X1406420Y931488D03*
X1411971Y928283D03*
X1406421Y944304D03*
X1408271Y941100D03*
X1411971D03*
X1404016Y944229D03*
Y941929D03*
X1408270Y947509D03*
X1411971D03*
X1408271Y934691D03*
X1406421Y950713D03*
Y957122D03*
X1408270Y953917D03*
Y960326D03*
X1411971Y953917D03*
Y960326D03*
X1404016Y954072D03*
Y956372D03*
X1401326Y956619D03*
X1398826D03*
X1406421Y963530D03*
X1408270Y966735D03*
X1411971D03*
X1406421Y969939D03*
X1406409Y976347D03*
X1408270Y973143D03*
X1411971D03*
X1404016Y971266D03*
Y968966D03*
X1398826Y971099D03*
X1406421Y982756D03*
X1408270Y979552D03*
X1411971D03*
X1404016Y983110D03*
Y985410D03*
X1398826Y985579D03*
X1404016Y997520D03*
X1412404Y999684D03*
Y1006093D03*
Y1012501D03*
X1406853Y1002888D03*
Y1009297D03*
X1408703Y999684D03*
Y1006093D03*
Y1012501D03*
X1404016Y1012151D03*
Y999820D03*
X1398826Y1000059D03*
X1404016Y1014451D03*
X1399156Y1014469D03*
X1398102Y1028854D03*
X1406853Y1028523D03*
X1412404Y1018910D03*
X1406853Y1015705D03*
Y1022114D03*
X1408703Y1018910D03*
X1412404Y1025318D03*
X1408703D03*
X1404016Y1026703D03*
X1412404Y1031727D03*
X1408703D03*
X1404016Y1029003D03*
Y1031303D03*
X1403153Y1047749D03*
X1403154Y1041340D03*
X1399454D03*
X1401304Y1044544D03*
X1412403Y1038136D03*
Y1044544D03*
X1406853Y1034931D03*
Y1041340D03*
X1408703Y1038136D03*
Y1044544D03*
X1410554Y1041340D03*
X1404016Y1033603D03*
X1399426Y1036883D03*
Y1034583D03*
Y1032283D03*
X1410554Y1047749D03*
X1397604Y1044544D03*
X1403153Y1054157D03*
X1406853D03*
X1405003Y1057361D03*
X1408703D03*
Y1063770D03*
X1412404Y1050952D03*
Y1057361D03*
Y1063770D03*
X1397604Y1057361D03*
X1401304Y1050952D03*
X1399453Y1054157D03*
X1405004Y1050952D03*
X1397604D03*
X1401304Y1063770D03*
X1399453Y1060565D03*
X1403153D03*
X1405003Y1063770D03*
X1406853Y1060565D03*
X1397604Y1076587D03*
X1408702Y1070178D03*
X1399453Y1073383D03*
Y1079791D03*
X1412404Y1070178D03*
Y1076587D03*
X1397604Y1070178D03*
X1401304D03*
X1405004D03*
X1406853Y1066974D03*
X1405003Y1076587D03*
X1406853Y1079791D03*
X1412404Y1082995D03*
Y1089404D03*
X1412403Y1095813D03*
X1401304Y1082995D03*
X1405003Y1089404D03*
X1399453Y1086200D03*
X1406853Y1092608D03*
X1399453D03*
X1397604Y1089404D03*
X1403154Y1086200D03*
X1406852D03*
X1403153Y1092608D03*
X1401304Y1095813D03*
X1397604Y1102221D03*
X1399453Y1099017D03*
X1412404Y1102221D03*
Y1108630D03*
X1401304D03*
X1403154Y1105426D03*
Y1111834D03*
X1405003Y1102221D03*
Y1108630D03*
X1406853Y1099017D03*
Y1105426D03*
Y1111834D03*
X1408703Y1102221D03*
Y1108630D03*
X1410554Y1099017D03*
X1412404Y1115039D03*
Y1121447D03*
Y1127856D03*
X1397603Y1121447D03*
Y1127856D03*
X1401304Y1115039D03*
Y1121447D03*
Y1127856D03*
X1403154Y1118243D03*
Y1124651D03*
X1405003Y1115039D03*
Y1121447D03*
Y1127856D03*
X1406853Y1118243D03*
Y1124651D03*
X1408703Y1115039D03*
Y1121447D03*
Y1127856D03*
X1412403Y1134264D03*
X1397603D03*
Y1140973D03*
X1401304Y1134264D03*
X1401303Y1140973D03*
X1403154Y1131060D03*
Y1137569D03*
X1405003Y1134264D03*
Y1140973D03*
X1406853Y1131060D03*
Y1137769D03*
X1408703Y1134264D03*
X1413820Y848176D03*
X1428620Y867401D03*
X1421220D03*
X1413820D03*
X1421220Y860993D03*
X1428621D03*
X1424921Y873810D03*
X1423071Y870606D03*
X1417520Y873810D03*
X1415671Y870606D03*
X1426771D03*
X1419371D03*
X1413821Y873810D03*
X1428621D03*
X1421220D03*
X1413820Y893036D03*
X1421220Y899445D03*
X1419371Y896240D03*
X1424920Y899445D03*
X1426772Y896240D03*
X1417520Y899445D03*
X1421220Y893036D03*
X1423071Y896240D03*
X1428621Y893036D03*
X1428620Y899445D03*
Y886627D03*
X1421220D03*
X1419371Y909057D03*
X1415671Y915466D03*
X1421221Y905853D03*
X1417521D03*
X1430471Y909057D03*
X1426772D03*
X1428621Y905853D03*
X1424921D03*
X1424922Y912262D03*
X1417522D03*
X1415671Y909057D03*
X1421222Y912262D03*
X1419371Y915466D03*
X1426771D03*
X1428620Y912262D03*
X1424921Y918670D03*
X1430471Y915466D03*
X1415671Y921875D03*
X1417520Y918670D03*
X1426771Y921875D03*
X1421220Y918670D03*
X1419371Y921875D03*
X1428620Y918670D03*
X1424921Y931488D03*
X1419371Y928283D03*
X1413820Y931488D03*
X1424921Y925079D03*
X1419371Y934691D03*
X1421220Y931488D03*
Y925079D03*
X1415671Y928283D03*
X1413820Y925079D03*
X1426771Y928283D03*
X1413821Y944304D03*
X1415671Y941100D03*
X1417521Y944304D03*
X1419371Y941100D03*
X1421220Y944304D03*
X1424921D03*
X1426771Y941100D03*
X1415670Y947509D03*
X1419370D03*
X1426771D03*
X1423071Y934691D03*
X1415671D03*
X1413821Y950713D03*
Y957122D03*
X1415670Y953917D03*
Y960326D03*
X1417521Y950713D03*
Y957122D03*
X1419370Y953917D03*
Y960326D03*
X1421220Y950713D03*
Y957122D03*
X1424921Y950713D03*
Y957122D03*
X1426771Y953917D03*
Y960326D03*
X1413821Y963530D03*
X1415670Y966735D03*
X1417521Y963530D03*
X1419370Y966735D03*
X1421220Y963530D03*
X1424921D03*
X1426771Y966735D03*
X1413821Y969939D03*
Y976347D03*
X1415670Y973143D03*
X1417521Y969939D03*
Y976347D03*
X1419370Y973143D03*
X1421220Y969939D03*
Y976347D03*
X1424921Y969939D03*
Y976347D03*
X1426771Y973143D03*
X1413821Y982756D03*
X1415670Y979552D03*
X1417521Y982756D03*
X1419370Y979552D03*
X1421220Y982756D03*
X1424921D03*
X1426771Y979552D03*
X1414254Y1002888D03*
Y1009297D03*
X1416103Y999684D03*
Y1006093D03*
Y1012501D03*
X1417954Y1002888D03*
Y1009297D03*
X1419803Y999684D03*
Y1006093D03*
Y1012501D03*
X1421653Y1002888D03*
Y1009297D03*
X1425354Y1002888D03*
Y1009297D03*
X1427203Y999684D03*
Y1006093D03*
Y1012501D03*
X1421653Y1028523D03*
X1414254D03*
X1417954D03*
X1425354D03*
X1414254Y1015705D03*
Y1022114D03*
X1416103Y1018910D03*
X1417954Y1015705D03*
Y1022114D03*
X1419803Y1018910D03*
X1421653Y1015705D03*
Y1022114D03*
X1425354Y1015705D03*
Y1022114D03*
X1427203Y1018910D03*
X1416103Y1025318D03*
X1419803D03*
X1427203D03*
X1416103Y1031727D03*
X1419803D03*
X1427203D03*
X1429053Y1047749D03*
X1414254Y1034931D03*
Y1041340D03*
X1416103Y1038136D03*
Y1044544D03*
X1417954Y1034931D03*
Y1041340D03*
X1419803Y1038136D03*
Y1044544D03*
X1421653Y1034931D03*
Y1041340D03*
X1423503Y1044544D03*
X1425354Y1034931D03*
X1425353Y1041340D03*
X1427203Y1038136D03*
X1421653Y1047749D03*
X1414254D03*
X1417954D03*
X1425353Y1054157D03*
X1425355Y1060565D03*
X1414254Y1054157D03*
X1416103Y1050952D03*
X1417954Y1054157D03*
X1419803Y1050952D03*
X1421653Y1054157D03*
X1414254Y1060565D03*
X1416103Y1057361D03*
X1417954Y1060565D03*
X1419803Y1057361D03*
X1421653Y1060565D03*
X1416103Y1063770D03*
X1419803D03*
X1427203D03*
X1429053Y1054157D03*
X1427203Y1050952D03*
X1430903D03*
X1430904Y1057361D03*
X1427204D03*
X1429053Y1073383D03*
X1427203Y1076587D03*
X1414254Y1066974D03*
Y1073383D03*
X1416103Y1070178D03*
Y1076587D03*
X1417954Y1066974D03*
Y1073383D03*
X1419803Y1070178D03*
Y1076587D03*
X1421653Y1066974D03*
Y1073383D03*
X1414254Y1079791D03*
X1417954D03*
X1421653D03*
X1429053Y1066974D03*
X1425353D03*
X1427204Y1070178D03*
X1429053Y1086200D03*
X1416103Y1082995D03*
X1419803D03*
X1414254Y1086200D03*
Y1092608D03*
X1416103Y1089404D03*
Y1095813D03*
X1417954Y1086200D03*
Y1092608D03*
X1419803Y1089404D03*
Y1095813D03*
X1421653Y1086200D03*
Y1092608D03*
X1423503Y1089404D03*
Y1095813D03*
X1425353Y1092608D03*
X1427202Y1082995D03*
X1414254Y1099017D03*
Y1105426D03*
Y1111834D03*
X1416103Y1102221D03*
Y1108630D03*
X1417954Y1099017D03*
Y1105426D03*
Y1111834D03*
X1419803Y1102221D03*
Y1108630D03*
X1421653Y1099017D03*
Y1105426D03*
Y1111834D03*
X1425354Y1099017D03*
Y1105426D03*
Y1111834D03*
X1427203Y1102221D03*
Y1108630D03*
X1429054Y1105426D03*
Y1111834D03*
X1414254Y1118243D03*
Y1124651D03*
X1416103Y1115039D03*
Y1121447D03*
Y1127856D03*
X1417954Y1118243D03*
Y1124651D03*
X1419803Y1115039D03*
Y1121447D03*
Y1127856D03*
X1421653Y1118243D03*
Y1124651D03*
X1425354Y1118243D03*
Y1124651D03*
X1427203Y1115039D03*
Y1121447D03*
Y1127856D03*
X1429054Y1118243D03*
Y1124651D03*
X1414254Y1131060D03*
Y1137769D03*
X1416103Y1134264D03*
X1417954Y1131060D03*
Y1137769D03*
X1419803Y1134264D03*
X1421653Y1131060D03*
Y1137769D03*
X1425354Y1131060D03*
Y1137769D03*
X1427203Y1134264D03*
X1429054Y1131060D03*
Y1137769D03*
X1443420Y848176D03*
X1436020D03*
X1443420Y867401D03*
X1436020D03*
X1443420Y860993D03*
X1436020D03*
X1445271Y870606D03*
X1439720Y873810D03*
X1437871Y870606D03*
X1432320Y873810D03*
X1430471Y870606D03*
X1441571D03*
X1434171D03*
X1436020Y873810D03*
X1443420D03*
X1430471Y896240D03*
X1436020Y893036D03*
X1437871Y896240D03*
X1441571D03*
X1432320Y899445D03*
X1434171Y896240D03*
X1439720Y899445D03*
X1443420Y893036D03*
X1436020Y899445D03*
X1443420D03*
X1436020Y886627D03*
X1443420D03*
X1447120Y899445D03*
X1445271Y902649D03*
X1434171Y909057D03*
X1437871Y915466D03*
X1443420Y912262D03*
X1445271Y915466D03*
X1437871Y909057D03*
X1434171Y915466D03*
X1436020Y918670D03*
X1439720Y912262D03*
X1436020D03*
Y905853D03*
X1439720D03*
X1443420D03*
X1445271Y909057D03*
X1430471Y921875D03*
X1443420Y918670D03*
X1439777Y928348D03*
X1437477D03*
X1435177D03*
X1444377D03*
X1442077D03*
X1445271Y921875D03*
X1439720Y918670D03*
X1441571Y921875D03*
X1434171D03*
X1445392Y942195D03*
X1429726Y944537D03*
Y939937D03*
Y942237D03*
X1429544Y959298D03*
Y956998D03*
X1437565Y956619D03*
X1434545D03*
X1445045D03*
X1429544Y970798D03*
Y973098D03*
X1437565Y971139D03*
X1434545Y971099D03*
X1429544Y986898D03*
Y984598D03*
X1437565Y985579D03*
X1434545D03*
X1445045D03*
X1429544Y998398D03*
Y1012198D03*
Y1000698D03*
X1437565Y1000079D03*
X1434545D03*
X1445045D03*
X1429544Y1014498D03*
X1437436Y1014509D03*
X1434545Y1014539D03*
X1445036Y1014549D03*
X1439321Y1028854D03*
X1436821D03*
X1434321D03*
X1441821D03*
X1434083Y1031908D03*
X1447553Y1041340D03*
X1443853D03*
X1436453Y1047750D03*
X1443853D03*
X1430904Y1044544D03*
Y1038136D03*
X1434083Y1034408D03*
X1434813Y1037069D03*
X1439413D03*
X1437113D03*
X1432753Y1041340D03*
X1440153D03*
X1438304Y1044544D03*
X1434604D03*
X1432753Y1060565D03*
X1438303Y1057361D03*
Y1063770D03*
X1442002Y1050952D03*
X1440153Y1054157D03*
X1436454D03*
X1434604Y1057361D03*
X1443854Y1054157D03*
Y1060565D03*
X1430903Y1063770D03*
X1440154Y1060565D03*
X1434603Y1050952D03*
X1436453Y1060565D03*
Y1073383D03*
X1434602Y1070178D03*
X1436453Y1066974D03*
X1440153D03*
X1442002Y1070178D03*
X1447553Y1066974D03*
X1440154Y1079791D03*
X1436454D03*
X1438304Y1076587D03*
X1432753Y1066974D03*
X1442004Y1076587D03*
X1440153Y1073383D03*
X1434604Y1076587D03*
X1438304Y1082995D03*
X1442004D03*
X1438303Y1095812D03*
X1434603D03*
X1442003Y1089403D03*
X1432754Y1092607D03*
X1430903Y1089403D03*
X1436454Y1086199D03*
X1430902Y1082995D03*
X1442003Y1095812D03*
X1440154Y1092607D03*
X1430903Y1095812D03*
X1434603Y1089403D03*
X1438303D03*
X1438304Y1102221D03*
X1443853Y1099017D03*
X1430903Y1102221D03*
Y1108630D03*
X1432754Y1105426D03*
X1432753Y1111834D03*
X1434603Y1108630D03*
X1436454Y1111834D03*
Y1099016D03*
X1430903Y1115039D03*
Y1121447D03*
Y1127856D03*
X1432753Y1118243D03*
Y1124651D03*
X1436454Y1118243D03*
Y1124651D03*
X1438303Y1115039D03*
Y1121447D03*
Y1127856D03*
X1440153Y1118243D03*
X1440154Y1124651D03*
X1442003Y1127856D03*
X1443854Y1131060D03*
Y1137469D03*
X1430903Y1134264D03*
Y1140973D03*
X1432753Y1131060D03*
X1432754Y1137469D03*
X1434603Y1140973D03*
X1436454Y1131060D03*
Y1137469D03*
X1438303Y1134264D03*
Y1140973D03*
X1440154Y1131060D03*
Y1137469D03*
X1442003Y1134264D03*
Y1140973D03*
X1450820Y848176D03*
X1458220D03*
X1450820Y867401D03*
X1458220D03*
X1450820Y860993D03*
X1458220D03*
X1456371Y870606D03*
X1452671D03*
X1454520Y873810D03*
X1460071Y870606D03*
X1450820Y880219D03*
X1452671Y883423D03*
X1458220Y880219D03*
X1460071Y883423D03*
X1448971D03*
X1456371D03*
X1458220Y873810D03*
X1450820D03*
Y893036D03*
X1448971Y896240D03*
X1458220Y893036D03*
X1460071Y896240D03*
X1454520Y886627D03*
Y899445D03*
X1458220Y886627D03*
X1450820D03*
X1452671Y896240D03*
X1456371Y902649D03*
X1460071Y915466D03*
X1456371D03*
X1447122Y912262D03*
X1454521Y918670D03*
X1452671Y915466D03*
X1454522Y912262D03*
X1448971Y902649D03*
X1456370Y909057D03*
X1458220Y905853D03*
X1452671Y902649D03*
X1448970Y915466D03*
X1447120Y905853D03*
X1454520D03*
X1448971Y909057D03*
X1452671D03*
X1456371Y928283D03*
X1454522Y931488D03*
X1454520Y925079D03*
X1458220D03*
X1448971Y921875D03*
X1447120Y918670D03*
X1446677Y928348D03*
X1454520Y937896D03*
X1456371Y941100D03*
X1460071Y934691D03*
X1456371Y947509D03*
X1449992Y942195D03*
X1447692D03*
X1454520Y963530D03*
X1456371Y966735D03*
X1458220Y963529D03*
X1460071Y953917D03*
X1456370Y960326D03*
X1456371Y953917D03*
X1454520Y957122D03*
Y950713D03*
X1447545Y956619D03*
X1460071Y973143D03*
X1458220Y982756D03*
X1454521Y969939D03*
X1450045Y971099D03*
X1445445D03*
X1447745D03*
X1452426Y973825D03*
Y971525D03*
X1456371Y979552D03*
X1454520Y982756D03*
X1456371Y973143D03*
X1454520Y976347D03*
X1447545Y985579D03*
X1456804Y999684D03*
X1454953Y1002888D03*
Y1009297D03*
X1456804Y1012501D03*
X1460504Y1006093D03*
X1447545Y1000079D03*
X1447345Y1014539D03*
X1460504Y1025318D03*
X1456804Y1031727D03*
X1454953Y1028523D03*
Y1022114D03*
X1456803Y1018910D03*
X1454953Y1015705D03*
X1446934Y1028889D03*
X1452466Y1031794D03*
Y1029494D03*
Y1027194D03*
X1456804Y1025318D03*
X1458653Y1015705D03*
X1460504Y1044544D03*
X1451253Y1047749D03*
X1445704Y1044544D03*
X1454953Y1034931D03*
X1456804Y1038136D03*
X1454953Y1041340D03*
X1456804Y1044544D03*
X1449404D03*
X1454953Y1047749D03*
X1453104Y1044544D03*
X1460504Y1063770D03*
X1456804D03*
X1458653Y1054157D03*
X1454954D03*
X1453104Y1057361D03*
Y1063770D03*
X1454954Y1060565D03*
X1456803Y1057361D03*
X1453103Y1050952D03*
X1445703Y1057361D03*
X1445704Y1063770D03*
X1447554Y1060565D03*
X1449403Y1057361D03*
X1449404Y1063770D03*
X1451254Y1054157D03*
X1445703Y1050952D03*
X1449404D03*
X1454953Y1066974D03*
X1445702Y1070178D03*
X1453104Y1076587D03*
X1456804D03*
Y1070178D03*
X1453104D03*
X1447553Y1073383D03*
X1449404Y1076587D03*
X1445704D03*
X1447553Y1079791D03*
X1451253Y1073383D03*
X1458653D03*
X1460504Y1082995D03*
X1445704D03*
X1456804Y1089404D03*
X1449404Y1095813D03*
X1454954Y1092607D03*
X1451254D03*
X1449403Y1089403D03*
X1447554Y1086199D03*
X1453103Y1082994D03*
X1458654Y1092607D03*
X1453103Y1095812D03*
X1447554Y1092607D03*
X1451254Y1086199D03*
X1454954D03*
X1456804Y1102221D03*
Y1121447D03*
X1449404D03*
X1456804Y1134264D03*
X1445703D03*
X1465620Y848176D03*
X1473020D03*
X1465620Y867401D03*
X1473020D03*
X1465620Y860993D03*
X1473020D03*
X1463771Y870606D03*
X1471171D03*
X1461920Y873810D03*
X1467471Y870606D03*
X1469320Y873810D03*
X1474871Y870606D03*
X1476720Y873810D03*
X1465620Y880219D03*
X1467471Y883423D03*
X1473020Y880219D03*
X1474871Y883423D03*
X1463771D03*
X1471171D03*
X1473020Y873810D03*
X1465620D03*
X1476720Y899445D03*
X1461920D03*
X1469320D03*
Y893036D03*
X1473020D03*
X1461920D03*
X1467471Y896240D03*
X1463771D03*
X1471171D03*
X1461920Y886627D03*
X1469320D03*
X1476720D03*
X1473020D03*
X1465620D03*
X1461920Y912262D03*
X1463771Y909057D03*
X1469320Y912262D03*
X1467471Y909057D03*
X1476720Y912262D03*
X1474871Y909057D03*
Y902649D03*
X1463771D03*
X1467471D03*
X1463771Y915466D03*
X1476720Y905853D03*
X1471171Y915466D03*
X1473020Y905853D03*
X1467471Y915466D03*
X1476720Y931488D03*
X1474871Y921875D03*
X1476720Y918670D03*
X1474871Y928283D03*
X1473020Y925079D03*
X1476720D03*
X1467471Y921875D03*
X1469320Y918670D03*
X1461920Y931488D03*
X1467471Y928283D03*
X1469320Y931488D03*
X1463771Y928283D03*
Y921875D03*
X1461920Y918670D03*
X1474871Y947509D03*
Y941100D03*
X1476720Y937896D03*
X1473020Y944304D03*
X1476720D03*
X1463771Y947509D03*
X1467471D03*
X1463771Y941100D03*
X1461920Y937896D03*
X1467471Y941100D03*
X1469320Y937896D03*
X1463771Y934691D03*
X1471171D03*
X1467471D03*
X1476720Y950713D03*
X1463771Y966735D03*
X1467471D03*
X1474871D03*
X1473020Y963530D03*
X1461920Y950713D03*
X1469320D03*
X1467471Y960326D03*
X1469320Y957122D03*
X1463771Y960326D03*
X1461920Y957122D03*
X1476720D03*
X1474871Y960326D03*
X1471171Y953917D03*
X1463771D03*
X1467471D03*
X1463771Y979552D03*
X1461920Y976347D03*
X1467471Y979552D03*
X1469320Y976347D03*
X1471171Y973143D03*
X1463771D03*
X1467471D03*
X1461920Y969939D03*
X1469320D03*
X1476720D03*
X1477153Y1002888D03*
X1475304Y999684D03*
X1471604Y1006093D03*
X1462353Y1002888D03*
X1469753D03*
X1464204Y999684D03*
X1467904D03*
X1467903Y1012501D03*
X1469753Y1009297D03*
X1464204Y1012501D03*
X1462353Y1009297D03*
X1475304Y1031727D03*
X1477153Y1028523D03*
X1464204Y1031727D03*
X1462353Y1028523D03*
X1467904Y1031727D03*
X1469753Y1028523D03*
X1462353Y1022114D03*
X1464204Y1018910D03*
X1469753Y1022114D03*
X1467904Y1018910D03*
X1464204Y1025318D03*
X1471604D03*
X1467904D03*
X1477153Y1041340D03*
X1475304Y1038136D03*
X1477153Y1047749D03*
Y1034931D03*
X1473453D03*
X1462353Y1047749D03*
X1469753D03*
X1462353Y1041340D03*
X1464204Y1038136D03*
X1469753Y1041340D03*
X1467904Y1038136D03*
X1464204Y1044544D03*
X1471604D03*
X1467904D03*
X1477153Y1060565D03*
X1475304Y1057361D03*
Y1050952D03*
X1477153Y1054157D03*
X1473453D03*
X1462353Y1060565D03*
X1464204Y1057361D03*
X1469753Y1060565D03*
X1467904Y1057361D03*
X1464204Y1050952D03*
X1467904D03*
X1464204Y1063770D03*
X1471604D03*
X1467904D03*
X1475304Y1070178D03*
X1477153Y1066974D03*
Y1079791D03*
X1475304Y1076587D03*
X1473453Y1073383D03*
X1477153D03*
X1462353Y1079791D03*
X1464204Y1076587D03*
X1469753Y1079791D03*
X1467904Y1076587D03*
X1464204Y1070178D03*
X1462353Y1066974D03*
X1467904Y1070178D03*
X1469753Y1066974D03*
X1467904Y1089404D03*
X1469753Y1086200D03*
X1475304Y1089404D03*
X1477153Y1086200D03*
X1464204Y1089404D03*
X1462353Y1086200D03*
X1473453Y1092608D03*
X1471604Y1082995D03*
X1477153Y1092608D03*
X1464204Y1082995D03*
X1467904D03*
X1464204Y1095813D03*
X1477154Y1105426D03*
Y1111833D03*
X1464204Y1115039D03*
Y1121447D03*
X1471604Y1134264D03*
X1464204D03*
X1487820Y848176D03*
X1480420D03*
X1487820Y867401D03*
X1480420D03*
X1487820Y860993D03*
X1480420D03*
X1493371Y870606D03*
X1478571D03*
X1485971D03*
X1489671D03*
X1491520Y873810D03*
X1482271Y870606D03*
X1484120Y873810D03*
X1487820Y880219D03*
X1489671Y883423D03*
X1480420Y880219D03*
X1482271Y883423D03*
X1485971D03*
X1493371D03*
X1478571D03*
X1487820Y873810D03*
X1480420D03*
Y899445D03*
X1491520Y886627D03*
X1484120D03*
X1480420D03*
X1487820D03*
X1480420Y912262D03*
X1482271Y909057D03*
Y902649D03*
X1484120Y905853D03*
X1480420D03*
X1482271Y928283D03*
Y921875D03*
X1480420Y918670D03*
Y931488D03*
Y925079D03*
X1484120D03*
X1482271Y947509D03*
Y941100D03*
X1480420Y937896D03*
X1484120Y944304D03*
X1480420D03*
Y950713D03*
X1482271Y966735D03*
X1480420Y957122D03*
X1482271Y960326D03*
X1484120Y963530D03*
X1480420Y969939D03*
X1479004Y1006093D03*
X1480853Y1002888D03*
X1482703Y999684D03*
X1493803D03*
X1488253Y1002888D03*
X1490104Y999684D03*
X1482704Y1031727D03*
X1480853Y1028523D03*
Y1041340D03*
X1482704Y1038136D03*
X1480853Y1047749D03*
X1484553Y1034931D03*
X1480853D03*
Y1060565D03*
X1482704Y1057361D03*
Y1050952D03*
X1484553Y1054157D03*
X1480853D03*
Y1079791D03*
X1482704Y1076587D03*
Y1070178D03*
X1480853Y1066974D03*
X1484553Y1073383D03*
X1480853D03*
X1486404Y1095813D03*
X1482703D03*
X1482704Y1089404D03*
X1480853Y1086200D03*
X1484553Y1092608D03*
X1480853D03*
X1493804Y1102221D03*
X1491953Y1099017D03*
X1486404Y1102221D03*
X1479003Y1108629D03*
X1488254Y1105426D03*
X1484554Y1111833D03*
X1482703Y1102220D03*
X1480854Y1111833D03*
Y1105426D03*
X1486403Y1108630D03*
X1488254Y1111833D03*
X1484554Y1105426D03*
X1479004Y1115039D03*
Y1121447D03*
X1493804D03*
X1486404D03*
X1482703Y1115038D03*
X1479004Y1134264D03*
X1493804D03*
X1486404D03*
X1495220Y848176D03*
X1508171Y864197D03*
X1510021Y854584D03*
X1495220Y867401D03*
X1502621D03*
X1495220Y860993D03*
X1502621D03*
X1500771Y870606D03*
X1508171D03*
X1497071D03*
X1498920Y873810D03*
X1504471Y870606D03*
X1506321Y873810D03*
X1495220Y880219D03*
X1497071Y883423D03*
X1502621Y880219D03*
X1504471Y883423D03*
X1500771D03*
X1495220Y873810D03*
X1502621D03*
X1506320Y893036D03*
X1498920Y886627D03*
X1506321D03*
X1495220D03*
X1502621D03*
X1510021D03*
X1495655Y1002888D03*
X1506753D03*
X1508603Y999684D03*
X1503053Y1002888D03*
X1501204Y999684D03*
X1506753Y1105426D03*
X1504904Y1102221D03*
X1501204D03*
X1499354Y1099017D03*
X1503053Y1118243D03*
X1510453D03*
X1501204Y1121447D03*
X1508603Y1121446D03*
X1510453Y1124650D03*
X1508603Y1127855D03*
X1501204Y1134264D03*
X1508603Y1140973D03*
X1504903D03*
X1519271Y851380D03*
X1515571D03*
X1511871Y864197D03*
X1519270D03*
X1522970D03*
X1511871Y857789D03*
X1519271D03*
X1515571D03*
X1517421Y860993D03*
Y854584D03*
X1517853Y1118243D03*
X1519703Y1121446D03*
X1516003Y1127855D03*
X1512303D03*
Y1121446D03*
X1516003D03*
X1517853Y1124650D03*
X1519703Y1127855D03*
X1514154Y1131059D03*
X1611475Y1259227D03*
X1714440Y1255381D03*
X1821083Y1252034D03*
G54D39*
X322500Y1391830D03*
X537477Y1395413D03*
X1298642Y1391830D03*
X1513618Y1395413D03*
G54D10*
X27559Y87795D03*
X40708Y631890D03*
Y1368897D03*
X51181Y1714961D03*
X373622Y87795D03*
X395670Y1714961D03*
X661023Y631890D03*
X707677Y1714961D03*
X800787Y87795D03*
X931692Y757874D03*
Y1072834D03*
Y1387795D03*
X1045865Y87795D03*
X1155708Y1714961D03*
X1271260Y631890D03*
X1461805Y1714961D03*
X1499606Y87795D03*
X1816771Y631890D03*
Y1368897D03*
X1806299Y1714961D03*
X1829921Y87795D03*
G54D36*
X277098Y185236D03*
X395208D03*
G54D32*
X205159Y1430034D03*
X393067Y1354446D03*
X422833D03*
X453169D03*
X468443Y1379662D03*
X482543Y1353962D03*
X718638Y1429579D03*
X1178470Y1466363D03*
X1369208Y1353946D03*
X1398974D03*
X1429310D03*
X1444043Y1379362D03*
X1459076Y1353946D03*
X1679944Y1463655D03*
X1836248Y269763D03*
Y299056D03*
G54D30*
X174685Y637367D03*
X174393Y668511D03*
X526478Y1439952D03*
X1502956Y1439530D03*
X1682882Y618174D03*
Y669109D03*
X1769790Y194789D03*
X1799350D03*
G54D47*
X493500Y246362D03*
X559236Y1441207D03*
G54D50*
X688500Y1601900D03*
X1041435Y153357D03*
X1056225Y153131D03*
X1099970Y1702570D03*
G54D65*
X1133779Y1653543D03*
G54D37*
X278126Y676260D03*
Y700414D03*
X395771Y1242785D03*
X420171D03*
X444493D03*
X468893D03*
X493293D03*
X1371912D03*
X1396312D03*
X1420634D03*
X1445034D03*
X1469434D03*
G54D28*
X159474Y1320753D03*
X183847Y1320778D03*
X208247D03*
X275289Y575702D03*
Y599861D03*
Y624015D03*
Y648169D03*
X673093Y1320778D03*
X697466Y1320803D03*
X721866D03*
X1100800Y251488D03*
X1100700Y275788D03*
X1131100Y1357088D03*
X1155500D03*
X1179900D03*
X1577000Y591888D03*
Y616388D03*
Y640888D03*
Y665288D03*
Y689788D03*
Y714288D03*
X1634259Y1354374D03*
X1658632Y1354399D03*
X1683032D03*
G54D77*
X1902608Y988322D03*
X1902682Y1351295D03*
X1951178Y1349597D03*
X1993618Y1349897D03*
G54D74*
X1881720Y988279D03*
X1881211Y1350983D03*
X1930200Y1349548D03*
X1972697Y1349606D03*
G54D23*
X40120Y744554D03*
Y1000853D03*
Y1287664D03*
X69820Y744554D03*
Y1000853D03*
Y1287664D03*
X99520Y744554D03*
Y1000853D03*
Y1287664D03*
X129220Y744554D03*
Y1000853D03*
Y1287664D03*
X158920Y744554D03*
Y1000853D03*
Y1287664D03*
X188620Y744554D03*
Y1000853D03*
Y1287664D03*
X218320Y744554D03*
Y1000853D03*
Y1287664D03*
X248020Y744554D03*
Y1000853D03*
Y1287664D03*
X633320Y744554D03*
Y1000853D03*
Y1287664D03*
X663020Y744554D03*
Y1000853D03*
Y1287664D03*
X692720Y744554D03*
Y1000853D03*
Y1287664D03*
X722420Y744554D03*
Y1000853D03*
Y1287664D03*
X752120Y744554D03*
Y1000853D03*
Y1287664D03*
X781820Y744554D03*
Y1000853D03*
Y1287664D03*
X811520Y744554D03*
Y1000853D03*
Y1287664D03*
X841220Y744554D03*
Y1000853D03*
Y1287664D03*
X1016262Y744554D03*
Y1000853D03*
Y1287664D03*
X1045962Y744554D03*
Y1000853D03*
Y1287664D03*
X1075662Y744554D03*
Y1000853D03*
Y1287664D03*
X1105362Y744554D03*
Y1000853D03*
Y1287664D03*
X1135062Y744554D03*
Y1000853D03*
Y1287664D03*
X1164762Y744554D03*
Y1000853D03*
Y1287664D03*
X1194462Y744554D03*
Y1000853D03*
Y1287664D03*
X1224162Y744554D03*
Y1000853D03*
Y1287664D03*
X1609462Y744554D03*
Y1000853D03*
Y1287664D03*
X1639162Y744554D03*
Y1000853D03*
Y1287664D03*
X1668862Y744554D03*
Y1000853D03*
Y1287664D03*
X1698562Y744554D03*
Y1000853D03*
Y1287664D03*
X1728262Y744554D03*
Y1000853D03*
Y1287664D03*
X1757962Y744554D03*
Y1000853D03*
Y1287664D03*
X1787662Y744554D03*
Y1000853D03*
Y1287664D03*
X1817362Y744554D03*
Y1000853D03*
Y1287664D03*
G54D60*
X928739Y321653D03*
G54D33*
X250326Y185236D03*
X368437D03*
G54D61*
X916545Y309459D03*
X911494Y321653D03*
X916545Y333847D03*
X940933Y309459D03*
X928739Y304408D03*
Y338898D03*
X940933Y333847D03*
X945984Y321653D03*
G54D67*
X1247638Y269488D03*
X1405118Y112008D03*
X1766929Y1714960D03*
G54D13*
X19685Y-29134D03*
Y1803261D03*
X1837795Y-29134D03*
Y1803261D03*
X2081889Y-29134D03*
Y1803261D03*
G54D68*
X1405876Y1453298D03*
X1430204Y1452014D03*
G54D18*
X38346Y1420330D03*
X117932Y605380D03*
X763601Y605413D03*
X1094074Y605380D03*
X1739706Y605455D03*
X1819208Y1420330D03*
G54D21*
X49280Y337402D03*
X41870Y1511291D03*
X441043Y1672205D03*
Y1718465D03*
X1416437Y1672204D03*
Y1718464D03*
X1808192Y1569255D03*
X1812980Y502472D03*
G54D38*
X306772Y991220D03*
X350099Y811121D03*
X356063Y1171318D03*
X531240Y811121D03*
X525276Y1171318D03*
X574567Y991220D03*
X1282914D03*
X1326240Y811121D03*
X1332205Y1171318D03*
X1507382Y811121D03*
X1501418Y1171318D03*
X1550709Y991220D03*
G54D53*
X791280Y1704890D03*
X1066280D03*
G54D34*
X238780Y1648385D03*
X230906Y1644448D03*
X238780Y1662558D03*
X230906Y1658621D03*
X238780Y1676732D03*
X230906Y1672795D03*
X238780Y1690905D03*
X230906Y1686968D03*
X238780Y1705078D03*
X230906Y1701141D03*
Y1715314D03*
X238780Y1719251D03*
X230906Y1729488D03*
X238780Y1733425D03*
X254528Y1648385D03*
X246654Y1644448D03*
X254528Y1662558D03*
X246654Y1658621D03*
X254528Y1676732D03*
X246654Y1672795D03*
X254528Y1690905D03*
X246654Y1686968D03*
X254528Y1705078D03*
X246654Y1701141D03*
Y1715314D03*
X254528Y1719251D03*
X246654Y1729488D03*
X254528Y1733425D03*
X270276Y1648385D03*
X262402Y1644448D03*
X270276Y1662558D03*
X262402Y1658621D03*
X270276Y1676732D03*
X262402Y1672795D03*
X270276Y1690905D03*
X262402Y1686968D03*
X270276Y1705078D03*
X262402Y1701141D03*
Y1715314D03*
X270276Y1719251D03*
X262402Y1729488D03*
X270276Y1733425D03*
X286024Y1648385D03*
X278150Y1644448D03*
X286024Y1662558D03*
X278150Y1658621D03*
X286024Y1676732D03*
X278150Y1672795D03*
X286024Y1690905D03*
X278150Y1686968D03*
X286024Y1705078D03*
X278150Y1701141D03*
Y1715314D03*
X286024Y1719251D03*
X278150Y1729488D03*
X286024Y1733425D03*
X297835Y1672795D03*
X305709Y1676732D03*
X297835Y1686968D03*
X305709Y1690905D03*
X297835Y1701141D03*
X305709Y1705078D03*
X297835Y1715314D03*
X305709Y1719251D03*
X297835Y1729488D03*
X305709Y1733425D03*
X313583Y1672795D03*
X321457Y1676732D03*
X313583Y1686968D03*
X321457Y1690905D03*
X313583Y1701141D03*
X321457Y1705078D03*
X313583Y1715314D03*
X321457Y1719251D03*
X313583Y1729488D03*
X321457Y1733425D03*
X329331Y1672795D03*
X337205Y1676732D03*
X329331Y1686968D03*
X337205Y1690905D03*
X329331Y1701141D03*
X337205Y1705078D03*
X329331Y1715314D03*
X337205Y1719251D03*
X329331Y1729488D03*
X337205Y1733425D03*
X345079Y1672795D03*
X352953Y1676732D03*
X345079Y1686968D03*
X352953Y1690905D03*
X345079Y1701141D03*
X352953Y1705078D03*
X345079Y1715314D03*
X352953Y1719251D03*
X345079Y1729488D03*
X352953Y1733425D03*
X495079Y1672795D03*
Y1686968D03*
Y1701141D03*
Y1715314D03*
Y1729488D03*
X510827Y1672795D03*
X502953Y1676732D03*
X518701D03*
X510827Y1686968D03*
X502953Y1690905D03*
X518701D03*
X510827Y1701141D03*
X502953Y1705078D03*
X518701D03*
X510827Y1715314D03*
X502953Y1719251D03*
X518701D03*
X510827Y1729488D03*
X502953Y1733425D03*
X518701D03*
X526575Y1672795D03*
X534449Y1676732D03*
X526575Y1686968D03*
X534449Y1690905D03*
X526575Y1701141D03*
X534449Y1705078D03*
X526575Y1715314D03*
X534449Y1719251D03*
X526575Y1729488D03*
X534449Y1733425D03*
X542323Y1672795D03*
X550197Y1676732D03*
X542323Y1686968D03*
X550197Y1690905D03*
X542323Y1701141D03*
X550197Y1705078D03*
X542323Y1715314D03*
X550197Y1719251D03*
X542323Y1729488D03*
X550197Y1733425D03*
X562008Y1672795D03*
Y1686968D03*
Y1701141D03*
Y1715314D03*
Y1729488D03*
X577756Y1672795D03*
X569882Y1676732D03*
X577756Y1686968D03*
X569882Y1690905D03*
X577756Y1701141D03*
X569882Y1705078D03*
X577756Y1715314D03*
X569882Y1719251D03*
X577756Y1729488D03*
X569882Y1733425D03*
X593504Y1672795D03*
X585630Y1676732D03*
X593504Y1686968D03*
X585630Y1690905D03*
X593504Y1701141D03*
X585630Y1705078D03*
X593504Y1715314D03*
X585630Y1719251D03*
X593504Y1729488D03*
X585630Y1733425D03*
X609252Y1672795D03*
X601378Y1676732D03*
X609252Y1686968D03*
X601378Y1690905D03*
X609252Y1701141D03*
X601378Y1705078D03*
X609252Y1715314D03*
X601378Y1719251D03*
X609252Y1729488D03*
X601378Y1733425D03*
X617126Y1676732D03*
Y1690905D03*
Y1705078D03*
Y1719251D03*
Y1733425D03*
X1238780Y1672795D03*
X1246654Y1676732D03*
X1238780Y1686968D03*
X1246654Y1690905D03*
X1238780Y1701141D03*
X1246654Y1705078D03*
X1238780Y1715314D03*
X1246654Y1719251D03*
X1238780Y1729488D03*
X1246654Y1733425D03*
X1254528Y1672795D03*
X1262402Y1676732D03*
X1254528Y1686968D03*
X1262402Y1690905D03*
X1254528Y1701141D03*
X1262402Y1705078D03*
X1254528Y1715314D03*
X1262402Y1719251D03*
X1254528Y1729488D03*
X1262402Y1733425D03*
X1270276Y1672795D03*
X1278150Y1676732D03*
X1270276Y1686968D03*
X1278150Y1690905D03*
X1270276Y1701141D03*
X1278150Y1705078D03*
X1270276Y1715314D03*
X1278150Y1719251D03*
X1270276Y1729488D03*
X1278150Y1733425D03*
X1286024Y1672795D03*
X1293898Y1676732D03*
X1286024Y1686968D03*
X1293898Y1690905D03*
X1286024Y1701141D03*
X1293898Y1705078D03*
X1286024Y1715314D03*
X1293898Y1719251D03*
X1286024Y1729488D03*
X1293898Y1733425D03*
X1305709Y1672795D03*
X1313583Y1676732D03*
X1305709Y1686968D03*
X1313583Y1690905D03*
X1305709Y1701141D03*
X1313583Y1705078D03*
X1305709Y1715314D03*
X1313583Y1719251D03*
X1305709Y1729488D03*
X1313583Y1733425D03*
X1321457Y1672795D03*
X1329331Y1676732D03*
X1321457Y1686968D03*
X1329331Y1690905D03*
X1321457Y1701141D03*
X1329331Y1705078D03*
X1321457Y1715314D03*
X1329331Y1719251D03*
X1321457Y1729488D03*
X1329331Y1733425D03*
X1337205Y1672795D03*
X1345079Y1676732D03*
X1337205Y1686968D03*
X1345079Y1690905D03*
X1337205Y1701141D03*
X1345079Y1705078D03*
X1337205Y1715314D03*
X1345079Y1719251D03*
X1337205Y1729488D03*
X1345079Y1733425D03*
X1352953Y1672795D03*
X1360827Y1676732D03*
X1352953Y1686968D03*
X1360827Y1690905D03*
X1352953Y1701141D03*
X1360827Y1705078D03*
X1352953Y1715314D03*
X1360827Y1719251D03*
X1352953Y1729488D03*
X1360827Y1733425D03*
X1502953Y1672795D03*
X1510827Y1676732D03*
X1502953Y1686968D03*
X1510827Y1690905D03*
X1502953Y1701141D03*
X1510827Y1705078D03*
X1502953Y1715314D03*
X1510827Y1719251D03*
X1502953Y1729488D03*
X1510827Y1733425D03*
X1518701Y1672795D03*
X1526575Y1676732D03*
X1518701Y1686968D03*
X1526575Y1690905D03*
X1518701Y1701141D03*
X1526575Y1705078D03*
X1518701Y1715314D03*
X1526575Y1719251D03*
X1518701Y1729488D03*
X1526575Y1733425D03*
X1534449Y1672795D03*
X1542323Y1676732D03*
X1534449Y1686968D03*
X1542323Y1690905D03*
X1534449Y1701141D03*
X1542323Y1705078D03*
X1534449Y1715314D03*
X1542323Y1719251D03*
X1534449Y1729488D03*
X1542323Y1733425D03*
X1550197Y1672795D03*
X1558071Y1676732D03*
X1550197Y1686968D03*
X1558071Y1690905D03*
X1550197Y1701141D03*
X1558071Y1705078D03*
X1550197Y1715314D03*
X1558071Y1719251D03*
X1550197Y1729488D03*
X1558071Y1733425D03*
X1569882Y1672795D03*
Y1686968D03*
Y1701141D03*
Y1715314D03*
Y1729488D03*
X1585630Y1672795D03*
X1577756Y1676732D03*
X1585630Y1686968D03*
X1577756Y1690905D03*
X1585630Y1701141D03*
X1577756Y1705078D03*
X1585630Y1715314D03*
X1577756Y1719251D03*
X1585630Y1729488D03*
X1577756Y1733425D03*
X1601378Y1672795D03*
X1593504Y1676732D03*
X1601378Y1686968D03*
X1593504Y1690905D03*
X1601378Y1701141D03*
X1593504Y1705078D03*
X1601378Y1715314D03*
X1593504Y1719251D03*
X1601378Y1729488D03*
X1593504Y1733425D03*
X1617126Y1672795D03*
X1609252Y1676732D03*
X1625000D03*
X1617126Y1686968D03*
X1609252Y1690905D03*
X1625000D03*
X1617126Y1701141D03*
X1609252Y1705078D03*
X1625000D03*
X1617126Y1715314D03*
X1609252Y1719251D03*
X1625000D03*
X1617126Y1729488D03*
X1609252Y1733425D03*
X1625000D03*
G54D44*
X441043Y1698268D03*
X1416437Y1698267D03*
G54D55*
X805690Y204724D03*
X1057658D03*
G54D20*
X41492Y290637D03*
X44833Y1659909D03*
X61340Y384362D03*
X61250Y396142D03*
X49250Y396332D03*
X49400Y384392D03*
X47618Y413113D03*
X47619Y421155D03*
X56799Y1524094D03*
Y1528094D03*
Y1532094D03*
Y1544094D03*
Y1548094D03*
Y1552094D03*
Y1556094D03*
X54333Y1604359D03*
X50900Y1677775D03*
X65881Y305426D03*
X72774Y1549669D03*
X66906Y1598324D03*
Y1603280D03*
X84274Y1517619D03*
X81038Y1536899D03*
X91538Y1539399D03*
X84700Y1627000D03*
X99274Y1526019D03*
X126225Y504368D03*
X120225D03*
Y510368D03*
X126225Y516368D03*
X120225D03*
X112749Y1524594D03*
Y1540594D03*
Y1544594D03*
Y1548594D03*
Y1536594D03*
Y1564594D03*
Y1560594D03*
X132225Y504368D03*
Y510368D03*
X132401Y516368D03*
X129670Y1563160D03*
X153271Y1540961D03*
X153138Y1549032D03*
X166986Y575918D03*
X161321Y1540858D03*
X161374Y1549073D03*
X189800Y705062D03*
X208312Y576125D03*
X196526Y567825D03*
X208312Y581085D03*
Y578605D03*
X197423Y601496D03*
X194059Y604901D03*
X208312Y615085D03*
Y610125D03*
Y612605D03*
X194059Y638901D03*
X197423Y635496D03*
X208312Y649085D03*
Y644125D03*
Y646605D03*
X213912Y576125D03*
X220668Y574131D03*
X223775D03*
X224064Y568113D03*
X221464D03*
X213912Y578605D03*
Y581085D03*
X217556Y590575D03*
X217561Y582131D03*
Y579531D03*
X223775Y587731D03*
X223759Y590675D03*
X220652D03*
X223775Y584531D03*
X220668Y576731D03*
Y579331D03*
X223775Y581931D03*
Y579331D03*
Y576731D03*
X220668Y581931D03*
Y608131D03*
X223775D03*
X224064Y602113D03*
X221464D03*
X223403Y596820D03*
Y594220D03*
X213912Y612605D03*
Y615085D03*
Y610125D03*
X217561Y616131D03*
Y613531D03*
X217556Y624575D03*
X223759Y624675D03*
X220652D03*
X223775Y618531D03*
X220668Y610731D03*
Y613331D03*
X223775Y615931D03*
Y613331D03*
Y610731D03*
X220668Y615931D03*
X223775Y621731D03*
X223403Y630820D03*
Y628220D03*
X224064Y636113D03*
X221464D03*
X213912Y646605D03*
Y649085D03*
Y644125D03*
X217561Y650131D03*
Y647531D03*
X223775Y655731D03*
Y652531D03*
X220668Y644731D03*
Y647331D03*
Y642131D03*
X223775Y649931D03*
Y647331D03*
Y644731D03*
Y642131D03*
X220668Y649931D03*
X217556Y658575D03*
X223403Y664820D03*
X223759Y658675D03*
X220652D03*
X217510Y668712D03*
X225167Y672006D03*
X222567D03*
X219967D03*
X217367D03*
X211348Y688087D03*
Y685287D03*
X214100Y687376D03*
Y690376D03*
Y684376D03*
Y681376D03*
Y678376D03*
X211348Y690787D03*
Y693587D03*
X214100Y693576D03*
X224506Y698138D03*
Y700738D03*
X221906Y698138D03*
Y700738D03*
X219306D03*
Y698138D03*
X231864Y568113D03*
X229264D03*
X226664D03*
X238393Y570490D03*
X240993D03*
X229264Y602113D03*
X226664D03*
X226003Y594220D03*
Y596820D03*
X228603Y594220D03*
Y596820D03*
X231864Y602113D03*
X233803Y594220D03*
Y596820D03*
X231203Y594220D03*
Y596820D03*
X238393Y604490D03*
X240993D03*
Y596820D03*
X238393D03*
X240993Y594220D03*
X238393D03*
X226003Y628220D03*
Y630820D03*
X228603Y628220D03*
Y630820D03*
X231864Y636113D03*
X233803Y628220D03*
Y630820D03*
X231203Y628220D03*
Y630820D03*
X229264Y636113D03*
X226664D03*
X238393Y638490D03*
X240993D03*
Y630820D03*
X238393D03*
X240993Y628220D03*
X238393D03*
X228603Y664820D03*
X233803D03*
X231203D03*
X226003D03*
X230367Y672006D03*
X227767D03*
X227106Y698138D03*
Y700738D03*
X246400Y563162D03*
X263580Y218627D03*
X318651Y22921D03*
X320825Y159062D03*
X410700Y1658460D03*
X435340Y125346D03*
X435240Y1609200D03*
X433383Y1602629D03*
X450380Y104647D03*
X440019Y1576809D03*
X442128Y1574879D03*
X441308Y1602654D03*
X505055Y1387601D03*
Y1382301D03*
Y1396001D03*
Y1398601D03*
Y1390201D03*
X563634Y1334315D03*
X561034D03*
X612670Y142872D03*
X612520Y154812D03*
X624610Y142842D03*
X624520Y154622D03*
X702975Y414864D03*
X739206Y608020D03*
Y603064D03*
X758830Y1674823D03*
X819114Y115223D03*
X824498Y145198D03*
X831114Y115223D03*
X829114Y150273D03*
X854577Y99651D03*
X876124Y66072D03*
Y86072D03*
Y106072D03*
Y126072D03*
X887869Y386618D03*
X881372Y920655D03*
X898062Y976652D03*
Y969716D03*
X942646Y400793D03*
X946865Y974077D03*
X953235Y972642D03*
X946938Y991162D03*
X943720Y985772D03*
X956022Y1620730D03*
X953022D03*
Y1632730D03*
X956022D03*
Y1629730D03*
X953022D03*
X956022Y1626730D03*
X953022D03*
Y1623730D03*
X956022D03*
X963610Y981292D03*
X959535Y990477D03*
X963780Y997496D03*
X962022Y1620730D03*
X959022D03*
Y1632730D03*
X962022D03*
Y1629730D03*
X959022D03*
X962022Y1626730D03*
X959022D03*
Y1623730D03*
X962022D03*
X978403Y-9022D03*
Y-13978D03*
Y-19022D03*
Y-23978D03*
Y6022D03*
Y10978D03*
Y20978D03*
Y16022D03*
X988835Y185443D03*
X989500Y376362D03*
X985672Y432961D03*
X987662Y1620870D03*
Y1629870D03*
Y1626870D03*
Y1623870D03*
Y1632870D03*
X1002500Y266862D03*
X991770Y418835D03*
X992608Y432961D03*
X1002640Y594692D03*
X990662Y1620870D03*
X993662D03*
Y1629870D03*
X990662D03*
X993662Y1626870D03*
X990662D03*
Y1623870D03*
X993662D03*
X990662Y1632870D03*
X993662D03*
X1001810Y1662700D03*
Y1665200D03*
X1018000Y263862D03*
X1022000Y264362D03*
X1014500Y263862D03*
X1010500D03*
X1018000Y266862D03*
X1010500D03*
X1006500D03*
X1014500D03*
X1011611Y430038D03*
X1019252Y1620870D03*
X1022252D03*
Y1623870D03*
Y1626870D03*
X1019252Y1623870D03*
Y1626870D03*
X1019910Y1662700D03*
Y1665200D03*
X1025000Y264362D03*
X1038220Y589862D03*
X1030980Y598722D03*
X1023740Y596152D03*
X1036480Y596272D03*
X1025252Y1620870D03*
Y1623870D03*
Y1626870D03*
X1023580Y1662700D03*
Y1665200D03*
X1027370Y1662700D03*
Y1665200D03*
X1040924Y286073D03*
X1043720Y589362D03*
X1050200Y598062D03*
X1050390Y604172D03*
X1053200Y612162D03*
X1050721Y1633043D03*
X1053721D03*
Y1624043D03*
Y1627043D03*
Y1630043D03*
X1050721Y1624043D03*
Y1627043D03*
Y1630043D03*
X1053721Y1621043D03*
X1050721D03*
X1044850Y1665050D03*
Y1662550D03*
X1067718Y288500D03*
X1070618D03*
X1056280Y601232D03*
X1056721Y1633043D03*
Y1624043D03*
Y1627043D03*
Y1630043D03*
Y1621043D03*
X1095900Y1646935D03*
X1095649Y1638875D03*
X1099457D03*
X1104457Y1675490D03*
X1120544Y312200D03*
X1129995Y301637D03*
X1150914Y197407D03*
X1148354Y222677D03*
X1150272Y638346D03*
X1160720Y180862D03*
X1165000Y190962D03*
X1162500D03*
X1164300Y197262D03*
X1163732Y204887D03*
X1160732D03*
X1158172Y230157D03*
X1159912Y638216D03*
X1166722Y636206D03*
X1158762Y642266D03*
X1168402Y642136D03*
X1159930Y1645632D03*
X1164830D03*
X1161613Y1669112D03*
X1173065Y194174D03*
X1172865Y210174D03*
X1172795Y222174D03*
X1180398Y289814D03*
X1171540Y310902D03*
X1176362Y636076D03*
X1180262Y642216D03*
X1181930Y1645632D03*
X1186830D03*
X1175830D03*
X1170930D03*
X1183613Y1669112D03*
X1172613D03*
X1189902Y642086D03*
X1192500Y1645942D03*
X1197400D03*
X1194183Y1669422D03*
X1192340Y1691422D03*
X1197240D03*
X1194023Y1714902D03*
X1206093Y120362D03*
X1214593Y168962D03*
X1208518Y174162D03*
X1203858Y185451D03*
X1208365Y271151D03*
X1210457Y1658415D03*
X1218810Y1691732D03*
X1213910D03*
X1203110Y1691467D03*
X1208010D03*
X1215593Y1715212D03*
X1204793Y1714947D03*
X1228704Y112122D03*
X1223100Y127300D03*
X1226093Y152792D03*
X1227500Y380400D03*
X1242520Y165362D03*
X1236593Y209562D03*
X1236584Y217462D03*
X1245614Y227462D03*
X1266093Y129962D03*
X1256093Y143462D03*
X1264685Y175506D03*
X1279485Y105752D03*
X1278949Y123567D03*
X1282293Y248962D03*
X1275557Y269477D03*
Y272436D03*
X1282653Y269446D03*
X1278557Y272436D03*
Y269477D03*
X1272557Y272436D03*
X1287795Y-29033D03*
Y-33989D03*
Y-9033D03*
Y-13989D03*
Y-19033D03*
Y-23989D03*
Y967D03*
Y-3989D03*
X1293430Y84072D03*
X1294354Y105912D03*
X1295053Y140181D03*
X1292293Y143162D03*
X1287943Y233748D03*
X1284437Y230280D03*
X1293893Y237962D03*
X1286611Y260908D03*
X1295887Y315571D03*
X1314741Y68652D03*
X1300454Y95302D03*
X1302964Y124633D03*
X1301993Y140462D03*
X1313950Y261612D03*
X1308790Y290172D03*
X1302450Y290072D03*
X1307798Y287561D03*
X1313246Y287631D03*
X1308220Y304262D03*
X1303120Y304162D03*
X1330102Y59025D03*
X1327920Y84418D03*
X1316478Y92970D03*
X1330273Y128373D03*
X1326493Y249562D03*
X1317893Y257462D03*
X1328393Y264262D03*
X1339280Y126175D03*
X1356223Y131569D03*
X1362793Y145262D03*
X1366124Y101529D03*
X1377597Y197604D03*
X1375300Y208422D03*
X1378452Y236055D03*
X1389609Y145291D03*
X1389443Y147859D03*
X1386780Y197668D03*
X1395321D03*
X1409558Y151948D03*
Y156904D03*
X1401240Y171672D03*
X1404071Y197668D03*
X1412851D03*
X1398700Y1597800D03*
X1436436Y300319D03*
X1456423Y209362D03*
X1453823Y205982D03*
X1445777Y362021D03*
X1449296Y410497D03*
X1451580Y1627990D03*
X1462777Y362021D03*
X1470877Y374496D03*
X1463277Y406446D03*
X1470954D03*
X1476570Y1657974D03*
X1480154Y-29033D03*
Y-33989D03*
Y-9033D03*
Y-13989D03*
Y-19033D03*
Y-23989D03*
Y967D03*
Y-3989D03*
X1481155Y1387742D03*
X1481255Y1382042D03*
X1481155Y1396342D03*
Y1398942D03*
Y1390342D03*
X1478724Y1637189D03*
X1505821Y215802D03*
X1524770Y195792D03*
X1521201Y215551D03*
X1531750Y199762D03*
X1529610Y211614D03*
X1532590Y225432D03*
X1561494Y584292D03*
X1604040Y219692D03*
X1604290Y242472D03*
X1636393Y181778D03*
X1632899Y213012D03*
X1670004Y537065D03*
Y543065D03*
Y531065D03*
X1683394Y469878D03*
X1683476Y473378D03*
X1684356Y476290D03*
X1681602Y485180D03*
X1684356Y485628D03*
X1677464Y491790D03*
X1682004Y537065D03*
X1682180Y543065D03*
X1676004D03*
X1682004Y531065D03*
X1676004D03*
X1697648Y463724D03*
X1693648D03*
X1692883Y703943D03*
X1709027Y655141D03*
X1725473Y474859D03*
X1754307Y262186D03*
X1751068Y262123D03*
X1754245Y269724D03*
X1751068Y266048D03*
X1754307Y266111D03*
X1754414Y275329D03*
X1752165Y273901D03*
X1749565D03*
X1751006Y269661D03*
X1749595Y276711D03*
X1752195D03*
X1748989Y380206D03*
X1764955Y301951D03*
X1768757Y380498D03*
X1793061Y24659D03*
X1828880Y1626595D03*
Y1646595D03*
Y1666595D03*
Y1686595D03*
X1840691Y329470D03*
Y349470D03*
Y369470D03*
Y389470D03*
Y409470D03*
Y429470D03*
Y449470D03*
Y469470D03*
Y489470D03*
Y509470D03*
Y529470D03*
Y549470D03*
Y569470D03*
Y589470D03*
Y669470D03*
Y1329470D03*
Y1409470D03*
Y1429470D03*
Y1449470D03*
Y1469470D03*
Y1489470D03*
Y1509470D03*
Y1529470D03*
Y1549470D03*
Y1569470D03*
Y1589470D03*
X1854470Y112379D03*
Y152379D03*
Y172379D03*
Y192379D03*
Y212379D03*
Y232379D03*
Y252379D03*
Y272379D03*
Y292379D03*
G54D59*
X922441Y154311D03*
Y243799D03*
G54D12*
X14092Y287115D03*
X17371Y49388D03*
X22223Y388057D03*
X29509Y398132D03*
X29962Y401000D03*
X24700Y765600D03*
X37371Y49388D03*
X36255Y304972D03*
X42809Y360862D03*
X39410Y384582D03*
X39226Y395346D03*
X33020Y382822D03*
X36524Y398013D03*
X30680Y438142D03*
X58379Y69340D03*
X60379Y66844D03*
Y71836D03*
X60692Y87118D03*
X54920Y185039D03*
Y177165D03*
X46834Y360862D03*
X55190D03*
X53825Y421746D03*
X54762Y444993D03*
X53800Y435451D03*
X58658Y754145D03*
X55177Y1322328D03*
X55277Y1326068D03*
X46994Y1663165D03*
X69058Y3010D03*
X79047Y23978D03*
X74091D03*
X72091Y25974D03*
X73020Y37106D03*
Y48720D03*
X67335Y69340D03*
X65335Y66844D03*
Y71836D03*
X65648Y87118D03*
X71379Y72844D03*
Y77836D03*
X76335Y72844D03*
Y77836D03*
X78335Y75340D03*
X69379D03*
X71772Y421746D03*
X75490Y432519D03*
X68365Y443677D03*
X64150Y434972D03*
X74340Y663422D03*
X76365Y699244D03*
X76565Y717949D03*
X72315Y717414D03*
X64325Y715674D03*
X75564Y1509952D03*
X78120Y1512936D03*
Y1521336D03*
X75922Y1564874D03*
Y1556474D03*
X73429Y1570008D03*
X78415D03*
X73832Y1689362D03*
X77833Y1689162D03*
X89058Y3010D03*
X81196Y17042D03*
Y22034D03*
X86152Y17042D03*
Y22034D03*
X95369Y17042D03*
Y22034D03*
X79196Y19538D03*
X88152D03*
X93369D03*
X88264Y23978D03*
X93220D03*
X86264Y25974D03*
X95220D03*
X81047D03*
X94279Y37106D03*
X87193D03*
X80106D03*
X94279Y48720D03*
X87193D03*
X80106D03*
X80379Y69340D03*
X89335D03*
X82379Y66844D03*
Y71836D03*
X87335Y66844D03*
Y71836D03*
X91379Y75340D03*
X93379Y72844D03*
Y77836D03*
X86490Y200787D03*
Y208661D03*
X85960Y224409D03*
X85788Y240157D03*
X90700Y282762D03*
Y300262D03*
X87654Y376026D03*
X87520Y386502D03*
X94811Y510173D03*
X80460Y655672D03*
X83100Y649762D03*
X82735Y717949D03*
X87865Y714394D03*
X85165D03*
X81225Y715854D03*
X79635Y717949D03*
X85835Y718049D03*
X93295Y762019D03*
X92071Y1492888D03*
X80649Y1509944D03*
X93544Y1510099D03*
X88459Y1510107D03*
X90998Y1513037D03*
Y1521437D03*
X84048Y1578008D03*
X90713Y1585852D03*
Y1589852D03*
Y1593867D03*
X90788Y1611821D03*
Y1605867D03*
Y1623821D03*
X90698Y1638362D03*
Y1634362D03*
X86245Y1690362D03*
X81833Y1689162D03*
X94220Y1686622D03*
X109058Y3010D03*
X100325Y17042D03*
Y22034D03*
X109542Y17042D03*
Y22034D03*
X102325Y19538D03*
X107542D03*
X102437Y23978D03*
X107393D03*
X100437Y25974D03*
X109393D03*
X108453Y37106D03*
X101366D03*
X108453Y48720D03*
X101366D03*
X102379Y69340D03*
X111335D03*
X104379Y66844D03*
Y71836D03*
X109335Y66844D03*
Y71836D03*
X98335Y72844D03*
Y77836D03*
X100335Y75340D03*
X101317Y431727D03*
X102060Y493578D03*
X111087Y520052D03*
X98134Y722501D03*
X99716Y1567878D03*
X99750Y1559478D03*
X96251Y1577532D03*
X107451Y1574704D03*
X100451D03*
X104318Y1592304D03*
Y1603690D03*
X110200Y1605200D03*
X104318Y1622380D03*
Y1641075D03*
X99980Y1685362D03*
Y1696052D03*
X114498Y17042D03*
Y22034D03*
X123716Y17042D03*
Y22034D03*
X116498Y19538D03*
X121716D03*
X121567Y23978D03*
X116611D03*
X114611Y25974D03*
X123567D03*
X122626Y37106D03*
X115539D03*
X122626Y48720D03*
X115539D03*
X124379Y69340D03*
X126379Y66844D03*
Y71836D03*
X115379Y72844D03*
Y77836D03*
X120335Y72844D03*
Y77836D03*
X122335Y75340D03*
X113379D03*
X114087Y285495D03*
Y302854D03*
X127206Y480216D03*
X123257Y547506D03*
X119087D03*
X115060D03*
X120267Y1327697D03*
X127366Y1535855D03*
Y1541874D03*
Y1547935D03*
X116798Y1586288D03*
Y1598572D03*
Y1635303D03*
X127195Y1670362D03*
X117795Y1698862D03*
X127195Y1688362D03*
Y1692362D03*
Y1708362D03*
X117255Y1730422D03*
X129058Y3010D03*
X128672Y17042D03*
Y22034D03*
X130672Y19538D03*
X129713Y37106D03*
Y48720D03*
X133335Y69340D03*
X131335Y66844D03*
Y71836D03*
X137379Y72844D03*
Y77836D03*
X142335Y72844D03*
Y77836D03*
X135379Y75340D03*
X130057Y636103D03*
X129600Y669400D03*
X132967Y760525D03*
X141470Y1359100D03*
X140104Y1560136D03*
X139080Y1731398D03*
X149058Y3010D03*
X159582Y17042D03*
Y22034D03*
X157582Y19538D03*
X152477Y23978D03*
X157433D03*
X150477Y25974D03*
X159433D03*
X158492Y37106D03*
X151405D03*
X158492Y48720D03*
X151405D03*
X146379Y69340D03*
X155335D03*
X148379Y66844D03*
Y71836D03*
X153335Y66844D03*
Y71836D03*
X158583Y75340D03*
X144335D03*
X149371Y423383D03*
Y419383D03*
Y427383D03*
Y439383D03*
Y431383D03*
Y435383D03*
Y443383D03*
X147141Y698811D03*
X147435Y690807D03*
X149861Y698831D03*
X150155Y690807D03*
X156685Y706836D03*
X153965Y706816D03*
X153879Y721660D03*
X156469D03*
X147031Y706835D03*
X149621D03*
X149669Y721660D03*
X147079D03*
X154477Y1360797D03*
X148663Y1378607D03*
X151163D03*
Y1383807D03*
Y1381207D03*
X158318Y1384286D03*
X155718D03*
X158318Y1387393D03*
X155718D03*
X148663Y1386407D03*
X151163D03*
X148663Y1383807D03*
Y1381207D03*
X160201Y1399732D03*
X157731D03*
Y1394132D03*
X160201D03*
X152806Y1414175D03*
X144748Y1514878D03*
X149728D03*
X154581Y1520981D03*
X158570D03*
X150502Y1572021D03*
X145522D03*
X159107Y1571364D03*
X144854Y1702389D03*
X154803Y1708532D03*
X155100Y1723262D03*
X169058Y3010D03*
X164538Y17042D03*
Y22034D03*
X173755Y17042D03*
Y22034D03*
X166538Y19538D03*
X171755D03*
X166650Y23978D03*
X171606D03*
X164650Y25974D03*
X173606D03*
X172665Y37106D03*
X165579D03*
X172665Y48720D03*
X165579D03*
X169583Y69340D03*
X171583Y66844D03*
Y71836D03*
X176539Y66844D03*
Y71836D03*
X165539Y72844D03*
X160583D03*
Y77836D03*
X165539D03*
X167539Y75340D03*
X174327Y230928D03*
X171180Y401885D03*
X163900Y409362D03*
X163132Y493299D03*
X162750Y512502D03*
X172807Y1360797D03*
X160918Y1384286D03*
X163518D03*
Y1387393D03*
X160918D03*
X169318Y1384286D03*
X166118D03*
X172262Y1384302D03*
Y1387409D03*
X174932Y1378797D03*
Y1381397D03*
X163718Y1390500D03*
X161118D03*
X162631Y1399732D03*
Y1394132D03*
X172231Y1390532D03*
X162693Y1411529D03*
X171262Y1443390D03*
X168900Y1520510D03*
X163920D03*
X166476Y1572464D03*
X171456D03*
X166529Y1707678D03*
X166661Y1721211D03*
X189058Y3010D03*
X178711Y17042D03*
Y22034D03*
X180711Y19538D03*
X179752Y37106D03*
Y48720D03*
X191583Y69340D03*
X178539D03*
X182583Y72844D03*
Y77836D03*
X187539Y72844D03*
Y77836D03*
X189539Y75340D03*
X180583D03*
X186457Y393071D03*
Y385071D03*
Y389071D03*
Y405071D03*
X192220Y408662D03*
Y412162D03*
X177871Y421383D03*
Y425383D03*
Y430883D03*
Y443383D03*
X187490Y568752D03*
X190977Y669718D03*
X191976Y684326D03*
X184215Y1361072D03*
X181403Y1361115D03*
X192620Y1360797D03*
X188233Y1387027D03*
Y1379227D03*
Y1381827D03*
Y1384427D03*
X183283Y1387987D03*
X185633Y1387027D03*
X180672Y1387987D03*
X185633Y1379227D03*
X180672Y1380187D03*
X183283D03*
X177532Y1378797D03*
X185633Y1384427D03*
Y1381827D03*
X180672Y1382787D03*
Y1385387D03*
X183283Y1382787D03*
Y1385387D03*
X177421Y1383997D03*
X177532Y1381397D03*
X182653Y1404535D03*
X192767Y1413725D03*
X185643Y1413945D03*
X185895Y1535462D03*
Y1539723D03*
Y1544029D03*
Y1548487D03*
Y1552875D03*
X176793Y1585173D03*
X188119Y1580678D03*
Y1575686D03*
Y1592590D03*
Y1587598D03*
X192529Y1728947D03*
X183822Y1720517D03*
X209058Y3010D03*
X203716Y17042D03*
Y22034D03*
X208672Y17042D03*
Y22034D03*
X201716Y19538D03*
X201567Y23978D03*
X196611D03*
X194611Y25974D03*
X203567D03*
X208784D03*
X202626Y37106D03*
X195539D03*
X202626Y48720D03*
X195539D03*
X200539Y69340D03*
X193583Y66844D03*
Y71836D03*
X198539Y66844D03*
Y71836D03*
X204717Y72844D03*
Y77836D03*
X202717Y75340D03*
X195888Y581071D03*
X194515Y583433D03*
X195888Y615071D03*
X194515Y617433D03*
Y651433D03*
X195888Y649071D03*
X205320Y667562D03*
X207856Y686443D03*
X203043Y686483D03*
X207824Y681560D03*
X203044Y684036D03*
X207834Y684006D03*
X203237Y681549D03*
X199720Y732862D03*
X206720Y731862D03*
X199220Y739362D03*
X207602Y756855D03*
X199602D03*
X201661Y1384286D03*
X193861D03*
X196461D03*
X199061D03*
X201661Y1387393D03*
X193861D03*
X196461D03*
X199061D03*
X204261Y1384286D03*
X207461D03*
X201861Y1390500D03*
X199261D03*
X195874Y1399732D03*
X198344D03*
X200774D03*
X195874Y1394132D03*
X198344D03*
X200774D03*
X201071Y1412173D03*
X193075Y1580678D03*
Y1575686D03*
X200179D03*
X205135D03*
X200179Y1580678D03*
X205135D03*
X193075Y1592590D03*
Y1587598D03*
X200179Y1592590D03*
X205135D03*
X200179Y1587598D03*
X205135D03*
X198375Y1599884D03*
X193419D03*
X205479D03*
X193419Y1616788D03*
Y1611796D03*
X198375D03*
X193419Y1604876D03*
X198375D03*
Y1616788D03*
X205479Y1611796D03*
Y1604876D03*
Y1616788D03*
X207229Y1631181D03*
X193410Y1711606D03*
X205582Y1700867D03*
X196443Y1722197D03*
X217889Y17042D03*
Y22034D03*
X222845Y17042D03*
Y22034D03*
X210672Y19538D03*
X215889D03*
X224845D03*
X215740Y23978D03*
X210784D03*
X217740Y25974D03*
X223886Y37106D03*
X216799D03*
X209713D03*
X223886Y48720D03*
X216799D03*
X209713D03*
X215717Y66844D03*
Y71836D03*
X220673Y66844D03*
Y71836D03*
X213717Y69340D03*
X222673D03*
X209673Y72844D03*
Y77836D03*
X211673Y75340D03*
X224717D03*
X209579Y457222D03*
Y462235D03*
X211220Y740362D03*
X215824Y1361199D03*
X211350Y1360797D03*
X218960Y1388312D03*
X210405Y1384302D03*
Y1387409D03*
X213075Y1381558D03*
X217133Y1384055D03*
X214425Y1384058D03*
X215675Y1381558D03*
X218175D03*
X213075Y1378958D03*
X215675D03*
X218175D03*
X210374Y1390532D03*
X212239Y1580678D03*
X217195D03*
Y1575686D03*
X212239D03*
X224299D03*
Y1580678D03*
X212239Y1587598D03*
X217195D03*
X212239Y1592590D03*
X217195D03*
X224299Y1587598D03*
Y1592590D03*
X210435Y1599884D03*
X222495D03*
X217539D03*
X210435Y1611796D03*
Y1604876D03*
Y1616788D03*
X222495D03*
X217539D03*
X222495Y1604876D03*
Y1611796D03*
X217539Y1604876D03*
Y1611796D03*
X212684Y1720307D03*
X229058Y3010D03*
X238063Y37162D03*
X230972Y37106D03*
Y48720D03*
X226717Y72844D03*
Y77836D03*
X231673Y72844D03*
Y77836D03*
X233673Y75340D03*
X233800Y162692D03*
X237539Y174266D03*
X228550Y420412D03*
X229255Y1575686D03*
Y1580678D03*
X236359D03*
Y1575686D03*
X241315Y1580678D03*
Y1575686D03*
X229255Y1587598D03*
Y1592590D03*
X236359D03*
Y1587598D03*
X241315Y1592590D03*
Y1587598D03*
X229599Y1599884D03*
X234555D03*
X229599Y1604876D03*
Y1611796D03*
X234555Y1604876D03*
Y1611796D03*
X229599Y1616788D03*
X234555D03*
X249058Y3010D03*
X243490Y23002D03*
X247720Y71862D03*
X244300Y59762D03*
X247720Y75862D03*
X251797Y100843D03*
X249735Y152694D03*
X242255Y162512D03*
X249300Y510362D03*
X253800Y515362D03*
X249860Y518222D03*
X248419Y1575686D03*
X253375D03*
X248419Y1580678D03*
X253375D03*
X248419Y1587598D03*
X253375D03*
X248419Y1592590D03*
X253375D03*
X246615Y1599884D03*
X241659D03*
X253719D03*
X241659Y1616788D03*
X246615D03*
Y1604876D03*
X241659D03*
X246615Y1611796D03*
X241659D03*
X253719Y1604876D03*
Y1611796D03*
Y1616788D03*
X269058Y3010D03*
X263280Y35312D03*
X272600Y27182D03*
X271600Y40162D03*
X272361Y120243D03*
X270364Y118415D03*
X261387Y133783D03*
X258257D03*
X264578Y155203D03*
Y159203D03*
X260700Y218662D03*
X268940Y217982D03*
X270745Y207562D03*
X265343Y244460D03*
X272029Y443735D03*
X274270Y746602D03*
X260479Y1580678D03*
X265435D03*
X260479Y1575592D03*
X265435D03*
X272539Y1575686D03*
Y1580678D03*
X260479Y1592590D03*
X265435D03*
X260479Y1587598D03*
X265435D03*
X272539D03*
Y1592590D03*
X258675Y1599884D03*
X270735Y1599790D03*
X265779D03*
X258675Y1604876D03*
Y1611796D03*
Y1616788D03*
X270735D03*
X265779D03*
X270735Y1611796D03*
Y1604876D03*
X265779D03*
Y1611796D03*
X289058Y3010D03*
X285900Y23962D03*
X287952Y39984D03*
X286071Y48720D03*
X286500Y52462D03*
X278984Y48720D03*
X287800Y60062D03*
X283953Y152503D03*
X288520Y157062D03*
X279740Y205962D03*
X276890Y249022D03*
X289920Y248652D03*
X286920D03*
X282420D03*
X287819Y691097D03*
X287820Y727962D03*
X278520Y738072D03*
X290077Y739735D03*
X289047Y760245D03*
X277495Y1575686D03*
Y1580678D03*
X284599D03*
X289555D03*
Y1575686D03*
X284599D03*
X277495Y1587598D03*
Y1592590D03*
X284599D03*
X289555D03*
X284599Y1587598D03*
X289555D03*
X282795Y1599884D03*
X277839D03*
X289899D03*
X282795Y1604876D03*
Y1611796D03*
X277839D03*
Y1604876D03*
X282795Y1616788D03*
X277839D03*
X289899D03*
Y1604876D03*
Y1611796D03*
X291520Y12762D03*
X291660Y21642D03*
X298720Y40017D03*
X306720Y39982D03*
X292942Y67513D03*
X293447Y78573D03*
X293452Y82483D03*
Y85983D03*
X303047Y79373D03*
X299947Y79273D03*
X299657Y92503D03*
X299628Y149203D03*
Y158703D03*
X294553Y153819D03*
X306087Y569718D03*
X294658Y637809D03*
X290680Y745312D03*
X299427Y768265D03*
X303831Y1318566D03*
X303807Y1342225D03*
X303831Y1344866D03*
X304047Y1368565D03*
X296659Y1575686D03*
X301615D03*
X296659Y1580678D03*
X301615D03*
X296659Y1587598D03*
X301615D03*
X296659Y1592590D03*
X301615D03*
X294855Y1599884D03*
X301959D03*
X294855Y1616788D03*
Y1604876D03*
Y1611796D03*
X301959Y1604876D03*
Y1611796D03*
Y1616788D03*
X309058Y3010D03*
X320057Y85803D03*
Y88803D03*
X314200Y585282D03*
X316080Y578262D03*
X320691Y602448D03*
X311820Y598762D03*
X316397Y776125D03*
X312301Y1345539D03*
Y1342432D03*
X309701Y1345539D03*
Y1342432D03*
X316655Y1352295D03*
X314175D03*
X311695D03*
X320101Y1342432D03*
X317701Y1348646D03*
X315101D03*
X314901Y1345539D03*
X317501D03*
X314901Y1342432D03*
X317501D03*
X316655Y1357895D03*
X311695D03*
X314175D03*
X317979Y1371248D03*
X315221Y1372445D03*
X308719Y1580678D03*
X313675D03*
X308719Y1575686D03*
X313675D03*
X320779D03*
Y1580678D03*
X308719Y1592590D03*
X313675D03*
X308719Y1587598D03*
X313675D03*
X320779D03*
Y1592590D03*
X306915Y1599884D03*
X318975D03*
X314019D03*
X306915Y1604876D03*
Y1611796D03*
Y1616788D03*
X318975D03*
X314019D03*
X318975Y1604876D03*
Y1611796D03*
X314019Y1604876D03*
Y1611796D03*
X329535Y49388D03*
X336240Y150738D03*
X330674Y368261D03*
X331760Y705882D03*
X328915Y1337104D03*
X331515D03*
X328915Y1331904D03*
X331515D03*
X328915Y1329304D03*
X331515D03*
X328915Y1334504D03*
X331515D03*
X328915Y1339704D03*
X326145Y1348651D03*
X326245Y1345555D03*
Y1342448D03*
X323301Y1342432D03*
X338917Y1349488D03*
X336347Y1348353D03*
X325735Y1575686D03*
Y1580678D03*
X332839D03*
X337795D03*
X332839Y1575686D03*
X337795D03*
X325735Y1587598D03*
Y1592590D03*
X332839D03*
X337795D03*
X332839Y1587598D03*
X337795D03*
X326079Y1599884D03*
X331035D03*
X338139D03*
X326079Y1604876D03*
Y1611796D03*
X331035Y1604876D03*
Y1611796D03*
X326079Y1616788D03*
X331035D03*
X338139D03*
Y1604876D03*
Y1611796D03*
X349535Y49388D03*
X343040Y122522D03*
X345869Y192716D03*
X353145Y228362D03*
X345164Y314234D03*
X349187Y715485D03*
X344446Y739434D03*
X348000Y755362D03*
X344429Y1322741D03*
X347029D03*
X341829D03*
X347029Y1319634D03*
X344429D03*
X341829D03*
X349629Y1322741D03*
Y1319634D03*
X352229D03*
X355429D03*
X346303Y1335097D03*
X343823D03*
Y1329497D03*
X346303D03*
X347229Y1325848D03*
X348783Y1329497D03*
X349829Y1325848D03*
X348783Y1335097D03*
X348804Y1346877D03*
X350470Y1349030D03*
X344899Y1575686D03*
X349855D03*
X344899Y1580678D03*
X349855D03*
X344899Y1587598D03*
X349855D03*
X344899Y1592590D03*
X349855D03*
X343095Y1599884D03*
X355155D03*
X350199D03*
X343095Y1616788D03*
Y1604876D03*
Y1611796D03*
X355155Y1604876D03*
Y1611796D03*
X350199Y1604876D03*
Y1611796D03*
X355155Y1616788D03*
X350199D03*
X366775Y127662D03*
X356250Y216342D03*
X358209Y208169D03*
X357764Y314234D03*
X363750Y369362D03*
X371370Y373622D03*
X364014Y382304D03*
X359930Y732985D03*
X360927Y757665D03*
X361043Y1306506D03*
X363643D03*
X367939Y1303319D03*
Y1305919D03*
Y1308519D03*
X358373Y1322757D03*
Y1319650D03*
X361043Y1314306D03*
Y1316906D03*
X362393Y1319406D03*
X361043Y1309106D03*
Y1311706D03*
X363643Y1316906D03*
Y1314306D03*
Y1309106D03*
Y1311706D03*
X358273Y1325853D03*
X370874Y1335876D03*
X367490Y1332568D03*
X356959Y1580678D03*
X361915D03*
X356959Y1575592D03*
X361915D03*
X369019Y1575686D03*
Y1580678D03*
X356959Y1592590D03*
X361915D03*
X356959Y1587598D03*
X361915D03*
X367215Y1599790D03*
X362259D03*
X369019Y1587598D03*
Y1592590D03*
X367215Y1616788D03*
X362259D03*
X367215Y1604876D03*
Y1611796D03*
X362259Y1604876D03*
Y1611796D03*
X376245Y212862D03*
Y217362D03*
Y221362D03*
Y225362D03*
X386120Y220322D03*
X385720Y323761D03*
X376500Y362736D03*
X373957Y1306208D03*
X381757D03*
X379157D03*
X376557D03*
X384357D03*
X387557D03*
X375951Y1321671D03*
X380911Y1316071D03*
X378431D03*
Y1321671D03*
X380911D03*
X373957Y1309315D03*
X381957Y1312422D03*
X381757Y1309315D03*
X379357Y1312422D03*
X379157Y1309315D03*
X376557D03*
X375951Y1316071D03*
X380842Y1334095D03*
X383549Y1333998D03*
X383127Y1395610D03*
X381060Y1433622D03*
X380930Y1531402D03*
X384210Y1534152D03*
X387152Y1582659D03*
X373975Y1575686D03*
Y1580678D03*
Y1587598D03*
Y1592590D03*
X379275Y1599884D03*
X374319D03*
X379275Y1604876D03*
Y1611796D03*
X374319Y1604876D03*
Y1611796D03*
X379275Y1616788D03*
X374319D03*
X374690Y1631700D03*
X375550Y1662052D03*
X386824Y1682866D03*
X387760Y1671092D03*
X393830Y62062D03*
X399800Y59662D03*
X403800D03*
X390830Y155833D03*
X388965Y209949D03*
X398720Y318643D03*
X403675Y363081D03*
X391195Y368199D03*
X391101Y380939D03*
X403581Y375880D03*
X390730Y394852D03*
X403570Y388874D03*
X395771Y1303480D03*
X393171D03*
X395771Y1300880D03*
X393171D03*
X395771Y1295680D03*
X393171D03*
X395771Y1298280D03*
X393171D03*
X394521Y1305980D03*
X390501Y1306224D03*
X400067Y1303319D03*
Y1300719D03*
Y1295519D03*
Y1298119D03*
Y1305919D03*
Y1308519D03*
X390401Y1312427D03*
X390501Y1309331D03*
X399673Y1332653D03*
X403130Y1335963D03*
X400919Y1411231D03*
X391370Y1424782D03*
X392108Y1582659D03*
X401812Y1616456D03*
X394910Y1632364D03*
Y1637320D03*
X402246Y1671745D03*
X409535Y49388D03*
X412930Y62572D03*
X413459Y129061D03*
X411434Y163662D03*
X407490Y216912D03*
X412820Y231922D03*
X405478Y236726D03*
X410090Y241932D03*
X420710Y242482D03*
X419023Y381760D03*
X418982Y407847D03*
X416485Y1306208D03*
X419685D03*
X413885D03*
X406085D03*
X411285D03*
X408685D03*
X414085Y1312422D03*
X413885Y1309315D03*
X411485Y1312422D03*
X408685Y1309315D03*
X406085D03*
X411285D03*
X413039Y1316071D03*
X408079D03*
X410559D03*
X413039Y1321671D03*
X408079D03*
X410559D03*
X416099Y1335568D03*
X414617Y1333473D03*
X412465Y1393878D03*
X419974Y1405289D03*
Y1412789D03*
X420474Y1420289D03*
X407125Y1424978D03*
X404475Y1552452D03*
X419002Y1600306D03*
X406526Y1591212D03*
Y1596168D03*
X406768Y1616456D03*
X408700Y1603500D03*
Y1614300D03*
X411910Y1629170D03*
Y1624214D03*
X410232Y1670244D03*
X429535Y49388D03*
X430655Y58677D03*
X433695Y214862D03*
X429395Y232562D03*
X426295Y227862D03*
X422210Y221452D03*
X429395Y236562D03*
Y240562D03*
X425249Y338061D03*
X431503Y376642D03*
X431462Y402729D03*
X422629Y1306224D03*
X432195Y1303319D03*
Y1305919D03*
X425299Y1303480D03*
X426649Y1305980D03*
X427899Y1303480D03*
X425299Y1295680D03*
X427899D03*
X432195Y1295519D03*
Y1298119D03*
X427899Y1298280D03*
X425299D03*
X432195Y1300719D03*
X427899Y1300880D03*
X425299D03*
X432195Y1308519D03*
X422529Y1312427D03*
X422629Y1309331D03*
X434983Y1335924D03*
X431578Y1332560D03*
X427474Y1405289D03*
X434974D03*
Y1412789D03*
X427474Y1420289D03*
X434974D03*
X423958Y1600306D03*
X428099Y1586282D03*
X428941Y1606441D03*
X449535Y49388D03*
X443678Y145710D03*
X445964Y314234D03*
X450400Y338812D03*
X442853Y542519D03*
Y547519D03*
X448613Y1306208D03*
X446013D03*
X443413D03*
X440813D03*
X438213D03*
X451813D03*
X443613Y1312422D03*
X443413Y1309315D03*
X440813D03*
X438213D03*
X446213Y1312422D03*
X446013Y1309315D03*
X440207Y1316071D03*
X445167D03*
X442687D03*
X440207Y1321671D03*
X445167D03*
X442687D03*
X446944Y1335928D03*
X445153Y1334095D03*
X446258Y1441606D03*
X449778D03*
X451910Y1643282D03*
X437562Y1649770D03*
X442518D03*
X469535Y49388D03*
X454568Y78782D03*
X466992Y145888D03*
X458264Y254862D03*
X460300Y303662D03*
X468490Y340572D03*
X469830Y366158D03*
X460323Y510183D03*
X458327Y1303980D03*
X460927D03*
X464427Y1305380D03*
X454757Y1306224D03*
X460927Y1306580D03*
X458327D03*
Y1301380D03*
X460927D03*
X464427Y1300180D03*
Y1302780D03*
X458327Y1296180D03*
X460927D03*
X464427D03*
X458327Y1298780D03*
X460927D03*
X464423Y1308519D03*
X454657Y1312427D03*
X454757Y1309331D03*
X464738Y1333085D03*
X467644Y1335981D03*
X455576Y1409125D03*
Y1417125D03*
Y1420625D03*
Y1427632D03*
Y1424125D03*
X454450Y1433580D03*
X464160Y1587122D03*
X458414Y1624994D03*
Y1629950D03*
X468040Y1654807D03*
X478240Y55935D03*
Y66575D03*
Y61129D03*
X484396Y161364D03*
X475500Y212685D03*
X472800Y299462D03*
X484800Y307362D03*
X476740Y309272D03*
X479740Y300202D03*
X482920Y398060D03*
X479379Y452445D03*
X480741Y1306208D03*
X478141D03*
X475541D03*
X472941D03*
X470341D03*
X483941D03*
X472941Y1309315D03*
X478141D03*
X470341D03*
X478341Y1312422D03*
X475741D03*
X475541Y1309315D03*
X472335Y1316071D03*
X477295D03*
X474815D03*
X472335Y1321671D03*
X477295D03*
X474815D03*
X477162Y1334095D03*
X478909Y1336038D03*
X485236Y1417844D03*
X482741Y1438698D03*
X482742Y1441312D03*
X484333Y1575686D03*
Y1580678D03*
X477229D03*
X472273D03*
Y1575686D03*
X477229D03*
X482529Y1599884D03*
X477573D03*
X484333Y1587598D03*
Y1592590D03*
X472273D03*
X477229D03*
Y1587598D03*
X472273D03*
X482529Y1616788D03*
X477573D03*
Y1611796D03*
X482529D03*
X477573Y1604876D03*
X482529D03*
X472210Y1618626D03*
X485150Y1624942D03*
X477905Y1667242D03*
X489535Y49347D03*
X497002Y88167D03*
X501540Y105152D03*
X498630Y140492D03*
X489980Y250512D03*
X492074Y300306D03*
X497568Y397632D03*
X494193Y550447D03*
X486885Y1306224D03*
X496451Y1306345D03*
X489555Y1303480D03*
X492155D03*
X490905Y1305980D03*
X492155Y1300880D03*
X489555D03*
X486785Y1312427D03*
X486885Y1309331D03*
X496220Y1322440D03*
X496451Y1316745D03*
Y1308945D03*
Y1314145D03*
Y1311545D03*
X499458Y1349468D03*
X499818Y1385027D03*
X499859Y1393027D03*
X490307Y1421499D03*
X491156Y1438713D03*
X499541Y1438698D03*
X491142Y1441312D03*
X499542D03*
X501349Y1580678D03*
X496393D03*
Y1575686D03*
X501349D03*
X489289D03*
Y1580678D03*
X501693Y1599884D03*
X494589D03*
X489633D03*
X501349Y1592590D03*
X496393D03*
X501349Y1587598D03*
X496393D03*
X489289D03*
Y1592590D03*
X501693Y1611796D03*
Y1604876D03*
Y1616788D03*
X489633Y1611796D03*
X494589Y1604876D03*
X489633D03*
X494589Y1611796D03*
X489633Y1616788D03*
X494589D03*
X487340Y1641352D03*
X517902Y69508D03*
X510815D03*
X503100Y78402D03*
X510030Y78412D03*
X504980Y101752D03*
X503290Y140492D03*
X507360D03*
X514850Y168443D03*
X504075Y231262D03*
X508000Y237862D03*
X505900Y311562D03*
X510740Y332592D03*
X513173Y408740D03*
X514425Y489112D03*
Y495112D03*
X509493Y539819D03*
X513025Y615742D03*
X516069Y1319634D03*
X502469D03*
Y1322741D03*
X512869Y1319634D03*
X510269D03*
X507669D03*
X505069D03*
X507669Y1322741D03*
X505069D03*
X510269D03*
X504463Y1329497D03*
Y1335097D03*
X509423Y1329497D03*
X506943D03*
X509423Y1335097D03*
X506943D03*
X510469Y1325848D03*
X507869D03*
X509382Y1347521D03*
X511149Y1349468D03*
X505018Y1385027D03*
X502418D03*
X505059Y1393027D03*
X502459D03*
X508001Y1438669D03*
X507942Y1441312D03*
X508453Y1575686D03*
X513409D03*
X508453Y1580678D03*
X513409D03*
X513753Y1599884D03*
X506649D03*
X508453Y1587598D03*
X513409D03*
X508453Y1592590D03*
X513409D03*
X513753Y1616788D03*
Y1604876D03*
Y1611796D03*
X506649D03*
Y1604876D03*
Y1616788D03*
X518606Y23797D03*
X532075Y69508D03*
Y57894D03*
X524988Y69508D03*
X529239Y99997D03*
Y92911D03*
X528400Y104225D03*
Y114275D03*
X527823Y131802D03*
Y149802D03*
X527278Y164726D03*
X529480Y183921D03*
X536127Y247652D03*
X523660Y323222D03*
X535220Y383552D03*
X528145Y408705D03*
X518735Y452442D03*
X526852Y511331D03*
X527042Y505830D03*
X526853Y516817D03*
X523033Y1319406D03*
X519013Y1319650D03*
Y1322757D03*
X527645Y1326076D03*
X528579Y1329143D03*
X528377Y1335982D03*
X518913Y1325853D03*
X528579Y1342143D03*
Y1344743D03*
X534597Y1345539D03*
Y1342432D03*
X528975Y1369724D03*
X532573Y1575686D03*
Y1580678D03*
X520513D03*
X525469D03*
X520513Y1575686D03*
X525469D03*
X525813Y1599884D03*
X530769D03*
X518709D03*
X532573Y1587598D03*
Y1592590D03*
X525469D03*
X520513D03*
Y1587598D03*
X525469D03*
X525813Y1611796D03*
X530769D03*
X525813Y1604876D03*
X530769D03*
Y1616788D03*
X525813D03*
X518709D03*
Y1604876D03*
Y1611796D03*
X548609Y32500D03*
X546248Y69508D03*
X539161D03*
Y57894D03*
X546234Y77443D03*
X542620Y103352D03*
X537360Y120522D03*
X550545Y147302D03*
X542798Y202646D03*
X535630Y306602D03*
X543035Y441005D03*
X538120Y463137D03*
X544813Y1322668D03*
X542213D03*
X538293D03*
X535693D03*
X548197Y1342432D03*
X539997Y1348646D03*
X542397Y1345539D03*
X542597Y1348646D03*
X537197Y1342432D03*
X539797D03*
X542397D03*
X544997D03*
X537197Y1345539D03*
X539797D03*
X539071Y1352295D03*
X536591D03*
X541551D03*
Y1357895D03*
X542256Y1369935D03*
X536591Y1357895D03*
X539071D03*
X549589Y1580678D03*
X544633D03*
X549589Y1575592D03*
X544633D03*
X537529Y1575686D03*
Y1580678D03*
X549933Y1599790D03*
X537873Y1599884D03*
X542829D03*
X549589Y1592590D03*
X544633D03*
X549589Y1587598D03*
X544633D03*
X537529D03*
Y1592590D03*
X549933Y1611796D03*
Y1604876D03*
Y1616788D03*
X542829D03*
X537873D03*
Y1604876D03*
X542829D03*
X537873Y1611796D03*
X542829D03*
X560421Y69508D03*
X553335D03*
X553320Y77443D03*
X564988Y118670D03*
X555545Y134340D03*
X565500Y145252D03*
X555220Y167937D03*
X553657Y193862D03*
X564944Y252173D03*
X553536Y307527D03*
X569080Y414002D03*
X559300Y422732D03*
X558933Y1323658D03*
Y1326258D03*
X556563Y1337918D03*
X553963D03*
X558933Y1328938D03*
X556563Y1335318D03*
Y1332718D03*
X558933Y1331538D03*
X553963Y1335318D03*
Y1332718D03*
X555313Y1340418D03*
X551141Y1345555D03*
X551041Y1348651D03*
X551141Y1342448D03*
X555372Y1343037D03*
X561070Y1346174D03*
X556693Y1575686D03*
X561649D03*
X556693Y1580678D03*
X561649D03*
X561993Y1599884D03*
X554889Y1599790D03*
X556693Y1587598D03*
X561649D03*
Y1592590D03*
X556693D03*
X561993Y1616788D03*
Y1604876D03*
Y1611796D03*
X554889D03*
Y1604876D03*
Y1616788D03*
X567673Y130542D03*
X581175Y164717D03*
X569965Y161232D03*
X579481Y202378D03*
Y210378D03*
X568149Y217916D03*
X580712Y215877D03*
X581645Y233362D03*
X569668Y229812D03*
X578711Y230109D03*
X578509Y265132D03*
X569880Y300992D03*
X580400Y302402D03*
X582436Y361032D03*
X570200Y372229D03*
X570760Y451710D03*
X571990Y501046D03*
X571700Y552200D03*
X580813Y1575686D03*
Y1580678D03*
X573709D03*
X568753D03*
Y1575686D03*
X573709D03*
X579009Y1599884D03*
X574053D03*
X566949D03*
X580813Y1587598D03*
Y1592590D03*
X573709D03*
X568753D03*
X573709Y1587598D03*
X568753D03*
X574053Y1616788D03*
X579009D03*
Y1611796D03*
X574053D03*
X579009Y1604876D03*
X574053D03*
X566949Y1616788D03*
Y1604876D03*
Y1611796D03*
X591395Y132142D03*
X595220Y140922D03*
X588000D03*
X592710Y156342D03*
X593248Y159480D03*
X598295Y171862D03*
X596581Y184849D03*
X590337Y177604D03*
X598760Y203712D03*
X593966Y229965D03*
X592039Y252202D03*
X588577Y285862D03*
X586820Y314662D03*
X597820Y317062D03*
X592920Y326362D03*
X591720Y430787D03*
X599220Y444362D03*
X593545Y488212D03*
X594090Y505107D03*
X589260Y519421D03*
X594240Y511953D03*
X593675Y534702D03*
X589989Y745475D03*
X597829Y1580678D03*
X592873D03*
X597829Y1575686D03*
X592873D03*
X585769D03*
Y1580678D03*
X598173Y1599884D03*
X586113D03*
X591069D03*
X597829Y1592590D03*
X592873D03*
X597829Y1587598D03*
X592873D03*
X585769D03*
Y1592590D03*
X598173Y1616788D03*
Y1611796D03*
Y1604876D03*
X586113D03*
X591069D03*
X586113Y1611796D03*
X591069D03*
Y1616788D03*
X586113D03*
X615185Y69508D03*
X603374D03*
X601050Y100008D03*
X610104Y119342D03*
X602306Y143077D03*
X602430Y153862D03*
X606260Y161652D03*
X615572Y173942D03*
X615573Y181984D03*
X614531Y200378D03*
X611030Y188372D03*
X603340Y208142D03*
X614531Y209878D03*
X609456Y204994D03*
X606719Y254966D03*
X609844Y330407D03*
X608830Y374302D03*
X605830Y402782D03*
X604779Y423862D03*
X600351Y461862D03*
X614220Y452862D03*
X610820Y472862D03*
X603779Y486922D03*
X606200Y514862D03*
X609520Y515162D03*
X614086Y537624D03*
X614000Y550800D03*
X603317Y738415D03*
X614660Y739553D03*
X602027Y761445D03*
X612407Y769485D03*
X609889Y1575686D03*
X604933D03*
X609889Y1580678D03*
X604933D03*
X615189Y1599884D03*
X610233D03*
X603129D03*
X609889Y1587598D03*
X604933D03*
X609889Y1592590D03*
X604933D03*
X615189Y1604876D03*
X610233D03*
X615189Y1611796D03*
X610233D03*
X615189Y1616788D03*
X610233D03*
X603129D03*
Y1611796D03*
Y1604876D03*
X631546Y85024D03*
X618460Y119342D03*
X631300Y167872D03*
X628195Y178414D03*
X628194Y170372D03*
X630818Y191248D03*
X625862D03*
X620030Y188782D03*
X627645Y236862D03*
X629564Y256277D03*
X623150Y273172D03*
X625800Y311912D03*
X628294Y317007D03*
X623580Y336429D03*
X629248Y436972D03*
X629220Y472862D03*
Y477862D03*
Y467862D03*
Y482862D03*
X626207Y747585D03*
X618114Y1258470D03*
X629053Y1575686D03*
Y1580678D03*
X621949D03*
X616993D03*
X621949Y1575686D03*
X616993D03*
X622293Y1599884D03*
X627249D03*
X629053Y1587598D03*
Y1592590D03*
X621949D03*
X616993D03*
X621949Y1587598D03*
X616993D03*
X627249Y1616788D03*
X622293D03*
Y1611796D03*
X627249D03*
X622293Y1604876D03*
X627249D03*
X646440Y43632D03*
X632463Y43302D03*
X645150Y69508D03*
X645350Y60612D03*
X632640Y107532D03*
X637500Y110362D03*
X642480Y184862D03*
X645876Y296231D03*
X633138Y296766D03*
X645528Y308623D03*
X645807Y304291D03*
X647200Y354300D03*
X643736Y457214D03*
X644245Y472862D03*
X644220Y467862D03*
X644245Y482862D03*
X636960Y516002D03*
X646069Y1580678D03*
X641113D03*
X646069Y1575592D03*
X641113D03*
X634009Y1575686D03*
Y1580678D03*
X646413Y1599790D03*
X639309Y1599884D03*
X634353D03*
X646069Y1592590D03*
X641113D03*
X646069Y1587598D03*
X641113D03*
X634009D03*
Y1592590D03*
X646413Y1616788D03*
Y1611796D03*
Y1604876D03*
X639309D03*
X634353D03*
X639309Y1611796D03*
X634353D03*
Y1616788D03*
X639309D03*
X641057Y1648659D03*
X645407Y1660425D03*
X639745Y1714362D03*
X648290Y1720052D03*
X639745Y1726362D03*
X661550Y45133D03*
X654464D03*
X652153Y98105D03*
X652680Y89712D03*
X651579Y102703D03*
X659000Y89262D03*
X651980Y133822D03*
X650790Y144982D03*
X660690Y408162D03*
X660720Y404362D03*
X653800Y498740D03*
X662282Y1386432D03*
X654606Y1431203D03*
X653173Y1575686D03*
X658129D03*
X653173Y1580678D03*
X658129D03*
X663429Y1599884D03*
X658473D03*
X651369Y1599790D03*
X653173Y1587598D03*
X658129D03*
X653173Y1592590D03*
X658129D03*
X663429Y1604876D03*
X658473D03*
X663429Y1611796D03*
X658473D03*
Y1616788D03*
X663429D03*
X651369D03*
Y1611796D03*
Y1604876D03*
X663043Y1647557D03*
X655307Y1647436D03*
X663118Y1659557D03*
X663145Y1664862D03*
Y1676862D03*
X656973Y1698727D03*
X652712Y1686275D03*
X672005Y44119D03*
X668800Y45262D03*
X666406Y69508D03*
X675225Y58108D03*
X673750Y77692D03*
X673690Y200672D03*
X673300Y211332D03*
X667020Y225762D03*
X680600Y375462D03*
X668329Y411714D03*
X677295Y404362D03*
X677195Y408262D03*
X674628Y414864D03*
Y443210D03*
X671479Y430612D03*
Y462108D03*
X668329Y481006D03*
X675220Y503837D03*
X680220D03*
X675220Y516852D03*
X671607Y742835D03*
X668096Y1360822D03*
X677137Y1384311D03*
X674537D03*
X671937D03*
X669337D03*
X677137Y1387418D03*
X674537D03*
X671937D03*
X669337D03*
X664782Y1383832D03*
Y1381232D03*
Y1378632D03*
Y1386432D03*
X679737Y1384311D03*
X677337Y1390525D03*
X674737D03*
X676250Y1399757D03*
X673820D03*
X671350D03*
X676250Y1394157D03*
X673820D03*
X671350D03*
X666425Y1414200D03*
X676312Y1411554D03*
X667926Y1547018D03*
X679192Y1564252D03*
X678515Y1573910D03*
X676648Y1657380D03*
X671620Y1670862D03*
X674195Y1708362D03*
X669120Y1718862D03*
X674195Y1732362D03*
X696838Y45112D03*
X686854Y43701D03*
X692380Y43532D03*
X682941Y69982D03*
X687050Y79212D03*
X685230Y76952D03*
X683820Y79192D03*
X682890Y72642D03*
X684953Y104968D03*
X694390Y133682D03*
X684520Y152482D03*
X688520D03*
X692520D03*
X686760Y222912D03*
X685600Y375462D03*
X690600D03*
X695600D03*
X688220Y388362D03*
X697220Y404362D03*
X697120Y408262D03*
X684077Y414864D03*
X680928Y424313D03*
X696676Y436911D03*
X693526Y443210D03*
Y440061D03*
Y436911D03*
X690376Y440061D03*
Y433761D03*
X693526Y452659D03*
Y449510D03*
X696676Y455809D03*
X693526D03*
X690376Y452659D03*
Y458959D03*
X696676Y477856D03*
X684077D03*
X680928Y468407D03*
X690220Y516852D03*
X684357Y742345D03*
X692784Y1298845D03*
X686426Y1360822D03*
X695022Y1361990D03*
X696462Y1386122D03*
X682937Y1384311D03*
X685881Y1384327D03*
Y1387434D03*
X691351Y1380922D03*
X688751D03*
X691240Y1383522D03*
X693851D03*
Y1378322D03*
Y1380922D03*
X691351Y1378322D03*
X688751D03*
X693851Y1386122D03*
X696462Y1378322D03*
Y1383522D03*
Y1380922D03*
X696272Y1404560D03*
X685850Y1390557D03*
X685015Y1438475D03*
X696940Y1437955D03*
X689875Y1577913D03*
X689128Y1652262D03*
X692595Y1670862D03*
X701838Y45112D03*
X700610Y57782D03*
X700741Y83050D03*
X706673Y122762D03*
X703520Y122540D03*
X704880Y133643D03*
X701926Y166535D03*
Y178346D03*
Y184252D03*
Y172441D03*
Y190157D03*
Y196063D03*
Y201968D03*
Y207874D03*
Y213779D03*
Y219685D03*
X700600Y375462D03*
X705600D03*
X706125Y421163D03*
X709274Y436911D03*
X706125Y440061D03*
Y436911D03*
X699825Y440061D03*
Y436911D03*
X712424Y443210D03*
Y440061D03*
Y436911D03*
Y455809D03*
X709274D03*
X706125D03*
Y452659D03*
X699825Y455809D03*
Y452659D03*
X712424D03*
Y449510D03*
X709274Y477856D03*
X699825Y468407D03*
X711220Y516852D03*
X705220D03*
X698600Y530700D03*
X701917Y742865D03*
X703755Y1290545D03*
X708795Y1303701D03*
X698094Y1361947D03*
X706239Y1360822D03*
X699062Y1380922D03*
Y1383522D03*
Y1378322D03*
X707480Y1384311D03*
X710080D03*
X707480Y1387418D03*
X710080D03*
X701662Y1380922D03*
Y1383522D03*
Y1378322D03*
X699062Y1386122D03*
X701662D03*
X712680Y1384311D03*
Y1387418D03*
X709493Y1399757D03*
Y1394157D03*
X712880Y1390525D03*
X711963Y1399757D03*
Y1394157D03*
X699262Y1413970D03*
X704568Y1414119D03*
X706680Y1437535D03*
X701730Y1437855D03*
X711440Y1436905D03*
X702112Y1583683D03*
X709111Y1618842D03*
X697595Y1658862D03*
X704433Y1657964D03*
X697770Y1680810D03*
X714015Y-27612D03*
X720308Y-26403D03*
X714015Y-21457D03*
Y-17583D03*
X714030Y-15068D03*
X714015Y-11428D03*
X714030Y-25097D03*
X720308Y-16374D03*
X714015Y-7554D03*
X714030Y-5039D03*
X720308Y-6345D03*
X728980Y39872D03*
X728028Y101968D03*
X728023Y98058D03*
X728028Y105468D03*
X727720Y356362D03*
X725220Y380787D03*
X715600Y375462D03*
X718220Y388362D03*
X715220Y404362D03*
X715120Y408262D03*
X725022Y414864D03*
X715574Y433761D03*
Y458959D03*
X728172Y449510D03*
X725022Y477856D03*
X722720Y521362D03*
X729200Y588952D03*
X713836Y1283689D03*
X724969Y1360822D03*
X729443Y1361224D03*
X726694Y1381583D03*
Y1378983D03*
X715280Y1384311D03*
X717880D03*
X715280Y1387418D03*
X721080Y1384311D03*
X724024Y1384327D03*
Y1387434D03*
X728044Y1384083D03*
X729294Y1381583D03*
Y1378983D03*
X715480Y1390525D03*
X723993Y1390557D03*
X714393Y1399757D03*
Y1394157D03*
X714455Y1411554D03*
X718230Y1600372D03*
X725378Y1614503D03*
X719770Y1614590D03*
X715780D03*
X722040Y1623970D03*
X713791Y1629816D03*
X721345Y1647300D03*
X716140Y1649895D03*
X726830Y1655380D03*
X724500Y1676500D03*
X744987Y49062D03*
X742840Y39832D03*
X736790D03*
X745130Y69508D03*
X738043D03*
X730957D03*
X731330Y60712D03*
X730820Y84062D03*
X737623Y98858D03*
X734523Y98758D03*
X735733Y111988D03*
X733220Y388362D03*
X737621Y411714D03*
X743720Y404362D03*
X743820Y408262D03*
X731322Y430612D03*
Y462108D03*
X737621Y481006D03*
X730070Y506212D03*
X744630Y506529D03*
X745220Y530362D03*
X737299Y766887D03*
X737784Y1360017D03*
X730752Y1384080D03*
X731794Y1381583D03*
Y1378983D03*
X732238Y1388343D03*
X738810Y1396665D03*
X741540Y1396585D03*
X739170Y1405655D03*
X741670Y1405675D03*
X738170Y1414185D03*
X740760Y1414165D03*
X758606Y23797D03*
X747487Y49062D03*
X752720Y59002D03*
X754219Y75707D03*
X754633Y108288D03*
Y105288D03*
X762172Y123898D03*
X754290Y286632D03*
X755200Y296062D03*
X759940Y438232D03*
X758420Y447662D03*
X751220Y530362D03*
X753137Y766625D03*
X757779Y1390645D03*
X757542Y1420684D03*
X761770Y1695347D03*
X765606Y44894D03*
X769474Y75360D03*
X765858Y87340D03*
X762368Y84088D03*
X769284Y103895D03*
X767061Y99959D03*
X767045Y95960D03*
X767028Y91490D03*
X776730Y117479D03*
X773943Y114633D03*
X771131Y111788D03*
X769775Y107977D03*
X766769Y140138D03*
X771774Y167518D03*
X773220Y296262D03*
X772866Y311558D03*
X776100Y375100D03*
X766195Y418212D03*
X765315Y464862D03*
Y488862D03*
X772220Y530362D03*
X775317Y764025D03*
X763747Y764335D03*
X768520Y1379962D03*
X768620Y1392762D03*
X767820Y1410262D03*
X785095Y49388D03*
X780617Y296345D03*
X779120Y306162D03*
X794600Y360600D03*
X787925Y387900D03*
X781195Y418212D03*
X791590Y417050D03*
X780020Y438287D03*
X781410Y431822D03*
X780340Y468982D03*
Y474862D03*
X793673Y512862D03*
X792720Y589862D03*
X789720Y581862D03*
X783100Y593582D03*
X788225Y1388683D03*
X805095Y49388D03*
X797443Y271469D03*
X806300Y279662D03*
X809700Y273562D03*
X795190Y298572D03*
X798620Y312773D03*
X809800Y360600D03*
X802200D03*
X806588Y351097D03*
X799800Y368700D03*
X802220Y393727D03*
X803150Y408512D03*
X795600Y402500D03*
X799458Y431217D03*
X795370Y474862D03*
X801567Y512942D03*
X798720Y585362D03*
X798220Y597362D03*
X808860Y603802D03*
X797720Y617862D03*
X799637Y763625D03*
X825095Y49388D03*
X821118Y134632D03*
X825698Y139062D03*
X813900Y269698D03*
X827403Y286625D03*
X816420Y287062D03*
X813855Y354008D03*
X820936Y356956D03*
X824980Y405260D03*
Y409260D03*
X821720Y428437D03*
X818500Y451700D03*
X816500Y476800D03*
X821720Y519082D03*
X815040Y590772D03*
X814800Y760922D03*
X822442Y762369D03*
X814234Y1340465D03*
X830975Y2388D03*
X830990Y4903D03*
X837268Y3597D03*
X830975Y22446D03*
Y8543D03*
Y12417D03*
X830990Y14932D03*
X830975Y18572D03*
X837268Y13626D03*
X830990Y24961D03*
X837268Y23655D03*
X836126Y62681D03*
X837791Y85186D03*
X831297Y104206D03*
X842864Y110296D03*
X830339Y228143D03*
X829680Y264580D03*
X836210Y272452D03*
X829720Y277562D03*
X829800Y271562D03*
X829320Y296762D03*
X834400Y283862D03*
X834900Y293462D03*
X828222Y359960D03*
X835471Y363003D03*
X843133Y366158D03*
X833300Y386500D03*
X838784Y392880D03*
X839200Y434300D03*
X841300Y446800D03*
X842600Y477200D03*
X842341Y474241D03*
X841795Y492862D03*
X829745Y498082D03*
X834635Y515447D03*
X830480Y527817D03*
X831700Y596962D03*
X836847Y762495D03*
X828799Y1336870D03*
X828910Y1331756D03*
Y1341725D03*
X845095Y49388D03*
X854107Y91232D03*
X850280Y113852D03*
X853828Y265057D03*
X854333Y276117D03*
X854338Y280027D03*
Y283527D03*
X852800Y288562D03*
X853200Y297462D03*
X856700Y304862D03*
X848000Y374622D03*
X851396Y369614D03*
X859734Y373032D03*
X857560Y417762D03*
X844200Y418800D03*
X847830Y443892D03*
X843810Y453322D03*
X846700Y473000D03*
X848710Y505641D03*
X860345Y522162D03*
X856698Y594011D03*
X853200Y751062D03*
X854687Y761685D03*
X865095Y49388D03*
X868187Y72006D03*
X860937Y71877D03*
X861350Y61672D03*
X871980Y199500D03*
X860833Y276817D03*
X863933Y276917D03*
X862043Y290047D03*
X867922Y376450D03*
X875922Y379793D03*
X870700Y382415D03*
Y390620D03*
Y394620D03*
X871320Y416752D03*
X862620Y503162D03*
Y499062D03*
X860345Y513062D03*
X892214Y141891D03*
X878220Y192055D03*
X880943Y283347D03*
Y286347D03*
X880473Y329370D03*
X883472Y382910D03*
X886362Y534380D03*
X886500Y739162D03*
X878152Y876760D03*
X889439Y1437938D03*
X903930Y202885D03*
X903980Y210355D03*
X903930Y217059D03*
X903980Y224529D03*
X893500Y339062D03*
X900061Y510962D03*
X906127Y496343D03*
X900061Y517898D03*
X893298Y534380D03*
X899462Y533380D03*
X906398D03*
X897000Y891895D03*
X894375Y913692D03*
X912214Y141891D03*
X917680Y174999D03*
Y177999D03*
Y171999D03*
X909386Y195925D03*
Y203011D03*
Y210098D03*
Y217185D03*
Y224271D03*
Y231358D03*
X919279Y461244D03*
X920682Y494586D03*
X920980Y503393D03*
X911720Y511662D03*
X911626Y523430D03*
X918562D03*
X924647Y526808D03*
Y533744D03*
X924600Y824262D03*
X922320Y1660953D03*
X932214Y141891D03*
X927133Y189386D03*
X925320Y203399D03*
X940709Y460438D03*
X938437Y455454D03*
X932724Y455538D03*
X926215Y461244D03*
X929234Y494915D03*
X938588Y485197D03*
X929698Y503595D03*
X928231Y530479D03*
X936273Y530478D03*
X927200Y811462D03*
X931496Y962082D03*
X929221Y1014664D03*
X927122Y1661380D03*
X938220Y1661062D03*
X952214Y141891D03*
X949710Y198289D03*
X941634Y199051D03*
Y193451D03*
X951354Y209437D03*
Y203837D03*
X944880Y210959D03*
Y216559D03*
Y230697D03*
Y225097D03*
X954874Y232071D03*
X954904Y225741D03*
X942827Y422743D03*
Y429679D03*
X945800Y432463D03*
Y439399D03*
X946492Y460410D03*
X956188Y495384D03*
Y502320D03*
X948495Y502784D03*
X948693Y509497D03*
X956188Y509484D03*
Y516420D03*
X952622Y529364D03*
X956700Y786862D03*
X941400Y810062D03*
X946100Y1661100D03*
X972214Y141891D03*
X963520Y214699D03*
X960703Y212668D03*
X971471Y242358D03*
X965792Y350959D03*
X965420Y365719D03*
X963856Y394202D03*
X960059Y387004D03*
X972986Y393171D03*
X970054Y478773D03*
Y485709D03*
X966720Y511362D03*
X960620Y509462D03*
X972379Y509303D03*
X959558Y529364D03*
X962162Y535130D03*
X969098D03*
X958755Y657078D03*
X963520Y665062D03*
X958866Y662378D03*
X959100Y789862D03*
X975688Y152950D03*
Y149950D03*
X985016Y344659D03*
X974791Y339990D03*
X986182Y361062D03*
X979380Y373082D03*
X988159Y409068D03*
X983760Y424292D03*
X980092Y421289D03*
X983720Y512362D03*
X976283Y534226D03*
X994553Y365711D03*
X997598Y382952D03*
X997612Y391804D03*
X1006221Y382945D03*
X997900Y400720D03*
X993387Y429827D03*
X999720Y512862D03*
X991097Y529902D03*
X996675Y1286985D03*
X1012214Y141826D03*
X1022002Y267342D03*
Y270142D03*
X1013500Y344900D03*
X1015638Y382968D03*
X1015637Y391334D03*
X1006589Y392017D03*
X1006750Y401010D03*
X1015657Y401013D03*
X1021259Y420548D03*
X1007249Y422682D03*
X1017511Y430038D03*
X1008720Y498362D03*
X1019145Y503823D03*
X1011720Y589362D03*
X1018720Y592362D03*
X1021720Y601862D03*
X1010630Y748741D03*
X1023407Y-27681D03*
X1029700Y-26472D03*
X1023407Y-32055D03*
X1029700Y-37001D03*
X1023407Y-17652D03*
X1023422Y-15137D03*
X1023407Y-11497D03*
X1029700Y-16443D03*
X1023422Y-25166D03*
X1023407Y-21526D03*
X1029700Y3615D03*
X1023422Y4921D03*
X1023407Y2406D03*
X1023422Y-5108D03*
X1023407Y-7623D03*
Y-1468D03*
X1029700Y-6414D03*
X1023407Y22464D03*
Y18590D03*
Y8561D03*
X1023422Y14950D03*
X1023407Y12435D03*
X1029700Y13644D03*
Y23673D03*
X1023422Y24979D03*
X1038609Y49388D03*
X1027520Y122732D03*
X1037650Y128842D03*
X1023220Y187574D03*
X1031502Y267342D03*
X1028202D03*
X1025102D03*
X1033133Y272564D03*
X1031502Y270142D03*
X1029833Y272564D03*
X1026733D03*
X1023633D03*
X1028202Y270142D03*
X1025102D03*
X1029094Y383070D03*
Y387872D03*
X1033860Y400802D03*
X1038294Y506504D03*
X1027190Y510672D03*
X1029220Y520032D03*
X1043629Y375078D03*
Y372578D03*
X1049100Y390162D03*
X1046156Y442699D03*
X1058609Y49388D03*
X1066820Y151632D03*
X1072310Y364422D03*
X1078609Y49388D03*
X1075100Y55682D03*
X1084146Y67102D03*
X1078270Y93462D03*
X1077270Y369061D03*
Y374131D03*
Y379251D03*
X1073724Y476867D03*
X1081906Y472577D03*
X1076739Y506461D03*
X1077751Y522235D03*
X1098609Y49388D03*
X1097794Y67881D03*
X1102480Y133722D03*
X1105553Y356475D03*
X1096477Y744385D03*
X1102930Y1668690D03*
X1092072Y1734244D03*
X1118609Y49388D03*
X1118110Y1398010D03*
X1109118Y1526046D03*
X1116338Y1711380D03*
X1113055Y1718338D03*
X1132856Y52926D03*
X1129948Y66786D03*
X1127788Y1397126D03*
X1131629Y1420615D03*
X1129029D03*
X1134229D03*
X1123674Y1414936D03*
X1121174D03*
X1123674Y1417536D03*
Y1420136D03*
X1121174Y1417536D03*
Y1420136D03*
X1131629Y1423722D03*
X1129029D03*
X1134229D03*
X1123674Y1422736D03*
X1121174D03*
X1131042Y1436061D03*
X1135942D03*
X1133512D03*
X1131042Y1430461D03*
X1135942D03*
X1133512D03*
X1134429Y1426829D03*
X1136004Y1447858D03*
X1126117Y1450504D03*
X1127008Y1550285D03*
X1133780Y1550301D03*
X1138609Y49388D03*
X1145603Y73679D03*
X1140465Y379592D03*
X1142302Y366532D03*
X1142790Y611122D03*
X1146118Y1397126D03*
X1150843Y1415126D03*
X1148243D03*
X1150843Y1417726D03*
X1148243D03*
X1150732Y1420326D03*
X1142629Y1420615D03*
X1145573Y1420631D03*
X1139429Y1420615D03*
X1136829D03*
X1145573Y1423738D03*
X1136829Y1423722D03*
X1145542Y1426861D03*
X1137029Y1426829D03*
X1145108Y1476732D03*
X1158609Y49388D03*
X1156790Y373231D03*
X1153467Y586462D03*
X1153490Y610322D03*
X1165931Y1397126D03*
X1154714Y1398295D03*
X1157786Y1398252D03*
X1167172Y1420615D03*
X1153913Y1420606D03*
Y1415406D03*
Y1418006D03*
X1159124D03*
Y1420606D03*
Y1415406D03*
X1161724D03*
Y1420606D03*
Y1418006D03*
X1156524Y1415406D03*
Y1420606D03*
Y1418006D03*
X1167172Y1423722D03*
X1153913Y1423206D03*
X1159124D03*
X1161724D03*
X1156524D03*
X1155964Y1440864D03*
X1164260Y1450423D03*
X1158954Y1450274D03*
X1168192Y1604130D03*
X1152950Y1616470D03*
X1165950Y1617729D03*
X1152930Y1633880D03*
X1174980Y585632D03*
X1174880Y592652D03*
X1173990Y602192D03*
X1183230Y739102D03*
X1184661Y1397126D03*
X1183716Y1420631D03*
X1180772Y1420615D03*
X1174972D03*
X1177572D03*
X1172372D03*
X1169772D03*
X1183716Y1423738D03*
X1174972Y1423722D03*
X1172372D03*
X1169772D03*
X1174085Y1436061D03*
Y1430461D03*
X1171655Y1436061D03*
X1169185D03*
X1171655Y1430461D03*
X1169185D03*
X1183685Y1426861D03*
X1175172Y1426829D03*
X1172572D03*
X1174147Y1447858D03*
X1179922Y1550285D03*
X1184501Y1606521D03*
X1185030Y1633010D03*
X1182470Y1618914D03*
X1172530Y1623020D03*
X1176900Y1627510D03*
X1198609Y49388D03*
X1188720Y56755D03*
X1191700Y56822D03*
X1185500Y101400D03*
X1190700Y99000D03*
X1197627Y132859D03*
X1196100Y188962D03*
X1193500D03*
X1192600Y217662D03*
X1193000Y204486D03*
X1195500D03*
X1195100Y217662D03*
X1194840Y240672D03*
X1199027Y588714D03*
X1189135Y1397529D03*
X1187736Y1420387D03*
X1188986Y1415287D03*
Y1417887D03*
X1186386Y1415287D03*
Y1417887D03*
X1191486Y1415287D03*
Y1417887D03*
X1190444Y1420384D03*
X1194750Y1424672D03*
X1197700Y1432672D03*
X1191930Y1424647D03*
X1198010Y1441902D03*
X1198880Y1457162D03*
X1197181Y1563587D03*
X1195994Y1580678D03*
Y1575686D03*
X1200950Y1580678D03*
Y1575686D03*
X1201294Y1599884D03*
X1195994Y1592590D03*
Y1587598D03*
X1200950Y1592590D03*
Y1587598D03*
X1201294Y1604876D03*
Y1611796D03*
Y1616788D03*
X1213026Y56742D03*
X1201800Y94600D03*
X1204800Y108900D03*
X1206900Y115900D03*
X1214573Y148909D03*
X1204420Y195362D03*
X1210084Y224362D03*
X1207220Y247148D03*
X1217720Y249862D03*
X1204880Y754032D03*
X1213010Y1575686D03*
X1208054D03*
X1213010Y1580678D03*
X1208054D03*
X1206250Y1599884D03*
X1213354D03*
X1213010Y1587598D03*
X1208054D03*
X1213010Y1592590D03*
X1208054D03*
X1206250Y1604876D03*
Y1611796D03*
Y1616788D03*
X1213354D03*
Y1604876D03*
Y1611796D03*
X1213980Y1676500D03*
X1218609Y49388D03*
X1228420Y58862D03*
X1230250Y89450D03*
X1223720Y217862D03*
Y205862D03*
X1232000Y244332D03*
Y248332D03*
X1225070Y1580678D03*
Y1575686D03*
X1220114D03*
Y1580678D03*
X1232174D03*
Y1575686D03*
X1218310Y1599884D03*
X1225414D03*
X1230370D03*
X1225070Y1592590D03*
X1220114D03*
X1225070Y1587598D03*
X1220114D03*
X1232174D03*
Y1592590D03*
X1218310Y1616788D03*
Y1604876D03*
Y1611796D03*
X1225414D03*
Y1604876D03*
X1230370Y1611796D03*
Y1604876D03*
X1225414Y1616788D03*
X1230370D03*
X1238609Y49388D03*
X1239907Y95008D03*
X1243808Y116832D03*
X1247333Y121999D03*
X1236520Y213462D03*
X1246444Y256098D03*
X1252040Y306480D03*
X1237130Y1575686D03*
Y1580678D03*
X1244234D03*
X1249190D03*
X1244234Y1575686D03*
X1249190D03*
X1242430Y1599884D03*
X1237474D03*
X1249534D03*
X1237130Y1587598D03*
Y1592590D03*
X1249190D03*
X1244234D03*
Y1587598D03*
X1249190D03*
X1242430Y1616788D03*
X1237474D03*
X1242430Y1611796D03*
Y1604876D03*
X1237474Y1611796D03*
Y1604876D03*
X1249534Y1611796D03*
Y1604876D03*
Y1616788D03*
X1258609Y49388D03*
X1262800Y101100D03*
X1264620Y92724D03*
X1252961Y111903D03*
X1267150Y305998D03*
X1256787Y749605D03*
X1261250Y1575686D03*
X1256294D03*
X1261250Y1580678D03*
X1256294D03*
X1254490Y1599884D03*
X1261594D03*
X1261250Y1587598D03*
X1256294D03*
X1261250Y1592590D03*
X1256294D03*
X1254490Y1611796D03*
Y1604876D03*
Y1616788D03*
X1261594D03*
Y1611796D03*
Y1604876D03*
X1278300Y81232D03*
X1280135Y1340002D03*
Y1337402D03*
Y1345202D03*
Y1342602D03*
X1280312Y1365689D03*
X1273310Y1580678D03*
Y1575592D03*
X1268354D03*
Y1580678D03*
X1280414Y1575686D03*
Y1580678D03*
X1266550Y1599884D03*
X1273654Y1599790D03*
X1278610D03*
X1273310Y1592590D03*
X1268354D03*
X1273310Y1587598D03*
X1268354D03*
X1280414D03*
Y1592590D03*
X1266550Y1616788D03*
Y1611796D03*
Y1604876D03*
X1273654Y1611796D03*
Y1604876D03*
X1278610Y1611796D03*
Y1604876D03*
X1273654Y1616788D03*
X1278610D03*
X1295278Y297056D03*
X1290322D03*
X1294937Y746965D03*
X1292904Y782048D03*
X1292614Y789910D03*
X1291205Y1345875D03*
X1286005Y1342768D03*
Y1345875D03*
X1296405Y1342768D03*
X1293805D03*
X1288605D03*
X1291205D03*
X1288605Y1345875D03*
X1293805D03*
X1291405Y1348982D03*
X1294005D03*
X1292916Y1352531D03*
X1290436D03*
X1287956D03*
X1292916Y1358131D03*
X1290436D03*
X1287956D03*
X1283280Y1372301D03*
X1293887Y1370043D03*
X1294477Y1372651D03*
X1285370Y1575686D03*
Y1580678D03*
X1297430D03*
X1292474D03*
Y1575686D03*
X1297430D03*
X1285714Y1599884D03*
X1290670D03*
X1297774D03*
X1285370Y1587598D03*
Y1592590D03*
X1297430D03*
X1292474D03*
X1297430Y1587598D03*
X1292474D03*
X1290670Y1616788D03*
X1285714D03*
Y1611796D03*
X1290670D03*
X1285714Y1604876D03*
X1290670D03*
X1297774Y1611796D03*
Y1604876D03*
Y1616788D03*
X1311960Y49672D03*
X1314450Y319841D03*
X1312845Y324764D03*
X1305909D03*
X1303017Y785837D03*
X1311952Y1321945D03*
X1307656Y1337104D03*
X1305056D03*
X1307656Y1334504D03*
Y1329304D03*
Y1331904D03*
X1305056Y1334504D03*
Y1329304D03*
Y1331904D03*
Y1339704D03*
X1312488Y1348353D03*
X1299605Y1342768D03*
X1302549Y1345891D03*
X1302520Y1348762D03*
X1315058Y1349488D03*
X1302549Y1342784D03*
X1309490Y1575686D03*
X1304534D03*
X1309490Y1580678D03*
X1304534D03*
X1302730Y1599884D03*
X1309834D03*
X1314790D03*
X1309490Y1587598D03*
X1304534D03*
X1309490Y1592590D03*
X1304534D03*
X1302730Y1611796D03*
Y1604876D03*
Y1616788D03*
X1309834D03*
Y1611796D03*
Y1604876D03*
X1314790Y1616788D03*
Y1611796D03*
Y1604876D03*
X1318609Y49388D03*
X1319125Y296540D03*
X1324081D03*
X1324636Y290920D03*
X1329592D03*
X1330248Y325670D03*
X1323312D03*
X1321386Y319841D03*
X1329977Y334384D03*
X1327601Y540049D03*
X1317970Y1322741D03*
Y1319634D03*
X1325770Y1322741D03*
X1323170D03*
X1331570Y1319634D03*
X1323170D03*
X1325770D03*
X1328370D03*
X1320570Y1322741D03*
Y1319634D03*
X1322444Y1329497D03*
X1324924D03*
X1319964D03*
X1322444Y1335097D03*
X1324924D03*
X1319964D03*
X1323370Y1325848D03*
X1325970D03*
X1324945Y1346877D03*
X1327196Y1349068D03*
X1321550Y1580678D03*
X1316594D03*
X1321550Y1575686D03*
X1316594D03*
X1328654D03*
Y1580678D03*
X1321894Y1599884D03*
X1326850D03*
X1321550Y1592590D03*
X1316594D03*
X1321550Y1587598D03*
X1316594D03*
X1328654D03*
Y1592590D03*
X1321894Y1611796D03*
Y1604876D03*
X1326850Y1611796D03*
Y1604876D03*
X1321894Y1616788D03*
X1326850D03*
X1332726Y-27681D03*
X1339019Y-26472D03*
X1332726Y-32055D03*
X1339019Y-37001D03*
X1332726Y-11497D03*
X1339019Y-16443D03*
X1332741Y-15137D03*
X1332726Y-17652D03*
Y-21526D03*
X1332741Y-25166D03*
X1332726Y2406D03*
X1332741Y4921D03*
X1339019Y3615D03*
X1332726Y-1468D03*
X1339019Y-6414D03*
X1332726Y-7623D03*
X1332741Y-5108D03*
X1332726Y18590D03*
Y22464D03*
X1339019Y13644D03*
X1332726Y12435D03*
X1332741Y14950D03*
X1332726Y8561D03*
X1332741Y24979D03*
X1339019Y23673D03*
X1338609Y49388D03*
X1346720Y82912D03*
X1343362Y283155D03*
X1335947Y290755D03*
X1340903D03*
X1343656Y330749D03*
X1343199Y324461D03*
X1336263D03*
X1336913Y334384D03*
X1335643Y540048D03*
X1336187Y755635D03*
X1339784Y1306506D03*
X1337184D03*
X1344080Y1305919D03*
X1343968Y1300579D03*
X1344080Y1308519D03*
X1334514Y1322757D03*
Y1319650D03*
X1337184Y1309106D03*
X1339784D03*
X1338534Y1319406D03*
X1339784Y1316906D03*
Y1314306D03*
Y1311706D03*
X1337184Y1314306D03*
Y1316906D03*
Y1311706D03*
X1334414Y1325853D03*
X1347015Y1335876D03*
X1343631Y1332568D03*
X1333610Y1575686D03*
Y1580678D03*
X1345670D03*
X1340714D03*
X1345670Y1575686D03*
X1340714D03*
X1338910Y1599884D03*
X1333954D03*
X1346014D03*
X1333610Y1587598D03*
Y1592590D03*
X1345670D03*
X1340714D03*
X1345670Y1587598D03*
X1340714D03*
X1338910Y1616788D03*
Y1611796D03*
Y1604876D03*
X1333954Y1616788D03*
Y1611796D03*
Y1604876D03*
X1346014Y1611796D03*
Y1604876D03*
Y1616788D03*
X1350550Y101632D03*
X1363846Y279848D03*
X1349362Y283155D03*
X1353902Y287540D03*
X1359902D03*
X1350592Y330749D03*
X1356968Y339611D03*
X1350032D03*
X1363539Y334043D03*
X1356603D03*
X1350098Y1306208D03*
X1352698D03*
X1355298D03*
X1360498D03*
X1363698D03*
X1357898D03*
X1352698Y1309315D03*
X1350098D03*
X1355498Y1312422D03*
X1358098D03*
X1355298Y1309315D03*
X1357898D03*
X1352092Y1316071D03*
Y1321671D03*
X1357052Y1316071D03*
X1354572D03*
X1357052Y1321671D03*
X1354572D03*
X1356983Y1334095D03*
X1359516Y1334058D03*
X1355357Y1396020D03*
X1357730Y1575686D03*
X1352774D03*
X1357730Y1580678D03*
X1352774D03*
X1350970Y1599884D03*
X1363030D03*
X1358074D03*
X1357730Y1587598D03*
X1352774D03*
X1357730Y1592590D03*
X1352774D03*
X1350970Y1611796D03*
Y1604876D03*
Y1616788D03*
X1363030D03*
Y1611796D03*
Y1604876D03*
X1358074Y1616788D03*
Y1611796D03*
Y1604876D03*
X1378550Y110692D03*
X1377742Y244372D03*
Y250372D03*
X1377626Y258914D03*
Y264914D03*
X1369846Y279848D03*
X1372381Y661428D03*
X1371931Y672978D03*
Y685278D03*
X1372243Y697108D03*
Y709108D03*
Y721108D03*
X1370662Y1305980D03*
X1371912Y1303480D03*
X1376208Y1305919D03*
Y1303319D03*
X1371912Y1300880D03*
X1376208Y1300719D03*
Y1295586D03*
X1371912Y1295747D03*
Y1298280D03*
X1376208Y1298119D03*
X1369312Y1303480D03*
X1366642Y1306224D03*
X1369312Y1300880D03*
Y1295747D03*
Y1298280D03*
X1376208Y1308519D03*
X1366542Y1312427D03*
X1366642Y1309331D03*
X1379271Y1335963D03*
X1375814Y1332653D03*
X1377060Y1411231D03*
X1371960Y1436172D03*
X1365040Y1431142D03*
X1369790Y1580678D03*
X1364834D03*
X1369790Y1575592D03*
X1364834D03*
X1376894Y1575686D03*
Y1580678D03*
X1375090Y1599790D03*
X1370134D03*
X1369790Y1592590D03*
X1364834D03*
X1369790Y1587598D03*
X1364834D03*
X1376894D03*
Y1592590D03*
X1375090Y1611796D03*
Y1604876D03*
Y1616788D03*
X1370134Y1611796D03*
Y1604876D03*
Y1616788D03*
X1383480Y88932D03*
X1383734Y243329D03*
Y237329D03*
X1388778Y250661D03*
X1388908Y260301D03*
X1386237Y265620D03*
Y275200D03*
X1385190Y501242D03*
X1390220Y497742D03*
X1381131Y656378D03*
Y668378D03*
X1395831Y666278D03*
X1386931Y660978D03*
X1381131Y680278D03*
X1396031Y680678D03*
X1386931Y675478D03*
X1387143Y690208D03*
X1380731Y692208D03*
X1395631Y695108D03*
X1380731Y704208D03*
X1387143Y704708D03*
X1380731Y716208D03*
X1395631Y709608D03*
X1387143Y719235D03*
X1395631Y724135D03*
X1382920Y733725D03*
X1391408Y738625D03*
X1382226Y1306208D03*
X1384826D03*
X1387426D03*
X1390026D03*
X1392626D03*
X1395826D03*
X1386700Y1321671D03*
X1389180D03*
X1382226Y1309315D03*
X1384826D03*
X1390226Y1312422D03*
X1387626D03*
X1390026Y1309315D03*
X1387426D03*
X1384220Y1316071D03*
Y1321671D03*
X1389180Y1316071D03*
X1386700D03*
X1390758Y1333473D03*
X1392076Y1335658D03*
X1388813Y1393160D03*
X1396115Y1405289D03*
Y1412789D03*
X1396615Y1420289D03*
X1384695Y1425047D03*
X1392475Y1576097D03*
X1381850Y1575686D03*
Y1580678D03*
X1396600Y1582500D03*
X1387150Y1599884D03*
X1382194D03*
X1381850Y1587598D03*
Y1592590D03*
X1396600Y1594000D03*
X1387150Y1616788D03*
X1382194D03*
X1387150Y1611796D03*
Y1604876D03*
X1382194Y1611796D03*
Y1604876D03*
X1404630Y220018D03*
X1412270Y230952D03*
X1405436Y238378D03*
X1400207Y238257D03*
X1398770Y1306224D03*
X1404040Y1303480D03*
X1408336Y1305919D03*
Y1303319D03*
X1404040Y1300880D03*
X1408336Y1300719D03*
Y1295586D03*
X1404040Y1295747D03*
Y1298280D03*
X1408336Y1298119D03*
X1401440Y1303480D03*
X1402790Y1305980D03*
X1401440Y1300880D03*
Y1295747D03*
Y1298280D03*
X1408336Y1308519D03*
X1398670Y1312427D03*
X1398770Y1309331D03*
X1411124Y1335924D03*
X1407719Y1332560D03*
X1403615Y1405289D03*
X1411115D03*
Y1412789D03*
X1403615Y1420289D03*
X1411115D03*
X1403350Y1516435D03*
X1403590Y1532255D03*
X1403350Y1521335D03*
X1403740Y1548375D03*
X1403590Y1537155D03*
X1403740Y1543475D03*
X1407200Y1591400D03*
X1411070Y1603282D03*
X1400000Y1630362D03*
Y1642362D03*
X1413350Y220018D03*
X1416020D03*
X1424690D03*
X1424520Y225002D03*
X1416810Y225422D03*
X1428640Y230022D03*
X1431430Y251265D03*
X1428940Y269292D03*
X1414354Y1306208D03*
X1416954D03*
X1419554D03*
X1422154D03*
X1424754D03*
X1427954D03*
X1418828Y1316071D03*
X1416348D03*
X1418828Y1321671D03*
X1416348D03*
X1421308Y1316071D03*
Y1321671D03*
X1414354Y1309315D03*
X1416954D03*
X1419554D03*
X1422354Y1312422D03*
X1419754D03*
X1422154Y1309315D03*
X1421294Y1334095D03*
X1423656Y1335468D03*
X1429345Y1433695D03*
X1427349Y1442776D03*
X1414264Y1439494D03*
X1419256Y1440258D03*
X1423829Y1442776D03*
X1416800Y1564862D03*
X1428403Y1581378D03*
X1418241Y1583441D03*
X1422145Y1575362D03*
X1426680Y1603262D03*
X1425770Y1633772D03*
X1413230Y1641042D03*
X1438609Y49388D03*
X1441125Y57362D03*
X1438680Y64412D03*
X1441490Y224062D03*
X1438720Y220018D03*
X1430130Y259342D03*
X1437177Y720965D03*
X1437182Y1298991D03*
X1430898Y1306224D03*
X1434582Y1304191D03*
Y1306791D03*
Y1301591D03*
Y1296458D03*
Y1298991D03*
X1440507Y1305430D03*
Y1302830D03*
Y1300230D03*
X1440536Y1296455D03*
X1440464Y1308519D03*
X1437182Y1304191D03*
Y1306791D03*
Y1301591D03*
Y1296458D03*
X1430798Y1312427D03*
X1430898Y1309331D03*
X1443785Y1335981D03*
X1440879Y1333085D03*
X1439155Y1399064D03*
X1431717Y1420625D03*
Y1417125D03*
Y1409125D03*
Y1427632D03*
X1436330Y1521152D03*
X1436570Y1536972D03*
X1436720Y1548192D03*
X1437140Y1576012D03*
X1438300Y1598400D03*
X1430250Y1608442D03*
X1438300Y1611000D03*
X1438273Y1671103D03*
X1458609Y49388D03*
X1458720Y153362D03*
Y149362D03*
Y169862D03*
Y165862D03*
Y161862D03*
Y157862D03*
Y181862D03*
Y177862D03*
Y173862D03*
X1446830Y236232D03*
X1453670Y278170D03*
X1459312Y341130D03*
X1460600Y352742D03*
X1456700Y369642D03*
X1454889Y658712D03*
X1454439Y670262D03*
Y682562D03*
X1454751Y694392D03*
Y706392D03*
X1454439Y718362D03*
X1459057Y733545D03*
X1457597Y739035D03*
X1446482Y1306208D03*
X1449082D03*
X1451682D03*
X1456882D03*
X1460082D03*
X1454282D03*
X1450956Y1321671D03*
X1448476D03*
X1453436Y1316071D03*
Y1321671D03*
X1446482Y1309315D03*
X1451882Y1312422D03*
X1449082Y1309315D03*
X1451682D03*
X1454482Y1312422D03*
X1454282Y1309315D03*
X1450956Y1316071D03*
X1448476D03*
X1453303Y1334095D03*
X1455436Y1335598D03*
X1461377Y1417844D03*
X1459135Y1439627D03*
X1459136Y1442241D03*
X1461517Y1575686D03*
Y1580678D03*
X1446600Y1595400D03*
X1461517Y1587598D03*
Y1592590D03*
X1460441Y1602441D03*
X1446786Y1610639D03*
X1452757Y1671399D03*
X1446380Y1676291D03*
X1464200Y67802D03*
X1470220Y145362D03*
X1470101Y207751D03*
X1476858Y225448D03*
X1466940Y230272D03*
X1466958Y244948D03*
X1468620Y258857D03*
X1467230Y252472D03*
X1466660Y273878D03*
X1475790Y404842D03*
X1473310Y418502D03*
X1463639Y653662D03*
X1469651Y655992D03*
X1462010Y645842D03*
X1463639Y665662D03*
X1478139Y660892D03*
X1469439Y670262D03*
X1463639Y677562D03*
X1463239Y689492D03*
X1478139Y689892D03*
X1469651Y684992D03*
X1463239Y701492D03*
X1478139Y704392D03*
X1469477Y699475D03*
X1463239Y713492D03*
X1478139Y718892D03*
X1469651Y713992D03*
X1474100Y735662D03*
X1466451Y726992D03*
X1474939Y731892D03*
X1472592Y1306345D03*
X1463026Y1306224D03*
X1465696Y1303480D03*
X1467046Y1305980D03*
X1468296Y1303480D03*
X1465696Y1300880D03*
X1468296D03*
X1472361Y1322440D03*
X1472592Y1308945D03*
Y1316745D03*
Y1314145D03*
Y1311545D03*
X1462926Y1312427D03*
X1463026Y1309331D03*
X1475599Y1349468D03*
X1475959Y1385027D03*
X1476000Y1393027D03*
X1465747Y1401405D03*
X1466448Y1421499D03*
X1475935Y1439627D03*
X1475936Y1442241D03*
X1467550Y1439642D03*
X1467536Y1442241D03*
X1473577Y1580678D03*
Y1575686D03*
X1466473D03*
Y1580678D03*
X1471773Y1599884D03*
X1466817D03*
X1473577Y1592590D03*
Y1587598D03*
X1466473D03*
Y1592590D03*
X1466817Y1611796D03*
X1471773D03*
X1466817Y1604876D03*
X1471773D03*
Y1616788D03*
X1466817D03*
X1478609Y49388D03*
X1481360Y358792D03*
X1488500Y410152D03*
X1478539Y675462D03*
X1486410Y1322741D03*
X1483810D03*
X1486410Y1319634D03*
X1483810D03*
X1481210Y1322741D03*
Y1319634D03*
X1492210D03*
X1489010D03*
X1478610Y1322741D03*
Y1319634D03*
X1484010Y1325848D03*
X1486610D03*
X1485564Y1335097D03*
X1483084D03*
X1485564Y1329497D03*
X1483084D03*
X1480604Y1335097D03*
Y1329497D03*
X1485523Y1347521D03*
X1487386Y1349258D03*
X1478559Y1385027D03*
X1481159Y1384727D03*
X1478600Y1393027D03*
X1481107Y1393095D03*
X1484395Y1439598D03*
X1484336Y1442241D03*
X1490593Y1580678D03*
Y1575686D03*
X1485637D03*
Y1580678D03*
X1478533D03*
Y1575686D03*
X1490937Y1599884D03*
X1478877D03*
X1483833D03*
X1490593Y1587598D03*
X1485637D03*
Y1592590D03*
X1490593D03*
X1478533D03*
Y1587598D03*
X1490937Y1604876D03*
Y1611796D03*
Y1616788D03*
X1483833D03*
X1478877D03*
Y1611796D03*
X1483833D03*
X1478877Y1604876D03*
X1483833D03*
X1498609Y49388D03*
X1496200Y359522D03*
X1497880Y373062D03*
X1503450Y382693D03*
X1497770Y732502D03*
X1495154Y1322757D03*
Y1319650D03*
X1499048Y1319946D03*
X1504720Y1329143D03*
X1495054Y1325853D03*
X1503786Y1326076D03*
X1504518Y1335982D03*
X1504720Y1342143D03*
Y1344743D03*
X1505116Y1369724D03*
X1509757Y1575686D03*
Y1580678D03*
X1502653D03*
X1497697D03*
X1502653Y1575686D03*
X1497697D03*
X1502997Y1599884D03*
X1507953D03*
X1495893D03*
X1509757Y1587598D03*
Y1592590D03*
X1502653D03*
X1497697D03*
X1502653Y1587598D03*
X1497697D03*
X1502997Y1616788D03*
X1507953D03*
X1502997Y1604876D03*
Y1611796D03*
X1507953Y1604876D03*
Y1611796D03*
X1495893Y1604876D03*
Y1611796D03*
Y1616788D03*
X1518608Y49377D03*
X1522920Y113030D03*
X1526675Y140117D03*
X1526083Y146225D03*
X1513759Y263676D03*
X1516683Y278437D03*
X1511624Y291175D03*
X1519336Y303426D03*
X1520094Y306543D03*
X1514369Y308467D03*
X1524505Y748912D03*
X1522066Y1312808D03*
X1526066D03*
X1518066D03*
X1515066D03*
X1511066D03*
X1510738Y1345539D03*
Y1342432D03*
X1518538Y1345539D03*
Y1342432D03*
X1515938Y1345539D03*
Y1342432D03*
X1513338Y1345539D03*
Y1342432D03*
X1521138D03*
X1524338D03*
X1518738Y1348646D03*
X1516138D03*
X1515212Y1352295D03*
X1512732D03*
X1517692D03*
X1515212Y1357895D03*
X1512732D03*
X1517692D03*
X1518451Y1369919D03*
X1521817Y1580678D03*
Y1575686D03*
X1514713D03*
Y1580678D03*
X1520013Y1599884D03*
X1515057D03*
X1521817Y1592590D03*
Y1587598D03*
X1514713D03*
Y1592590D03*
X1520013Y1604876D03*
X1515057D03*
X1520013Y1611796D03*
X1515057D03*
Y1616788D03*
X1520013D03*
X1534818Y66801D03*
Y71793D03*
X1539774Y66801D03*
Y71793D03*
X1541774Y69297D03*
X1532818D03*
X1534774Y103093D03*
X1529818D03*
X1535320Y113062D03*
X1529500Y129602D03*
X1545447Y156035D03*
X1537262Y197834D03*
X1540989Y616587D03*
X1535052Y1325904D03*
X1532552Y1334504D03*
X1535052D03*
X1529952D03*
X1532552Y1339704D03*
X1529952D03*
X1537652Y1325904D03*
Y1334504D03*
X1532552Y1337104D03*
X1529952D03*
X1538510Y1346392D03*
X1531302Y1342204D03*
X1535892Y1346354D03*
Y1343754D03*
X1527282Y1345555D03*
Y1342448D03*
X1538757Y1356355D03*
X1527182Y1348651D03*
X1538757Y1360855D03*
Y1365355D03*
X1533877Y1575592D03*
X1538833D03*
X1533877Y1580678D03*
X1538833D03*
X1526773D03*
Y1575686D03*
X1539177Y1599790D03*
X1527117Y1599884D03*
X1532073D03*
X1533877Y1587598D03*
X1538833D03*
X1533877Y1592590D03*
X1538833D03*
X1526773D03*
Y1587598D03*
X1539177Y1611796D03*
Y1604876D03*
Y1616788D03*
X1527117D03*
Y1604876D03*
Y1611796D03*
X1532073Y1616788D03*
Y1604876D03*
Y1611796D03*
X1547768Y3010D03*
X1555635Y16999D03*
Y21991D03*
X1553635Y19495D03*
X1553486Y23935D03*
X1548530D03*
X1546530Y25931D03*
X1555486D03*
X1547429Y37106D03*
X1554515D03*
Y48720D03*
X1547429D03*
X1554818Y69297D03*
X1556818Y66801D03*
Y71793D03*
X1543818Y75297D03*
X1552774D03*
X1550774Y77793D03*
Y72801D03*
X1545818Y77793D03*
Y72801D03*
X1554239Y138263D03*
X1554723Y200375D03*
X1557560Y196912D03*
X1554723Y224529D03*
Y248945D03*
X1554727Y631527D03*
X1550417Y677045D03*
X1550057Y693485D03*
X1548479Y706088D03*
X1557997Y1575686D03*
Y1580678D03*
X1550893D03*
X1545937D03*
X1550893Y1575686D03*
X1545937D03*
X1556193Y1599884D03*
X1551237D03*
X1544133Y1599790D03*
X1557997Y1587598D03*
Y1592590D03*
X1545937D03*
X1550893D03*
Y1587598D03*
X1545937D03*
X1551237Y1616788D03*
X1556193D03*
Y1604876D03*
X1551237D03*
X1556193Y1611796D03*
X1551237D03*
X1544133Y1604876D03*
Y1611796D03*
Y1616788D03*
X1567768Y3010D03*
X1560591Y16999D03*
Y21991D03*
X1569808Y16999D03*
Y21991D03*
X1574764Y16999D03*
Y21991D03*
X1562591Y19495D03*
X1567808D03*
X1567659Y23935D03*
X1562703D03*
X1560703Y25931D03*
X1569659D03*
X1574876D03*
X1561602Y37106D03*
X1568688D03*
Y48720D03*
X1561602D03*
X1563774Y69297D03*
X1561774Y66801D03*
Y71793D03*
X1565818Y75297D03*
X1574774D03*
X1572774Y77793D03*
Y72801D03*
X1567818Y77793D03*
Y72801D03*
X1559860Y240002D03*
X1575169Y303929D03*
X1560717Y648522D03*
X1570720Y729362D03*
X1570057Y1580678D03*
X1575013D03*
X1570057Y1575686D03*
X1575013D03*
X1562953D03*
Y1580678D03*
X1575357Y1599884D03*
X1563297D03*
X1568253D03*
X1570057Y1592590D03*
X1575013D03*
X1570057Y1587598D03*
X1575013D03*
X1562953D03*
Y1592590D03*
X1575357Y1616788D03*
Y1604876D03*
Y1611796D03*
X1563297Y1604876D03*
Y1611796D03*
X1568253Y1604876D03*
Y1611796D03*
X1563297Y1616788D03*
X1568253D03*
X1587768Y3010D03*
X1583981Y16999D03*
Y21991D03*
X1588937Y16999D03*
Y21991D03*
X1576764Y19495D03*
X1581981D03*
X1590937D03*
X1576876Y23935D03*
X1581832D03*
X1591050D03*
X1583832Y25931D03*
X1589050D03*
X1575775Y37106D03*
X1582862D03*
X1589948D03*
Y48720D03*
X1582862D03*
X1575775D03*
X1576818Y69297D03*
X1585774D03*
X1578818Y66801D03*
Y71793D03*
X1583774Y66801D03*
Y71793D03*
X1587818Y75297D03*
X1589818Y77793D03*
Y72801D03*
X1582117Y1575686D03*
X1587073D03*
X1582117Y1580678D03*
X1587073D03*
X1587417Y1599884D03*
X1580313D03*
X1582117Y1587598D03*
X1587073D03*
X1582117Y1592590D03*
X1587073D03*
X1587417Y1604876D03*
Y1611796D03*
Y1616788D03*
X1580313D03*
Y1604876D03*
Y1611796D03*
X1607768Y3010D03*
X1598155Y16999D03*
Y21991D03*
X1603111Y16999D03*
Y21991D03*
X1596155Y19495D03*
X1605111D03*
X1596006Y23935D03*
X1598006Y25931D03*
X1597035Y37106D03*
X1604122D03*
Y48720D03*
X1597035D03*
X1598818Y69297D03*
X1607774D03*
X1600818Y66801D03*
Y71793D03*
X1605774Y66801D03*
Y71793D03*
X1596774Y75297D03*
X1594774Y77793D03*
Y72801D03*
X1603778Y189943D03*
X1603726Y198061D03*
X1596444Y215526D03*
X1598030Y251002D03*
X1606980Y1449922D03*
X1606237Y1575686D03*
Y1580678D03*
X1594177D03*
X1599133D03*
X1594177Y1575686D03*
X1599133D03*
X1599477Y1599884D03*
X1604433D03*
X1592373D03*
X1606237Y1587598D03*
Y1592590D03*
X1594177D03*
X1599133D03*
X1594177Y1587598D03*
X1599133D03*
X1599477Y1616788D03*
X1604433D03*
X1599477Y1604876D03*
Y1611796D03*
X1604433Y1604876D03*
Y1611796D03*
X1592373Y1604876D03*
Y1611796D03*
Y1616788D03*
X1620818Y69297D03*
X1622818Y66801D03*
Y71793D03*
X1609818Y75297D03*
X1618774D03*
X1616774Y77793D03*
Y72801D03*
X1611818Y77793D03*
Y72801D03*
X1623448Y1420028D03*
Y1417428D03*
Y1414828D03*
Y1412228D03*
X1612630Y1418842D03*
X1615597Y1433669D03*
X1618297Y1580678D03*
X1623253D03*
X1618297Y1575686D03*
X1623253D03*
X1611193D03*
Y1580678D03*
X1623597Y1599884D03*
X1611537D03*
X1616493D03*
X1618297Y1592590D03*
X1623253D03*
X1618297Y1587598D03*
X1623253D03*
X1611193D03*
Y1592590D03*
X1623597Y1616788D03*
Y1604876D03*
Y1611796D03*
X1611537Y1604876D03*
Y1611796D03*
X1616493Y1604876D03*
Y1611796D03*
X1611537Y1616788D03*
X1616493D03*
X1634021Y16999D03*
Y21991D03*
X1638977Y16999D03*
Y21991D03*
X1632021Y19495D03*
X1631872Y23935D03*
X1626916D03*
X1624916Y25931D03*
X1633872D03*
X1639089D03*
X1625814Y37106D03*
X1632901D03*
X1639988D03*
X1625814Y48720D03*
X1632901D03*
X1639988D03*
X1629774Y69297D03*
X1627774Y66801D03*
Y71793D03*
X1633022Y75297D03*
X1635022Y77793D03*
X1639978D03*
Y72801D03*
X1635022D03*
X1635032Y196188D03*
X1642135Y414202D03*
X1629262Y1394418D03*
X1625948Y1417428D03*
Y1412228D03*
X1633103Y1417907D03*
X1630503D03*
X1635703D03*
X1633103Y1421014D03*
X1630503D03*
X1635703D03*
X1638303Y1417907D03*
Y1421014D03*
X1625948Y1414828D03*
Y1420028D03*
X1635903Y1424121D03*
X1638503D03*
X1632516Y1427753D03*
Y1433353D03*
X1634986Y1427753D03*
Y1433353D03*
X1637416Y1427753D03*
Y1433353D03*
X1627591Y1447796D03*
X1637478Y1445150D03*
X1630357Y1575592D03*
X1635313D03*
X1630357Y1580678D03*
X1635313D03*
X1640613Y1599790D03*
X1635657D03*
X1628553Y1599884D03*
X1630357Y1587598D03*
X1635313D03*
X1630357Y1592590D03*
X1635313D03*
X1640613Y1604876D03*
Y1611796D03*
X1635657Y1604876D03*
Y1611796D03*
X1640613Y1616788D03*
X1635657D03*
X1628553D03*
Y1604876D03*
Y1611796D03*
X1648194Y16999D03*
Y21991D03*
X1653150Y16999D03*
Y21991D03*
X1640977Y19495D03*
X1646194D03*
X1655150D03*
X1641089Y23935D03*
X1646045D03*
X1648045Y25931D03*
X1654161Y37106D03*
X1647074D03*
Y48720D03*
X1654161D03*
X1644022Y69297D03*
X1652978D03*
X1646022Y66801D03*
Y71793D03*
X1650978Y66801D03*
Y71793D03*
X1655022Y75297D03*
X1641978D03*
X1657022Y77793D03*
Y72801D03*
X1652610Y394727D03*
X1652810Y407402D03*
X1647110Y434177D03*
X1651890Y520540D03*
X1649220Y620662D03*
X1656188Y1394736D03*
X1647592Y1394418D03*
X1655779Y1417618D03*
Y1412418D03*
Y1415018D03*
X1644103Y1417907D03*
X1647047Y1417923D03*
Y1421030D03*
X1653279Y1412418D03*
X1650679D03*
X1653279Y1415018D03*
X1650679D03*
X1653168Y1417618D03*
X1650557D03*
X1640903Y1417907D03*
X1647016Y1424153D03*
X1648947Y1476695D03*
X1647373Y1580678D03*
X1642417D03*
X1647373Y1575686D03*
X1642417D03*
X1647717Y1599884D03*
X1652673D03*
X1647373Y1592590D03*
X1642417D03*
X1647373Y1587598D03*
X1642417D03*
X1647717Y1616788D03*
X1652673D03*
X1647717Y1604876D03*
Y1611796D03*
X1652673Y1604876D03*
Y1611796D03*
X1671050Y23935D03*
X1669050Y25931D03*
X1669948Y37106D03*
Y48720D03*
X1666022Y69297D03*
X1668022Y66801D03*
Y71793D03*
X1672978Y66801D03*
Y71793D03*
X1663978Y75297D03*
X1661978Y77793D03*
Y72801D03*
X1668030Y200580D03*
X1666074Y229710D03*
X1660176Y231100D03*
X1670400Y229462D03*
X1659610Y394727D03*
X1663610D03*
X1661110Y434177D03*
X1660866Y546749D03*
X1664040Y569642D03*
X1668040D03*
X1672040D03*
X1662120Y604782D03*
X1657220Y620662D03*
X1667405Y1394418D03*
X1659260Y1394693D03*
X1658390Y1420218D03*
Y1415018D03*
Y1412418D03*
Y1417618D03*
X1663590Y1420218D03*
X1660990D03*
Y1415018D03*
Y1417618D03*
Y1412418D03*
X1663590Y1415018D03*
Y1417618D03*
Y1412418D03*
X1668646Y1417907D03*
Y1421014D03*
X1671246Y1417907D03*
Y1421014D03*
X1670659Y1427753D03*
X1673129D03*
X1670659Y1433353D03*
X1673129D03*
X1657438Y1438156D03*
X1660428Y1447566D03*
X1667577Y1447545D03*
X1666123Y1497362D03*
X1665940Y1512862D03*
X1666110Y1504662D03*
X1666123Y1524862D03*
Y1537862D03*
Y1541862D03*
Y1553557D03*
X1666198Y1565557D03*
Y1585321D03*
X1678155Y16999D03*
Y21991D03*
X1683111Y16999D03*
Y21991D03*
X1676155Y19495D03*
X1685111D03*
X1676006Y23935D03*
X1685223D03*
X1678006Y25931D03*
X1683223D03*
X1677035Y37106D03*
X1684122D03*
X1677035Y48720D03*
X1684122D03*
X1688156Y69297D03*
X1674978D03*
X1677156Y75297D03*
X1686112D03*
X1684112Y77793D03*
Y72801D03*
X1679156Y77793D03*
Y72801D03*
X1676300Y219762D03*
X1681900Y227962D03*
X1682810Y465940D03*
X1676040Y569627D03*
X1688301Y722158D03*
X1683121D03*
X1680401D03*
X1686135Y1394418D03*
X1687860Y1415179D03*
X1689210Y1417679D03*
X1687860Y1412579D03*
X1685190Y1417923D03*
X1676446Y1417907D03*
X1679046D03*
X1682246D03*
X1676446Y1421014D03*
X1685190Y1421030D03*
X1673846Y1417907D03*
Y1421014D03*
X1676646Y1424121D03*
X1685159Y1424153D03*
X1675559Y1427753D03*
Y1433353D03*
X1674046Y1424121D03*
X1675621Y1445150D03*
X1679508Y1503421D03*
Y1522921D03*
Y1543921D03*
Y1563380D03*
Y1583880D03*
X1692328Y16999D03*
Y21991D03*
X1697284Y16999D03*
Y21991D03*
X1690328Y19495D03*
X1699284D03*
X1690179Y23935D03*
X1692179Y25931D03*
X1691208Y37106D03*
X1698295D03*
X1705381D03*
X1698295Y48720D03*
X1691208D03*
X1705381D03*
X1697112Y69297D03*
X1690156Y66801D03*
Y71793D03*
X1695112Y66801D03*
Y71793D03*
X1699156Y75297D03*
X1701156Y77793D03*
Y72801D03*
X1695950Y96437D03*
X1697725Y205120D03*
X1700846Y455894D03*
X1702760Y478207D03*
X1696760D03*
X1702760Y490207D03*
X1696760D03*
Y484207D03*
X1696120Y506937D03*
X1703720Y509362D03*
X1696851Y515607D03*
X1693701D03*
X1702270Y552742D03*
X1698920Y698562D03*
X1695227Y722325D03*
X1699307Y722465D03*
X1698137Y718345D03*
X1701087Y719055D03*
X1695367Y719345D03*
X1691021Y722158D03*
X1698537Y766015D03*
X1690809Y1393970D03*
X1699150Y1393613D03*
X1690460Y1415179D03*
Y1412579D03*
X1691918Y1417676D03*
X1692960Y1415179D03*
Y1412579D03*
X1693404Y1421939D03*
X1699593Y1428384D03*
X1697820Y1423616D03*
X1699545Y1425868D03*
X1699437Y1431295D03*
X1699457Y1439185D03*
Y1447805D03*
X1691988Y1498303D03*
Y1517803D03*
Y1538803D03*
Y1558262D03*
X1714520Y37162D03*
X1710920Y82162D03*
X1708112Y75297D03*
X1706112Y77793D03*
Y72801D03*
X1708000Y99122D03*
X1714180Y154790D03*
X1721400Y374462D03*
X1711477Y465229D03*
Y468379D03*
X1708760Y478031D03*
Y490207D03*
Y484207D03*
X1710500Y538162D03*
X1706720Y703762D03*
X1709107Y728449D03*
X1718149Y1496270D03*
X1717149Y1505895D03*
X1720174D03*
X1717988Y1520951D03*
X1711988D03*
X1717149Y1513945D03*
X1720174D03*
X1714988Y1520951D03*
X1708988D03*
X1717988Y1530445D03*
X1714988D03*
X1708988D03*
X1711988D03*
X1727768Y3010D03*
X1732320Y28162D03*
X1728820D03*
X1725320D03*
X1729520Y61762D03*
X1729620Y57262D03*
X1730820Y76362D03*
X1726918Y101967D03*
X1733378Y134907D03*
X1736508D03*
X1723240Y185200D03*
X1737704Y183139D03*
X1737260Y368132D03*
X1732660Y372692D03*
X1725400Y372062D03*
X1725500Y383662D03*
X1737434Y398990D03*
X1727760Y420415D03*
X1747768Y3010D03*
X1754090Y16302D03*
X1748400Y37262D03*
X1753398Y48720D03*
X1745485Y119539D03*
X1747482Y121367D03*
X1741222Y151527D03*
X1747591Y171733D03*
X1751084Y190928D03*
X1745000Y299862D03*
X1746970Y1451872D03*
X1750970Y1459172D03*
Y1456172D03*
X1767768Y3010D03*
X1769900Y37732D03*
X1760485Y48720D03*
X1759700Y57662D03*
X1764400Y57462D03*
X1758063Y68637D03*
X1758573Y87107D03*
Y83607D03*
X1768168Y80497D03*
X1758568Y79697D03*
X1765068Y80397D03*
X1766278Y93627D03*
X1768483Y166260D03*
X1763731Y283817D03*
X1766725Y282981D03*
X1763731Y279517D03*
X1760398Y279548D03*
X1766765Y279433D03*
X1757439Y279611D03*
X1760398Y283848D03*
X1759509Y292434D03*
X1762549Y286704D03*
X1757439Y283911D03*
X1768045Y295238D03*
X1765053Y295188D03*
X1762285Y295137D03*
X1759629Y295164D03*
X1767309Y290994D03*
X1763045Y289691D03*
X1759529Y289864D03*
X1766655Y286531D03*
X1767455Y302651D03*
X1758563Y310478D03*
X1754963D03*
X1770520Y364148D03*
Y368148D03*
X1767300Y461393D03*
X1765670Y458012D03*
X1767300Y465893D03*
X1764112Y703948D03*
X1761612D03*
X1764112Y695648D03*
X1763570Y693192D03*
X1761612Y695648D03*
X1764072Y720508D03*
X1761572D03*
X1764112Y712248D03*
X1761612D03*
X1760160Y1476032D03*
X1763730Y1483712D03*
Y1480712D03*
X1763830Y1490782D03*
Y1487782D03*
X1785178Y86927D03*
Y89927D03*
X1784238Y150744D03*
X1786690Y234782D03*
Y231782D03*
X1771029Y295164D03*
X1771229Y291064D03*
X1772863Y310478D03*
X1782420Y443987D03*
X1773870Y438222D03*
X1776160Y592792D03*
X1787768Y3010D03*
X1794910Y44573D03*
X1797324Y161465D03*
X1803129Y362293D03*
X1802929Y385293D03*
X1795479Y408056D03*
X1795468Y421334D03*
X1800107Y1256426D03*
X1795484Y1496401D03*
X1792645Y1511423D03*
X1798450Y1524830D03*
X1801450D03*
Y1527830D03*
X1814322Y49388D03*
X1807549Y56415D03*
X1807580Y59397D03*
X1810835Y163986D03*
X1806365Y154032D03*
X1819939Y177243D03*
X1820307Y373829D03*
X1820144Y398052D03*
X1819374Y410432D03*
X1818874Y423932D03*
X1818816Y468872D03*
X1803517Y1495567D03*
X1818410Y1525815D03*
X1812250Y1521830D03*
X1811250Y1524830D03*
Y1527830D03*
X1807850D03*
X1804650D03*
Y1524830D03*
X1807850D03*
X1814370Y1528900D03*
X1814210Y1525815D03*
X1818524Y1528991D03*
X1834322Y49388D03*
X1823508Y158868D03*
X1829026Y367701D03*
X1823426Y1507916D03*
X1831994Y1525977D03*
X1835334Y1520921D03*
X1828510Y1525915D03*
X1821710D03*
X1830466Y1606658D03*
X1838910Y185772D03*
X1843134Y244362D03*
X1836750Y373632D03*
X1838020Y459121D03*
X1854096Y52383D03*
G54D42*
X335349Y985939D03*
X549278Y949619D03*
X1300207Y177799D03*
X1311491Y985939D03*
X1355761Y177798D03*
X1525420Y949619D03*
X1879155Y592848D03*
Y840748D03*
X1889155Y592848D03*
Y840748D03*
X1900275Y964708D03*
X1910275D03*
X1931395Y592868D03*
X1921395D03*
X1952395Y1205248D03*
X1942395D03*
X1963362Y593010D03*
X1973362D03*
X1984482Y1205220D03*
X1994482D03*
X2015452Y593020D03*
X2005452D03*
X2026452Y1205400D03*
X2047419Y593162D03*
X2036452Y1205400D03*
X2057419Y593162D03*
X2078539Y1205372D03*
X2068539D03*
G54D56*
X828780Y1694890D03*
Y1684890D03*
X818780Y1694890D03*
Y1684890D03*
X828780Y1704890D03*
X818780D03*
X828780Y1714890D03*
X818780D03*
X853780Y1694890D03*
Y1684890D03*
Y1704890D03*
Y1714890D03*
X863780Y1694890D03*
Y1684890D03*
Y1704890D03*
Y1714890D03*
X888780Y1684890D03*
Y1694890D03*
Y1704890D03*
Y1714890D03*
X898780Y1684890D03*
Y1694890D03*
Y1704890D03*
Y1714890D03*
X918780Y1704890D03*
X958780Y1694890D03*
Y1684890D03*
Y1704890D03*
Y1714890D03*
X968780Y1694890D03*
Y1684890D03*
Y1704890D03*
Y1714890D03*
X993780Y1684890D03*
Y1694890D03*
X1003780Y1684890D03*
Y1694890D03*
X993780Y1704890D03*
Y1714890D03*
X1003780Y1704890D03*
Y1714890D03*
X1028780Y1684890D03*
Y1694890D03*
X1038780Y1684890D03*
Y1694890D03*
X1028780Y1704890D03*
Y1714890D03*
X1038780Y1704890D03*
Y1714890D03*
G54D16*
X27699Y770144D03*
Y783530D03*
Y776837D03*
Y800263D03*
Y793570D03*
Y820341D03*
Y813648D03*
Y806955D03*
Y830381D03*
Y850459D03*
Y843766D03*
Y837074D03*
Y867192D03*
Y857152D03*
Y880577D03*
Y873885D03*
Y893963D03*
Y887270D03*
Y917389D03*
Y910696D03*
Y904003D03*
Y930774D03*
Y924081D03*
Y947507D03*
Y940814D03*
Y964239D03*
Y954200D03*
Y977625D03*
Y970932D03*
Y991011D03*
Y984318D03*
Y1031168D03*
Y1024475D03*
Y1017782D03*
Y1044554D03*
Y1037861D03*
Y1057940D03*
Y1051247D03*
Y1078018D03*
Y1071326D03*
Y1064633D03*
Y1094751D03*
Y1088058D03*
Y1108137D03*
Y1101444D03*
Y1124869D03*
Y1114829D03*
Y1144948D03*
Y1138255D03*
Y1131562D03*
Y1161680D03*
Y1151641D03*
Y1175066D03*
Y1168373D03*
Y1188452D03*
Y1181759D03*
Y1205184D03*
Y1198491D03*
Y1225263D03*
Y1218570D03*
Y1211877D03*
Y1241995D03*
Y1235302D03*
Y1248688D03*
X43841Y766798D03*
X36399Y770144D03*
X43841Y780184D03*
Y773491D03*
X36399Y783530D03*
Y776837D03*
X43841Y803609D03*
Y796916D03*
Y790223D03*
X36399Y800263D03*
Y793570D03*
X43841Y816995D03*
Y810302D03*
X36399Y820341D03*
Y813648D03*
Y806955D03*
X43841Y833727D03*
Y827034D03*
X36399Y830381D03*
X43841Y847113D03*
Y840420D03*
X36399Y850459D03*
Y843766D03*
Y837074D03*
X43841Y863845D03*
Y853806D03*
X36399Y867192D03*
Y857152D03*
X43841Y883924D03*
Y877231D03*
Y870538D03*
X36399Y880577D03*
Y873885D03*
X43841Y900656D03*
Y890617D03*
X36399Y893963D03*
Y887270D03*
X43841Y914042D03*
Y907349D03*
X36399Y917389D03*
Y910696D03*
Y904003D03*
X43841Y927428D03*
Y920735D03*
X36399Y930774D03*
Y924081D03*
X43841Y944160D03*
Y937467D03*
X36399Y947507D03*
Y940814D03*
X43841Y960892D03*
Y950853D03*
X36399Y964239D03*
Y954200D03*
X43841Y980971D03*
Y974278D03*
Y967585D03*
X36399Y977625D03*
Y970932D03*
X43841Y987664D03*
X36399Y991011D03*
Y984318D03*
X43841Y1027822D03*
Y1017782D03*
X36399Y1031168D03*
Y1024475D03*
Y1017782D03*
X43841Y1047900D03*
Y1041207D03*
Y1034515D03*
X36399Y1044554D03*
Y1037861D03*
X43841Y1061286D03*
Y1054593D03*
X36399Y1057940D03*
Y1051247D03*
X43841Y1074672D03*
Y1067979D03*
X36399Y1078018D03*
Y1071326D03*
Y1064633D03*
X43841Y1091404D03*
Y1084711D03*
X36399Y1094751D03*
Y1088058D03*
X43841Y1111483D03*
Y1104790D03*
Y1098097D03*
X36399Y1108137D03*
Y1101444D03*
X43841Y1128215D03*
Y1121522D03*
X36399Y1124869D03*
Y1114829D03*
X43841Y1141601D03*
Y1134908D03*
X36399Y1144948D03*
Y1138255D03*
Y1131562D03*
X43841Y1158333D03*
Y1148294D03*
X36399Y1161680D03*
Y1151641D03*
X43841Y1171719D03*
Y1165026D03*
X36399Y1175066D03*
Y1168373D03*
X43841Y1185105D03*
Y1178412D03*
X36399Y1188452D03*
Y1181759D03*
X43841Y1208530D03*
Y1201837D03*
Y1195144D03*
X36399Y1205184D03*
Y1198491D03*
X43841Y1221916D03*
Y1215223D03*
X36399Y1225263D03*
Y1218570D03*
Y1211877D03*
X43841Y1238648D03*
Y1231955D03*
X36399Y1241995D03*
Y1235302D03*
X43841Y1245341D03*
X36399Y1248688D03*
X36449Y1257262D03*
X33546Y1273364D03*
X30746D03*
X57399Y770144D03*
X52541Y766798D03*
X57399Y783530D03*
Y776837D03*
X52541Y780184D03*
Y773491D03*
X57399Y800263D03*
Y793570D03*
X52541Y803609D03*
Y796916D03*
Y790223D03*
X57399Y820341D03*
Y813648D03*
Y806955D03*
X52541Y816995D03*
Y810302D03*
X57399Y830381D03*
X52541Y833727D03*
Y827034D03*
X57399Y850459D03*
Y843766D03*
Y837074D03*
X52541Y847113D03*
Y840420D03*
X57399Y867192D03*
Y857152D03*
X52541Y863845D03*
Y853806D03*
X57399Y880577D03*
Y873885D03*
X52541Y883924D03*
Y877231D03*
Y870538D03*
X57399Y893963D03*
Y887270D03*
X52541Y900656D03*
Y890617D03*
X57399Y917389D03*
Y910696D03*
Y904003D03*
X52541Y914042D03*
Y907349D03*
X57399Y930774D03*
Y924081D03*
X52541Y927428D03*
Y920735D03*
X57399Y947507D03*
Y940814D03*
X52541Y944160D03*
Y937467D03*
X57399Y964239D03*
Y954200D03*
X52541Y960892D03*
Y950853D03*
X57399Y977625D03*
Y970932D03*
X52541Y980971D03*
Y974278D03*
Y967585D03*
X57399Y991011D03*
Y984318D03*
X52541Y987664D03*
X57399Y1031168D03*
Y1024475D03*
Y1017782D03*
X52541Y1027822D03*
Y1017782D03*
X57399Y1044554D03*
Y1037861D03*
X52541Y1047900D03*
Y1041207D03*
Y1034515D03*
X57399Y1057940D03*
Y1051247D03*
X52541Y1061286D03*
Y1054593D03*
X57399Y1078018D03*
Y1071326D03*
Y1064633D03*
X52541Y1074672D03*
Y1067979D03*
X57399Y1094751D03*
Y1088058D03*
X52541Y1091404D03*
Y1084711D03*
X57399Y1108137D03*
Y1101444D03*
X52541Y1111483D03*
Y1104790D03*
Y1098097D03*
X57399Y1124869D03*
Y1114829D03*
X52541Y1128215D03*
Y1121522D03*
X57399Y1144948D03*
Y1138255D03*
Y1131562D03*
X52541Y1141601D03*
Y1134908D03*
X57399Y1161680D03*
Y1151641D03*
X52541Y1158333D03*
Y1148294D03*
X57399Y1175066D03*
Y1168373D03*
X52541Y1171719D03*
Y1165026D03*
X57399Y1188452D03*
Y1181759D03*
X52541Y1185105D03*
Y1178412D03*
X57399Y1205184D03*
Y1198491D03*
X52541Y1208530D03*
Y1201837D03*
Y1195144D03*
X57399Y1225263D03*
Y1218570D03*
Y1211877D03*
X52541Y1221916D03*
Y1215223D03*
X57399Y1241995D03*
Y1235302D03*
X52541Y1238648D03*
Y1231955D03*
Y1248688D03*
X57399D03*
X52541Y1245341D03*
X60446Y1273364D03*
X49546D03*
X46746D03*
X73541Y766798D03*
X66099Y770144D03*
X73541Y780184D03*
Y773491D03*
X66099Y783530D03*
Y776837D03*
X73541Y803609D03*
Y796916D03*
Y790223D03*
X66099Y800263D03*
Y793570D03*
X73541Y816995D03*
Y810302D03*
X66099Y820341D03*
Y813648D03*
Y806955D03*
X73541Y833727D03*
Y827034D03*
X66099Y830381D03*
X73541Y847113D03*
Y840420D03*
X66099Y850459D03*
Y843766D03*
Y837074D03*
X73541Y863845D03*
Y853806D03*
X66099Y867192D03*
Y857152D03*
X73541Y883924D03*
Y877231D03*
Y870538D03*
X66099Y880577D03*
Y873885D03*
X73541Y900656D03*
Y890617D03*
X66099Y893963D03*
Y887270D03*
X73541Y914042D03*
Y907349D03*
X66099Y917389D03*
Y910696D03*
Y904003D03*
X73541Y927428D03*
Y920735D03*
X66099Y930774D03*
Y924081D03*
X73541Y944160D03*
Y937467D03*
X66099Y947507D03*
Y940814D03*
X73541Y960892D03*
Y950853D03*
X66099Y964239D03*
Y954200D03*
X73541Y980971D03*
Y974278D03*
Y967585D03*
X66099Y977625D03*
Y970932D03*
X73541Y987664D03*
X66099Y991011D03*
Y984318D03*
X73541Y1027822D03*
Y1017782D03*
X66099Y1031168D03*
Y1024475D03*
Y1017782D03*
X73541Y1047900D03*
Y1041207D03*
Y1034515D03*
X66099Y1044554D03*
Y1037861D03*
X73541Y1061286D03*
Y1054593D03*
X66099Y1057940D03*
Y1051247D03*
X73541Y1074672D03*
Y1067979D03*
X66099Y1078018D03*
Y1071326D03*
Y1064633D03*
X73541Y1091404D03*
Y1084711D03*
X66099Y1094751D03*
Y1088058D03*
X73541Y1111483D03*
Y1104790D03*
Y1098097D03*
X66099Y1108137D03*
Y1101444D03*
X73541Y1128215D03*
Y1121522D03*
X66099Y1124869D03*
Y1114829D03*
X73541Y1141601D03*
Y1134908D03*
X66099Y1144948D03*
Y1138255D03*
Y1131562D03*
X73541Y1158333D03*
Y1148294D03*
X66099Y1161680D03*
Y1151641D03*
X73541Y1171719D03*
Y1165026D03*
X66099Y1175066D03*
Y1168373D03*
X73541Y1185105D03*
Y1178412D03*
X66099Y1188452D03*
Y1181759D03*
X73541Y1208530D03*
Y1201837D03*
Y1195144D03*
X66099Y1205184D03*
Y1198491D03*
X73541Y1221916D03*
Y1215223D03*
X66099Y1225263D03*
Y1218570D03*
Y1211877D03*
X73541Y1238648D03*
Y1231955D03*
X66099Y1241995D03*
Y1235302D03*
X66189Y1257488D03*
X73541Y1245341D03*
X66099Y1248688D03*
X76446Y1273364D03*
X63246D03*
X87099Y770144D03*
X82241Y766798D03*
X87099Y783530D03*
Y776837D03*
X82241Y780184D03*
Y773491D03*
X87099Y800263D03*
Y793570D03*
X82241Y803609D03*
Y796916D03*
Y790223D03*
X87099Y820341D03*
Y813648D03*
Y806955D03*
X82241Y816995D03*
Y810302D03*
X87099Y830381D03*
X82241Y833727D03*
Y827034D03*
X87099Y850459D03*
Y843766D03*
Y837074D03*
X82241Y847113D03*
Y840420D03*
X87099Y867192D03*
Y857152D03*
X82241Y863845D03*
Y853806D03*
X87099Y880577D03*
Y873885D03*
X82241Y883924D03*
Y877231D03*
Y870538D03*
X87099Y893963D03*
Y887270D03*
X82241Y900656D03*
Y890617D03*
X87099Y917389D03*
Y910696D03*
Y904003D03*
X82241Y914042D03*
Y907349D03*
X87099Y930774D03*
Y924081D03*
X82241Y927428D03*
Y920735D03*
X87099Y947507D03*
Y940814D03*
X82241Y944160D03*
Y937467D03*
X87099Y964239D03*
Y954200D03*
X82241Y960892D03*
Y950853D03*
X87099Y977625D03*
Y970932D03*
X82241Y980971D03*
Y974278D03*
Y967585D03*
X87099Y991011D03*
Y984318D03*
X82241Y987664D03*
X87099Y1031168D03*
Y1024475D03*
Y1017782D03*
X82241Y1027822D03*
Y1017782D03*
X87099Y1044554D03*
Y1037861D03*
X82241Y1047900D03*
Y1041207D03*
Y1034515D03*
X87099Y1057940D03*
Y1051247D03*
X82241Y1061286D03*
Y1054593D03*
X87099Y1078018D03*
Y1071326D03*
Y1064633D03*
X82241Y1074672D03*
Y1067979D03*
X87099Y1094751D03*
Y1088058D03*
X82241Y1091404D03*
Y1084711D03*
X87099Y1108137D03*
Y1101444D03*
X82241Y1111483D03*
Y1104790D03*
Y1098097D03*
X87099Y1124869D03*
Y1114829D03*
X82241Y1128215D03*
Y1121522D03*
X87099Y1144948D03*
Y1138255D03*
Y1131562D03*
X82241Y1141601D03*
Y1134908D03*
X87099Y1161680D03*
Y1151641D03*
X82241Y1158333D03*
Y1148294D03*
X87099Y1175066D03*
Y1168373D03*
X82241Y1171719D03*
Y1165026D03*
X87099Y1188452D03*
Y1181759D03*
X82241Y1185105D03*
Y1178412D03*
X87099Y1205184D03*
Y1198491D03*
X82241Y1208530D03*
Y1201837D03*
Y1195144D03*
X87099Y1225263D03*
Y1218570D03*
Y1211877D03*
X82241Y1221916D03*
Y1215223D03*
X87099Y1241995D03*
Y1235302D03*
X82241Y1238648D03*
Y1231955D03*
X87099Y1248688D03*
X82241Y1245341D03*
X92946Y1273364D03*
X90146D03*
X79246D03*
X103241Y766798D03*
X95799Y770144D03*
X103241Y780184D03*
Y773491D03*
X95799Y783530D03*
Y776837D03*
X103241Y803609D03*
Y796916D03*
Y790223D03*
X95799Y800263D03*
Y793570D03*
X103241Y816995D03*
Y810302D03*
X95799Y820341D03*
Y813648D03*
Y806955D03*
X103241Y833727D03*
Y827034D03*
X95799Y830381D03*
X103241Y847113D03*
Y840420D03*
X95799Y850459D03*
Y843766D03*
Y837074D03*
X103241Y863845D03*
Y853806D03*
X95799Y867192D03*
Y857152D03*
X103241Y883924D03*
Y877231D03*
Y870538D03*
X95799Y880577D03*
Y873885D03*
X103241Y900656D03*
Y890617D03*
X95799Y893963D03*
Y887270D03*
X103241Y914042D03*
Y907349D03*
X95799Y917389D03*
Y910696D03*
Y904003D03*
X103241Y927428D03*
Y920735D03*
X95799Y930774D03*
Y924081D03*
X103241Y944160D03*
Y937467D03*
X95799Y947507D03*
Y940814D03*
X103241Y960892D03*
Y950853D03*
X95799Y964239D03*
Y954200D03*
X103241Y980971D03*
Y974278D03*
Y967585D03*
X95799Y977625D03*
Y970932D03*
X103241Y987664D03*
X95799Y991011D03*
Y984318D03*
X103241Y1027822D03*
Y1017782D03*
X95799Y1031168D03*
Y1024475D03*
Y1017782D03*
X103241Y1047900D03*
Y1041207D03*
Y1034515D03*
X95799Y1044554D03*
Y1037861D03*
X103241Y1061286D03*
Y1054593D03*
X95799Y1057940D03*
Y1051247D03*
X103241Y1074672D03*
Y1067979D03*
X95799Y1078018D03*
Y1071326D03*
Y1064633D03*
X103241Y1091404D03*
Y1084711D03*
X95799Y1094751D03*
Y1088058D03*
X103241Y1111483D03*
Y1104790D03*
Y1098097D03*
X95799Y1108137D03*
Y1101444D03*
X103241Y1128215D03*
Y1121522D03*
X95799Y1124869D03*
Y1114829D03*
X103241Y1141601D03*
Y1134908D03*
X95799Y1144948D03*
Y1138255D03*
Y1131562D03*
X103241Y1158333D03*
Y1148294D03*
X95799Y1161680D03*
Y1151641D03*
X103241Y1171719D03*
Y1165026D03*
X95799Y1175066D03*
Y1168373D03*
X103241Y1185105D03*
Y1178412D03*
X95799Y1188452D03*
Y1181759D03*
X103241Y1208530D03*
Y1201837D03*
Y1195144D03*
X95799Y1205184D03*
Y1198491D03*
X103241Y1221916D03*
Y1215223D03*
X95799Y1225263D03*
Y1218570D03*
Y1211877D03*
X103241Y1238648D03*
Y1231955D03*
X95799Y1241995D03*
Y1235302D03*
X95849Y1257262D03*
X103241Y1245341D03*
X95799Y1248688D03*
X108946Y1273364D03*
X106146D03*
X125499Y770144D03*
X116799D03*
X111941Y766798D03*
X125499Y783530D03*
X116799D03*
X125499Y776837D03*
X116799D03*
X111941Y780184D03*
Y773491D03*
X125499Y800263D03*
X116799D03*
X125499Y793570D03*
X116799D03*
X111941Y803609D03*
Y796916D03*
Y790223D03*
X125499Y820341D03*
X116799D03*
X125499Y813648D03*
X116799D03*
X125499Y806955D03*
X116799D03*
X111941Y816995D03*
Y810302D03*
X125499Y830381D03*
X116799D03*
X111941Y833727D03*
Y827034D03*
X125499Y850459D03*
X116799D03*
X125499Y843766D03*
X116799D03*
X125499Y837074D03*
X116799D03*
X111941Y847113D03*
Y840420D03*
X125499Y867192D03*
X116799D03*
X125499Y857152D03*
X116799D03*
X111941Y863845D03*
Y853806D03*
X125499Y880577D03*
X116799D03*
X125499Y873885D03*
X116799D03*
X111941Y883924D03*
Y877231D03*
Y870538D03*
X125499Y893963D03*
X116799D03*
X125499Y887270D03*
X116799D03*
X111941Y900656D03*
Y890617D03*
X125499Y917389D03*
X116799D03*
X125499Y910696D03*
X116799D03*
X125499Y904003D03*
X116799D03*
X111941Y914042D03*
Y907349D03*
X125499Y930774D03*
X116799D03*
X125499Y924081D03*
X116799D03*
X111941Y927428D03*
Y920735D03*
X125499Y947507D03*
X116799D03*
X125499Y940814D03*
X116799D03*
X111941Y944160D03*
Y937467D03*
X125499Y964239D03*
X116799D03*
X125499Y954200D03*
X116799D03*
X111941Y960892D03*
Y950853D03*
X125499Y977625D03*
X116799D03*
X125499Y970932D03*
X116799D03*
X111941Y980971D03*
Y974278D03*
Y967585D03*
X125499Y991011D03*
X116799D03*
X125499Y984318D03*
X116799D03*
X111941Y987664D03*
X125499Y1031168D03*
X116799D03*
X125499Y1024475D03*
X116799D03*
X125499Y1017782D03*
X116799D03*
X111941Y1027822D03*
Y1017782D03*
X125499Y1044554D03*
X116799D03*
X125499Y1037861D03*
X116799D03*
X111941Y1047900D03*
Y1041207D03*
Y1034515D03*
X125499Y1057940D03*
X116799D03*
X125499Y1051247D03*
X116799D03*
X111941Y1061286D03*
Y1054593D03*
X125499Y1078018D03*
X116799D03*
X125499Y1071326D03*
X116799D03*
X125499Y1064633D03*
X116799D03*
X111941Y1074672D03*
Y1067979D03*
X125499Y1094751D03*
X116799D03*
X125499Y1088058D03*
X116799D03*
X111941Y1091404D03*
Y1084711D03*
X125499Y1108137D03*
X116799D03*
X125499Y1101444D03*
X116799D03*
X111941Y1111483D03*
Y1104790D03*
Y1098097D03*
X125499Y1124869D03*
X116799D03*
X125499Y1114829D03*
X116799D03*
X111941Y1128215D03*
Y1121522D03*
X125499Y1144948D03*
X116799D03*
X125499Y1138255D03*
X116799D03*
X125499Y1131562D03*
X116799D03*
X111941Y1141601D03*
Y1134908D03*
X125499Y1161680D03*
X116799D03*
X125499Y1151641D03*
X116799D03*
X111941Y1158333D03*
Y1148294D03*
X125499Y1175066D03*
X116799D03*
X125499Y1168373D03*
X116799D03*
X111941Y1171719D03*
Y1165026D03*
X125499Y1188452D03*
X116799D03*
X125499Y1181759D03*
X116799D03*
X111941Y1185105D03*
Y1178412D03*
X125499Y1205184D03*
X116799D03*
X125499Y1198491D03*
X116799D03*
X111941Y1208530D03*
Y1201837D03*
Y1195144D03*
X125499Y1225263D03*
X116799D03*
X125499Y1218570D03*
X116799D03*
X125499Y1211877D03*
X116799D03*
X111941Y1221916D03*
Y1215223D03*
X125499Y1241995D03*
X116799D03*
X125499Y1235302D03*
X116799D03*
X111941Y1238648D03*
Y1231955D03*
X125412Y1257102D03*
X125499Y1248688D03*
X116799D03*
X111941Y1245341D03*
X119846Y1273364D03*
X122646D03*
X141641Y766798D03*
X132941D03*
X141641Y773491D03*
X132941D03*
X141641Y780184D03*
X132941D03*
X141641Y803609D03*
X132941D03*
X141641Y790223D03*
X132941D03*
X141641Y796916D03*
X132941D03*
X141641Y816995D03*
X132941D03*
X141641Y810302D03*
X132941D03*
X141641Y833727D03*
X132941D03*
X141641Y827034D03*
X132941D03*
X141641Y840420D03*
X132941D03*
X141641Y847113D03*
X132941D03*
Y863845D03*
X141641D03*
Y853806D03*
X132941D03*
Y883924D03*
X141641D03*
X132941Y870538D03*
X141641D03*
X132941Y877231D03*
X141641D03*
X132941Y900656D03*
X141641D03*
X132941Y890617D03*
X141641D03*
X132941Y907349D03*
X141641D03*
X132941Y914042D03*
X141641D03*
X132941Y920735D03*
X141641D03*
X132941Y927428D03*
X141641D03*
X132941Y937467D03*
X141641D03*
X132941Y944160D03*
X141641D03*
X132941Y960892D03*
X141641D03*
X132941Y950853D03*
X141641D03*
X132941Y980971D03*
X141641D03*
X132941Y974278D03*
X141641D03*
X132941Y967585D03*
X141641D03*
X132941Y987664D03*
X141641D03*
X132941Y1027822D03*
X141641D03*
X132941Y1017782D03*
X141641D03*
X132941Y1047900D03*
X141641D03*
X132941Y1041207D03*
X141641D03*
X132941Y1034515D03*
X141641D03*
Y1061286D03*
X132941D03*
X141641Y1054593D03*
X132941D03*
X141641Y1074672D03*
X132941D03*
X141641Y1067979D03*
X132941D03*
X141641Y1091404D03*
X132941D03*
X141641Y1084711D03*
X132941D03*
X141641Y1111483D03*
X132941D03*
X141641Y1104790D03*
X132941D03*
X141641Y1098097D03*
X132941D03*
X141641Y1128215D03*
X132941D03*
X141641Y1121522D03*
X132941D03*
X141641Y1141601D03*
X132941D03*
X141641Y1134908D03*
X132941D03*
X141641Y1158333D03*
X132941D03*
X141641Y1148294D03*
X132941D03*
X141641Y1171719D03*
X132941D03*
X141641Y1165026D03*
X132941D03*
X141641Y1185105D03*
X132941D03*
X141641Y1178412D03*
X132941D03*
X141641Y1208530D03*
X132941D03*
X141641Y1201837D03*
X132941D03*
X141641Y1195144D03*
X132941D03*
Y1221916D03*
X141641D03*
X132941Y1215223D03*
X141641D03*
X132941Y1238648D03*
X141641D03*
X132941Y1231955D03*
X141641D03*
X132941Y1245341D03*
X141641D03*
X135846Y1273364D03*
X138646D03*
X146499Y770144D03*
X155199D03*
X146499Y783530D03*
X155199D03*
X146499Y776837D03*
X155199D03*
X146499Y800263D03*
X155199D03*
X146499Y793570D03*
X155199D03*
X146499Y820341D03*
X155199D03*
X146499Y813648D03*
X155199D03*
X146499Y806955D03*
X155199D03*
X146499Y830381D03*
X155199D03*
X146499Y850459D03*
X155199D03*
X146499Y843766D03*
X155199D03*
X146499Y837074D03*
X155199D03*
Y867192D03*
X146499D03*
Y857152D03*
X155199D03*
Y880577D03*
X146499D03*
X155199Y873885D03*
X146499D03*
X155199Y893963D03*
X146499D03*
X155199Y887270D03*
X146499D03*
X155199Y917389D03*
X146499D03*
X155199Y910696D03*
X146499D03*
X155199Y904003D03*
X146499D03*
X155199Y930774D03*
X146499D03*
X155199Y924081D03*
X146499D03*
X155199Y947507D03*
X146499D03*
X155199Y940814D03*
X146499D03*
X155199Y964239D03*
X146499D03*
X155199Y954200D03*
X146499D03*
X155199Y977625D03*
X146499D03*
X155199Y970932D03*
X146499D03*
X155199Y991011D03*
X146499D03*
X155199Y984318D03*
X146499D03*
X155199Y1031168D03*
X146499D03*
X155199Y1024475D03*
X146499D03*
X155199Y1017782D03*
X146499D03*
X155199Y1044554D03*
X146499D03*
X155199Y1037861D03*
X146499D03*
X155199Y1057940D03*
X146499D03*
X155199Y1051247D03*
X146499D03*
X155199Y1078018D03*
X146499D03*
X155199Y1071326D03*
X146499D03*
X155199Y1064633D03*
X146499D03*
X155199Y1094751D03*
X146499D03*
X155199Y1088058D03*
X146499D03*
X155199Y1108137D03*
X146499D03*
X155199Y1101444D03*
X146499D03*
X155199Y1124869D03*
X146499D03*
X155199Y1114829D03*
X146499D03*
X155199Y1144948D03*
X146499D03*
X155199Y1138255D03*
X146499D03*
X155199Y1131562D03*
X146499D03*
X155199Y1161680D03*
X146499D03*
X155199Y1151641D03*
X146499D03*
X155199Y1175066D03*
X146499D03*
X155199Y1168373D03*
X146499D03*
X155199Y1188452D03*
X146499D03*
X155199Y1181759D03*
X146499D03*
X155199Y1205184D03*
X146499D03*
X155199Y1198491D03*
X146499D03*
X155199Y1225263D03*
X146499D03*
X155199Y1218570D03*
X146499D03*
X155199Y1211877D03*
X146499D03*
X155199Y1241995D03*
X146499D03*
X155199Y1235302D03*
X146499D03*
X155135Y1257134D03*
X155199Y1248688D03*
X146499D03*
X149546Y1273364D03*
X152346D03*
X176199Y770144D03*
X162641Y766798D03*
X171341D03*
X176199Y783530D03*
Y776837D03*
X162641Y780184D03*
X171341D03*
Y773491D03*
X162641D03*
X176199Y800263D03*
X162641Y803609D03*
X171341D03*
X176199Y793570D03*
X162641Y796916D03*
X171341D03*
X162641Y790223D03*
X171341D03*
X176199Y820341D03*
X162641Y816995D03*
X171341D03*
X176199Y813648D03*
Y806955D03*
X162641Y810302D03*
X171341D03*
X162641Y833727D03*
X171341D03*
X176199Y830381D03*
X162641Y827034D03*
X171341D03*
X176199Y850459D03*
Y843766D03*
Y837074D03*
X162641Y847113D03*
X171341D03*
X162641Y840420D03*
X171341D03*
X176199Y867192D03*
X171341Y863845D03*
X162641D03*
X176199Y857152D03*
X162641Y853806D03*
X171341D03*
Y883924D03*
X162641D03*
X176199Y880577D03*
Y873885D03*
X171341Y877231D03*
X162641D03*
X171341Y870538D03*
X162641D03*
X171341Y900656D03*
X162641D03*
X176199Y893963D03*
Y887270D03*
X171341Y890617D03*
X162641D03*
X176199Y917389D03*
Y910696D03*
Y904003D03*
X171341Y914042D03*
X162641D03*
X171341Y907349D03*
X162641D03*
X176199Y930774D03*
Y924081D03*
X171341Y927428D03*
X162641D03*
X171341Y920735D03*
X162641D03*
X176199Y947507D03*
Y940814D03*
X171341Y944160D03*
X162641D03*
X171341Y937467D03*
X162641D03*
X176199Y964239D03*
Y954200D03*
X171341Y960892D03*
X162641D03*
X171341Y950853D03*
X162641D03*
X171341Y980971D03*
X162641D03*
X176199Y977625D03*
Y970932D03*
X171341Y974278D03*
X162641D03*
X171341Y967585D03*
X162641D03*
X176199Y991011D03*
Y984318D03*
X171341Y987664D03*
X162641D03*
X176199Y1031168D03*
Y1024475D03*
Y1017782D03*
X171341Y1027822D03*
X162641D03*
X171341Y1017782D03*
X162641D03*
X171341Y1047900D03*
X162641D03*
X176199Y1044554D03*
Y1037861D03*
X171341Y1041207D03*
X162641D03*
X171341Y1034515D03*
X162641D03*
X176199Y1057940D03*
Y1051247D03*
X171341Y1061286D03*
X162641D03*
X171341Y1054593D03*
X162641D03*
X176199Y1078018D03*
Y1071326D03*
Y1064633D03*
X171341Y1074672D03*
X162641D03*
X171341Y1067979D03*
X162641D03*
X176199Y1094751D03*
Y1088058D03*
X171341Y1091404D03*
X162641D03*
X171341Y1084711D03*
X162641D03*
X171341Y1111483D03*
X162641D03*
X176199Y1108137D03*
Y1101444D03*
X171341Y1104790D03*
X162641D03*
X171341Y1098097D03*
X162641D03*
X171341Y1128215D03*
X162641D03*
X176199Y1124869D03*
Y1114829D03*
X171341Y1121522D03*
X162641D03*
X176199Y1144948D03*
Y1138255D03*
Y1131562D03*
X171341Y1141601D03*
X162641D03*
X171341Y1134908D03*
X162641D03*
X176199Y1161680D03*
Y1151641D03*
X171341Y1158333D03*
X162641D03*
X171341Y1148294D03*
X162641D03*
X176199Y1175066D03*
Y1168373D03*
X171341Y1171719D03*
X162641D03*
X171341Y1165026D03*
X162641D03*
X176199Y1188452D03*
Y1181759D03*
X171341Y1185105D03*
X162641D03*
X171341Y1178412D03*
X162641D03*
X176199Y1205184D03*
Y1198491D03*
X171341Y1208530D03*
X162641D03*
X171341Y1201837D03*
X162641D03*
X171341Y1195144D03*
X162641D03*
X176199Y1225263D03*
Y1218570D03*
Y1211877D03*
X162641Y1221916D03*
X171341D03*
Y1215223D03*
X162641D03*
X176199Y1241995D03*
Y1235302D03*
X171341Y1238648D03*
X162641D03*
X171341Y1231955D03*
X162641D03*
X176199Y1248688D03*
X171341Y1245341D03*
X162641D03*
X165546Y1273364D03*
X168346D03*
X192341Y766798D03*
X184899Y770144D03*
X192341Y780184D03*
Y773491D03*
X184899Y783530D03*
Y776837D03*
X192341Y803609D03*
Y796916D03*
Y790223D03*
X184899Y800263D03*
Y793570D03*
X192341Y816995D03*
Y810302D03*
X184899Y820341D03*
Y813648D03*
Y806955D03*
X192341Y833727D03*
X191491Y827034D03*
X184899Y830381D03*
X192341Y847113D03*
Y840420D03*
X184899Y850459D03*
Y843766D03*
Y837074D03*
X191491Y863845D03*
X184899Y867192D03*
X192341Y853806D03*
X184899Y857152D03*
X192341Y883924D03*
Y877231D03*
Y870538D03*
X184899Y880577D03*
Y873885D03*
X192341Y900656D03*
Y890617D03*
X184899Y893963D03*
Y887270D03*
X192341Y914042D03*
Y907349D03*
X184899Y917389D03*
Y910696D03*
Y904003D03*
X191491Y927428D03*
X192341Y920735D03*
X184899Y930774D03*
Y924081D03*
X192341Y937467D03*
Y944160D03*
X184899Y947507D03*
Y940814D03*
X192341Y960892D03*
Y950853D03*
X184899Y964239D03*
Y954200D03*
X192341Y974278D03*
Y980971D03*
Y967585D03*
X184899Y977625D03*
Y970932D03*
X192341Y987664D03*
X184899Y991011D03*
Y984318D03*
X192341Y1027822D03*
Y1017782D03*
X184899Y1031168D03*
Y1024475D03*
Y1017782D03*
X192341Y1047900D03*
Y1041207D03*
Y1034515D03*
X184899Y1044554D03*
Y1037861D03*
X192341Y1054593D03*
Y1061286D03*
X184899Y1057940D03*
Y1051247D03*
X192341Y1074672D03*
Y1067979D03*
X184899Y1078018D03*
Y1071326D03*
Y1064633D03*
X192341Y1091404D03*
X191491Y1084711D03*
X184899Y1094751D03*
Y1088058D03*
X192341Y1111483D03*
Y1104790D03*
Y1098097D03*
X184899Y1108137D03*
Y1101444D03*
X192341Y1128215D03*
Y1121522D03*
X184899Y1124869D03*
Y1114829D03*
X192341Y1141601D03*
Y1134908D03*
X184899Y1144948D03*
Y1138255D03*
Y1131562D03*
X191491Y1158333D03*
X192341Y1148294D03*
X184899Y1161680D03*
Y1151641D03*
X192341Y1171719D03*
Y1165026D03*
X184899Y1175066D03*
Y1168373D03*
X192341Y1185105D03*
Y1178412D03*
X184899Y1188452D03*
Y1181759D03*
X192341Y1208530D03*
Y1201837D03*
Y1195144D03*
X184899Y1205184D03*
Y1198491D03*
X192341Y1221916D03*
Y1215223D03*
X184899Y1225263D03*
Y1218570D03*
Y1211877D03*
X192341Y1238648D03*
X191491Y1231955D03*
X184899Y1241995D03*
Y1235302D03*
X184923Y1258871D03*
X192341Y1245341D03*
X184899Y1248688D03*
X192594Y1271262D03*
X192605Y1268774D03*
X182046Y1273364D03*
X179246D03*
X186697Y1578182D03*
Y1590094D03*
X191997Y1602380D03*
Y1614292D03*
X205899Y770144D03*
X201041Y766798D03*
X205899Y783530D03*
Y776837D03*
X201041Y780184D03*
Y773491D03*
X205899Y800263D03*
Y793570D03*
X201041Y803609D03*
Y796916D03*
Y790223D03*
X205899Y813648D03*
Y806955D03*
X205049Y820341D03*
X201041Y816995D03*
Y810302D03*
X205049Y830381D03*
X201041Y833727D03*
Y827034D03*
X205899Y850459D03*
Y837074D03*
Y843766D03*
X201041Y847113D03*
Y840420D03*
X205049Y867192D03*
X201041Y863845D03*
X205049Y857152D03*
X201041Y853806D03*
X205899Y873885D03*
Y880577D03*
X201041Y883924D03*
Y877231D03*
Y870538D03*
X205899Y893963D03*
Y887270D03*
X201041Y900656D03*
Y890617D03*
X205899Y917389D03*
Y910696D03*
Y904003D03*
X201041Y914042D03*
Y907349D03*
X205049Y930774D03*
Y924081D03*
X201041Y927428D03*
Y920735D03*
X205899Y940814D03*
Y947507D03*
X201041Y937467D03*
Y944160D03*
X205899Y964239D03*
Y954200D03*
X201041Y960892D03*
Y950853D03*
X205899Y970932D03*
Y977625D03*
X201041Y974278D03*
Y980971D03*
Y967585D03*
X205899Y991011D03*
Y984318D03*
X201041Y987664D03*
X205899Y1031168D03*
Y1017782D03*
Y1024475D03*
X201041Y1027822D03*
Y1017782D03*
X205899Y1044554D03*
Y1037861D03*
X201041Y1047900D03*
Y1041207D03*
Y1034515D03*
X205899Y1057940D03*
Y1051247D03*
X201041Y1054593D03*
Y1061286D03*
X205049Y1078018D03*
X205899Y1071326D03*
Y1064633D03*
X201041Y1074672D03*
Y1067979D03*
X205899Y1094751D03*
X205049Y1088058D03*
X201041Y1091404D03*
Y1084711D03*
X205899Y1101444D03*
Y1108137D03*
X201041Y1111483D03*
Y1104790D03*
Y1098097D03*
X205899Y1114829D03*
Y1124869D03*
X201041Y1128215D03*
Y1121522D03*
X205899Y1144948D03*
Y1138255D03*
Y1131562D03*
X201041Y1141601D03*
Y1134908D03*
X205049Y1161680D03*
Y1151641D03*
X201041Y1158333D03*
Y1148294D03*
X205899Y1168373D03*
Y1175066D03*
X201041Y1171719D03*
Y1165026D03*
X205899Y1188452D03*
Y1181759D03*
X201041Y1185105D03*
Y1178412D03*
X205899Y1205184D03*
Y1198491D03*
X201041Y1208530D03*
Y1201837D03*
Y1195144D03*
X205049Y1225263D03*
X205899Y1211877D03*
Y1218570D03*
X201041Y1221916D03*
Y1215223D03*
X205899Y1241995D03*
X205049Y1235302D03*
X201041Y1238648D03*
Y1231955D03*
X205899Y1248688D03*
X201041Y1245341D03*
X206268Y1271348D03*
X206337Y1268720D03*
X194497Y1578182D03*
X206557D03*
X198757D03*
X194497Y1590094D03*
X206557D03*
X198757D03*
X199797Y1614292D03*
Y1602380D03*
X204057Y1614292D03*
Y1602380D03*
X222041Y766798D03*
X214599Y770144D03*
X222041Y780184D03*
Y773491D03*
X214599Y783530D03*
Y776837D03*
X222041Y803609D03*
Y796916D03*
Y790223D03*
X214599Y800263D03*
Y793570D03*
X222041Y810302D03*
X221191Y816995D03*
X214599Y813648D03*
Y806955D03*
X215449Y820341D03*
X222041Y833727D03*
X221191Y827034D03*
X215449Y830381D03*
X222041Y847113D03*
Y840420D03*
X214599Y850459D03*
Y837074D03*
Y843766D03*
X221191Y863845D03*
X215449Y867192D03*
X222041Y853806D03*
X215449Y857152D03*
X222041Y877231D03*
X221191Y870538D03*
X222041Y883924D03*
X214599Y873885D03*
Y880577D03*
X222041Y900656D03*
Y890617D03*
X214599Y893963D03*
Y887270D03*
X222041Y914042D03*
Y907349D03*
X214599Y917389D03*
Y910696D03*
Y904003D03*
X221241Y927428D03*
X222041Y920735D03*
X215449Y930774D03*
Y924081D03*
X222041Y944160D03*
X221191Y937467D03*
X214599Y940814D03*
Y947507D03*
X222041Y960892D03*
Y950853D03*
X214599Y964239D03*
Y954200D03*
X222041Y980971D03*
Y974278D03*
Y967585D03*
X214599Y970932D03*
Y977625D03*
Y991011D03*
Y984318D03*
X222041Y987664D03*
Y1027822D03*
Y1017782D03*
X214599Y1031168D03*
Y1017782D03*
Y1024475D03*
X222041Y1047900D03*
Y1041207D03*
Y1034515D03*
X214599Y1044554D03*
Y1037861D03*
X222041Y1054593D03*
Y1061286D03*
X214599Y1057940D03*
Y1051247D03*
X222041Y1067979D03*
X221191Y1074672D03*
X215449Y1078018D03*
X214599Y1071326D03*
Y1064633D03*
X222041Y1091404D03*
X221191Y1084711D03*
X214599Y1094751D03*
X215449Y1088058D03*
X222041Y1111483D03*
Y1098097D03*
Y1104790D03*
X214599Y1101444D03*
Y1108137D03*
X222041Y1128215D03*
Y1121522D03*
X214599Y1114829D03*
Y1124869D03*
X222041Y1141601D03*
X221191Y1134908D03*
X214599Y1144948D03*
Y1138255D03*
Y1131562D03*
X222041Y1158333D03*
X221191Y1148294D03*
X215449Y1161680D03*
Y1151641D03*
X222041Y1165026D03*
Y1171719D03*
X214599Y1168373D03*
Y1175066D03*
X222041Y1185105D03*
Y1178412D03*
X214599Y1188452D03*
Y1181759D03*
X222041Y1208530D03*
Y1201837D03*
Y1195144D03*
X214599Y1205184D03*
Y1198491D03*
X222041Y1221916D03*
Y1215223D03*
X215449Y1225263D03*
X214599Y1211877D03*
Y1218570D03*
X221191Y1231955D03*
Y1238648D03*
X214599Y1241995D03*
X215449Y1235302D03*
X222041Y1245341D03*
X214824Y1258711D03*
X214599Y1248688D03*
X224987Y1273535D03*
X218617Y1578182D03*
X210817D03*
X222877D03*
X218617Y1590094D03*
X210817D03*
X222877D03*
X211857Y1614292D03*
Y1602380D03*
X223917Y1614292D03*
X216117D03*
X223917Y1602380D03*
X216117D03*
X235599Y770144D03*
X230741Y766798D03*
X235599Y783530D03*
Y776837D03*
X230741Y780184D03*
Y773491D03*
X235599Y800263D03*
Y793570D03*
X230741Y803609D03*
Y796916D03*
Y790223D03*
X234749Y820341D03*
Y813648D03*
X235599Y806955D03*
X230741Y810302D03*
X231006Y817554D03*
X235599Y830381D03*
X230741Y833727D03*
X231591Y827034D03*
X235599Y850459D03*
Y837074D03*
Y843766D03*
X230741Y847113D03*
Y840420D03*
X234749Y867492D03*
X231591Y863845D03*
X234749Y857152D03*
X230741Y853806D03*
X235599Y874185D03*
Y880577D03*
X230741Y877231D03*
X231059Y871084D03*
X230741Y883924D03*
X235599Y893963D03*
Y887270D03*
X230741Y900656D03*
Y890617D03*
X235599Y917389D03*
Y910696D03*
Y904003D03*
X230741Y914042D03*
Y907349D03*
X235599Y930774D03*
Y924081D03*
X231541Y927428D03*
X230741Y920735D03*
X235599Y947507D03*
X234859Y940814D03*
X230741Y944660D03*
X231591Y937467D03*
X235599Y964239D03*
Y954200D03*
X230741Y960892D03*
Y950853D03*
X235599Y977625D03*
Y970932D03*
X230741Y980971D03*
Y974278D03*
Y967585D03*
X235599Y991011D03*
X230741Y987664D03*
X235599Y984318D03*
Y1031168D03*
X230741Y1027822D03*
Y1017782D03*
X235599D03*
Y1024475D03*
Y1044554D03*
Y1037861D03*
X230741Y1047900D03*
Y1041207D03*
Y1034515D03*
X235599Y1051247D03*
Y1057940D03*
X230741Y1054593D03*
Y1061286D03*
X234749Y1078018D03*
X235599Y1071326D03*
Y1064633D03*
X230741Y1067979D03*
X231591Y1074672D03*
X235599Y1094751D03*
X234749Y1088058D03*
X230741Y1091404D03*
Y1084711D03*
X235599Y1108137D03*
Y1101444D03*
X230741Y1111483D03*
Y1098097D03*
Y1104790D03*
X234749Y1124869D03*
X235599Y1114829D03*
X230741Y1128215D03*
Y1121522D03*
X235599Y1144948D03*
Y1138255D03*
X234749Y1131562D03*
X230741Y1141601D03*
X231591Y1134908D03*
X235599Y1151641D03*
Y1161680D03*
X230741Y1158333D03*
X231591Y1148294D03*
X235599Y1175066D03*
Y1168373D03*
X230741Y1165026D03*
Y1171719D03*
X235599Y1188452D03*
Y1181759D03*
X230741Y1185105D03*
Y1178412D03*
X235599Y1205184D03*
Y1198491D03*
X230741Y1208530D03*
Y1201837D03*
Y1195144D03*
X234749Y1225263D03*
X235599Y1218570D03*
Y1211877D03*
X230741Y1221916D03*
Y1215223D03*
X235599Y1241995D03*
X235186Y1234977D03*
X231591Y1231955D03*
Y1238648D03*
X235599Y1248688D03*
X230741Y1245341D03*
X227746Y1273364D03*
X240966Y1273143D03*
X238971Y1274353D03*
X230677Y1578182D03*
X234937D03*
X230677Y1590094D03*
X234937D03*
X228177Y1614292D03*
X235977D03*
X228177Y1602380D03*
X235977D03*
X240237D03*
Y1614292D03*
X233268Y1679920D03*
Y1675383D03*
X241142Y1679320D03*
X233268Y1698627D03*
Y1694093D03*
Y1689556D03*
Y1684454D03*
X241142Y1683857D03*
Y1688391D03*
Y1693493D03*
Y1698030D03*
X233268Y1712800D03*
Y1708266D03*
Y1703729D03*
X241142Y1702564D03*
Y1707666D03*
Y1712203D03*
X233268Y1717903D03*
Y1722440D03*
Y1726974D03*
X241142Y1716737D03*
Y1730911D03*
Y1726377D03*
Y1721840D03*
X251741Y766798D03*
X244299Y770144D03*
X251741Y780184D03*
Y773491D03*
X244299Y783530D03*
Y776837D03*
X251741Y803609D03*
Y796916D03*
Y790223D03*
X244299Y800263D03*
Y793570D03*
X250891Y816995D03*
X251741Y810302D03*
X245149Y820341D03*
Y813648D03*
X244299Y806955D03*
X251741Y833727D03*
X250891Y827034D03*
X244299Y830381D03*
X251741Y847113D03*
Y840420D03*
X244299Y850459D03*
Y837074D03*
Y843766D03*
X250891Y863845D03*
Y853806D03*
X245149Y867192D03*
Y857152D03*
X251741Y870538D03*
Y883924D03*
Y877231D03*
X244299Y873885D03*
Y880577D03*
X250891Y900656D03*
X251741Y890617D03*
X244299Y893963D03*
Y887270D03*
X251741Y914042D03*
Y907349D03*
X244299Y917389D03*
Y910696D03*
Y904003D03*
X250891Y927428D03*
X251741Y920735D03*
X245149Y930774D03*
X244299Y924081D03*
X251741Y944160D03*
X250891Y937467D03*
X244299Y947507D03*
X245149Y940814D03*
X251741Y960892D03*
Y950853D03*
X244299Y964239D03*
Y954200D03*
X251741Y980971D03*
Y974278D03*
Y967585D03*
X244299Y977625D03*
Y970932D03*
X251741Y987664D03*
X244299Y991011D03*
Y984318D03*
Y1031168D03*
X251741Y1027822D03*
Y1017782D03*
X244299D03*
Y1024475D03*
X251741Y1047900D03*
Y1041207D03*
Y1034515D03*
X244299Y1044554D03*
Y1037861D03*
X251741Y1061286D03*
Y1054593D03*
X244299Y1051247D03*
Y1057940D03*
X250891Y1074672D03*
Y1067979D03*
X245149Y1078018D03*
X244299Y1071326D03*
Y1064633D03*
X251741Y1091404D03*
Y1084711D03*
X244299Y1094751D03*
X245149Y1088058D03*
X251741Y1104790D03*
X250891Y1111483D03*
X251741Y1098097D03*
X244299Y1108137D03*
Y1101444D03*
X251741Y1128215D03*
X250891Y1121522D03*
X245149Y1124869D03*
X244299Y1114829D03*
X251741Y1134908D03*
Y1141601D03*
X244299Y1144948D03*
Y1138255D03*
X245149Y1131562D03*
X251741Y1158333D03*
Y1148294D03*
X244299Y1151641D03*
Y1161680D03*
X251741Y1171719D03*
Y1165026D03*
X244299Y1175066D03*
Y1168373D03*
X251741Y1185105D03*
Y1178412D03*
X244299Y1188452D03*
Y1181759D03*
X251741Y1208530D03*
Y1201837D03*
X250891Y1195144D03*
X244299Y1205184D03*
Y1198491D03*
X250891Y1221916D03*
X251741Y1215223D03*
X245149Y1225263D03*
X244299Y1218570D03*
Y1211877D03*
X250891Y1231955D03*
X244299Y1241995D03*
X245149Y1235302D03*
X251741Y1238648D03*
X244299Y1248688D03*
X251741Y1245341D03*
X244789Y1260093D03*
X254897Y1274040D03*
X257197Y1273640D03*
X242737Y1578182D03*
X246997D03*
X254797D03*
X242737Y1590094D03*
X246997D03*
X254797D03*
X248037Y1602380D03*
Y1614292D03*
X252297Y1602380D03*
Y1614292D03*
X249016Y1675383D03*
Y1679920D03*
X256890Y1679320D03*
X249016Y1684454D03*
Y1689556D03*
Y1694093D03*
Y1698627D03*
X256890Y1683857D03*
Y1688391D03*
Y1693493D03*
Y1698030D03*
X249016Y1703729D03*
Y1708266D03*
Y1712800D03*
X256890Y1702564D03*
Y1707666D03*
Y1712203D03*
X249016Y1726974D03*
Y1722440D03*
Y1717903D03*
X256890Y1716737D03*
Y1730911D03*
Y1726377D03*
Y1721840D03*
X260441Y766798D03*
Y780184D03*
Y773491D03*
Y803609D03*
Y796916D03*
Y790223D03*
X261291Y816995D03*
X260441Y810302D03*
Y833727D03*
X261291Y827034D03*
X260441Y847113D03*
Y840420D03*
X261291Y863845D03*
Y853806D03*
X260441Y870538D03*
Y883924D03*
Y877231D03*
Y900656D03*
Y890617D03*
Y914042D03*
Y907349D03*
X261291Y927428D03*
X260441Y920735D03*
Y944160D03*
X261291Y937467D03*
X260441Y960892D03*
Y950853D03*
Y980971D03*
Y974278D03*
Y967585D03*
Y987664D03*
Y1027822D03*
Y1017782D03*
Y1047900D03*
Y1041207D03*
Y1034515D03*
Y1061286D03*
Y1054593D03*
X261291Y1074672D03*
Y1067979D03*
X260441Y1091404D03*
Y1084711D03*
Y1104790D03*
X261291Y1111483D03*
X260441Y1098097D03*
Y1128215D03*
X261291Y1121522D03*
X260441Y1134908D03*
Y1141601D03*
Y1158333D03*
Y1148294D03*
Y1171719D03*
Y1165026D03*
Y1185105D03*
Y1178412D03*
Y1208530D03*
Y1201837D03*
Y1195144D03*
X261291Y1221916D03*
X260441Y1215223D03*
X261291Y1231955D03*
X260441Y1238648D03*
Y1245341D03*
X266857Y1578182D03*
X259057D03*
X271117D03*
X266857Y1590094D03*
X259057D03*
X271117D03*
X260097Y1602380D03*
Y1614292D03*
X272157Y1602380D03*
Y1614292D03*
X264357D03*
Y1602380D03*
X264764Y1675383D03*
Y1679920D03*
X272638Y1679320D03*
X264764Y1684454D03*
Y1689556D03*
Y1694093D03*
Y1698627D03*
X272638Y1683857D03*
Y1688391D03*
Y1693493D03*
Y1698030D03*
X264764Y1703729D03*
Y1708266D03*
Y1712800D03*
X272638Y1702564D03*
Y1707666D03*
Y1712203D03*
X264764Y1726974D03*
Y1722440D03*
Y1717903D03*
X272638Y1716737D03*
Y1730911D03*
Y1726377D03*
Y1721840D03*
X278917Y1578182D03*
X283177D03*
X278917Y1590094D03*
X283177D03*
X284217Y1602380D03*
Y1614292D03*
X276417D03*
Y1602380D03*
X288477Y1614292D03*
Y1602380D03*
X280512Y1675383D03*
Y1679920D03*
Y1684454D03*
Y1689556D03*
Y1694093D03*
Y1698627D03*
Y1703729D03*
Y1708266D03*
Y1712800D03*
Y1726974D03*
Y1722440D03*
Y1717903D03*
X290977Y1578182D03*
X295237D03*
X303037D03*
X290977Y1590094D03*
X295237D03*
X303037D03*
X296277Y1614292D03*
Y1602380D03*
X300537D03*
Y1614292D03*
X300197Y1679920D03*
Y1675383D03*
Y1698627D03*
Y1694093D03*
Y1689556D03*
Y1684454D03*
Y1712800D03*
Y1708266D03*
Y1703729D03*
Y1717903D03*
Y1722440D03*
Y1726974D03*
X315097Y1578182D03*
X307297D03*
X319357D03*
X315097Y1590094D03*
X307297D03*
X319357D03*
X308337Y1602380D03*
Y1614292D03*
X320397D03*
X312597D03*
X320397Y1602380D03*
X312597D03*
X308071Y1679320D03*
X315945Y1679920D03*
Y1675383D03*
X308071Y1683857D03*
Y1698030D03*
Y1693493D03*
Y1688391D03*
X315945Y1698627D03*
Y1694093D03*
Y1689556D03*
Y1684454D03*
X308071Y1702564D03*
Y1712203D03*
Y1707666D03*
X315945Y1712800D03*
Y1708266D03*
Y1703729D03*
X308071Y1716737D03*
Y1721840D03*
Y1726377D03*
Y1730911D03*
X315945Y1717903D03*
Y1722440D03*
Y1726974D03*
X327157Y1578182D03*
X331417D03*
X327157Y1590094D03*
X331417D03*
X324657Y1602380D03*
X332457D03*
X324657Y1614292D03*
X332457D03*
X336717Y1602380D03*
Y1614292D03*
X323819Y1679320D03*
X331693Y1679920D03*
Y1675383D03*
X323819Y1683857D03*
Y1698030D03*
Y1693493D03*
Y1688391D03*
X331693Y1698627D03*
Y1694093D03*
Y1689556D03*
Y1684454D03*
X323819Y1702564D03*
Y1712203D03*
Y1707666D03*
X331693Y1712800D03*
Y1708266D03*
Y1703729D03*
X323819Y1716737D03*
Y1721840D03*
Y1726377D03*
Y1730911D03*
X331693Y1717903D03*
Y1722440D03*
Y1726974D03*
X352579Y854584D03*
X347029Y870606D03*
Y889832D03*
X343707Y1091513D03*
X339217Y1578182D03*
X343477D03*
X351277D03*
X339217Y1590094D03*
X343477D03*
X351277D03*
X344517Y1602380D03*
Y1614292D03*
X348777Y1602380D03*
Y1614292D03*
X339567Y1679320D03*
X347441Y1679920D03*
Y1675383D03*
X355315Y1679320D03*
X339567Y1683857D03*
Y1698030D03*
Y1693493D03*
Y1688391D03*
X347441Y1698627D03*
Y1694093D03*
Y1689556D03*
Y1684454D03*
X355315Y1683857D03*
Y1698030D03*
Y1693493D03*
Y1688391D03*
X339567Y1702564D03*
Y1712203D03*
Y1707666D03*
X347441Y1712800D03*
Y1708266D03*
Y1703729D03*
X355315Y1702564D03*
Y1712203D03*
Y1707666D03*
X339567Y1716737D03*
Y1721840D03*
Y1726377D03*
Y1730911D03*
X347441Y1717903D03*
Y1722440D03*
Y1726974D03*
X355315Y1716737D03*
Y1721840D03*
Y1726377D03*
Y1730911D03*
X359979Y841467D03*
X367379D03*
X365529Y851380D03*
X369229D03*
X359979Y880219D03*
Y899445D03*
X371078D03*
X359979Y918670D03*
X365529Y941100D03*
X359979Y937896D03*
X371078D03*
X369662Y1006093D03*
X365962Y1076587D03*
X363337Y1578088D03*
X355537Y1578182D03*
X367597D03*
X363337Y1590094D03*
X355537D03*
X367597D03*
X356577Y1602380D03*
Y1614292D03*
X368637D03*
X360837D03*
X368637Y1602286D03*
X360837Y1602380D03*
X382179Y841467D03*
X374779D03*
X380329Y851380D03*
X376629D03*
X372929D03*
X384029D03*
X387729D03*
X378478Y931488D03*
X378911Y1060565D03*
X375397Y1578182D03*
Y1590094D03*
X372897Y1602380D03*
X380697D03*
X372897Y1614292D03*
X380697D03*
X389579Y841467D03*
X396978Y899445D03*
Y937896D03*
X415185Y985580D03*
X417575D03*
X415185Y1014540D03*
X417575D03*
X435829Y851380D03*
Y864197D03*
Y877014D03*
Y889832D03*
Y902649D03*
X428429Y921875D03*
X430279Y937897D03*
X433979D03*
X433980Y944305D03*
Y957123D03*
Y950714D03*
Y963531D03*
Y976348D03*
Y969940D03*
Y982757D03*
X434411Y1009298D03*
X434412Y1002889D03*
X434411Y1028524D03*
Y1022115D03*
X434412Y1015706D03*
Y1034932D03*
X434411Y1092608D03*
X450629Y851380D03*
Y877014D03*
X437678Y912262D03*
X441379Y937897D03*
X445079D03*
X437679D03*
X446929Y941101D03*
X446930Y947510D03*
Y960327D03*
Y953918D03*
Y966736D03*
Y979553D03*
Y973144D03*
X447362Y1006094D03*
Y999685D03*
Y1012502D03*
Y1025319D03*
Y1018911D03*
Y1031728D03*
X456178Y912262D03*
X461729Y921875D03*
X462261Y942152D03*
X464561D03*
X466861D03*
X454423Y949139D03*
X454393Y963829D03*
Y966129D03*
X463874Y956540D03*
X466272D03*
X454423Y951439D03*
X466272Y971100D03*
X463874Y971140D03*
X454263Y981209D03*
Y978909D03*
X454463Y995299D03*
Y992999D03*
X466272Y985580D03*
X463874D03*
X466272Y1014540D03*
X463874D03*
X454443Y1009409D03*
Y1007109D03*
X466272Y1000060D03*
X463874D03*
X468895Y1014550D03*
X465862Y1057361D03*
X458462Y1063770D03*
X465862D03*
X456611Y1073383D03*
X454762Y1070178D03*
X467711Y1073383D03*
Y1066974D03*
X474678Y899445D03*
Y912262D03*
X480229Y921875D03*
X471204Y1014540D03*
X475111Y1060565D03*
X484361Y1057361D03*
X475111Y1066974D03*
X473262Y1070178D03*
X478811Y1073383D03*
X484361Y1076587D03*
X482512Y1066974D03*
X478812Y1079791D03*
X475111D03*
X482911Y1578182D03*
X478651D03*
X470851D03*
X482911Y1590094D03*
X478651D03*
X470851D03*
X483951Y1614292D03*
Y1602380D03*
X476151D03*
Y1614292D03*
X489478Y912262D03*
X495462Y1057361D03*
X499162Y1063770D03*
X495462Y1076587D03*
X493612Y1073383D03*
X486211D03*
X497311Y1066974D03*
X495462Y1108630D03*
X493611Y1111834D03*
X494971Y1578182D03*
X490711D03*
X494971Y1590094D03*
X490711D03*
X500271Y1614292D03*
Y1602380D03*
X488211Y1614292D03*
Y1602380D03*
X496011D03*
Y1614292D03*
X497441Y1675383D03*
Y1679920D03*
Y1684454D03*
Y1689556D03*
Y1694093D03*
Y1698627D03*
Y1703729D03*
Y1708266D03*
Y1712800D03*
Y1726974D03*
Y1722440D03*
Y1717903D03*
X507978Y937896D03*
X509829Y947509D03*
X510262Y1057361D03*
X506562Y1063770D03*
X510262Y1076587D03*
X512111Y1073383D03*
X508411Y1066974D03*
X515811D03*
X508411Y1079791D03*
X515811Y1086200D03*
X507031Y1578182D03*
X514831D03*
X502771D03*
X507031Y1590094D03*
X514831D03*
X502771D03*
X512331Y1614292D03*
Y1602380D03*
X508071Y1614292D03*
Y1602380D03*
X513189Y1675383D03*
Y1679920D03*
X505315Y1679320D03*
X513189Y1684454D03*
Y1689556D03*
Y1694093D03*
Y1698627D03*
X505315Y1688391D03*
Y1693493D03*
Y1698030D03*
Y1683857D03*
X513189Y1703729D03*
Y1708266D03*
Y1712800D03*
X505315Y1707666D03*
Y1712203D03*
Y1702564D03*
X513189Y1726974D03*
Y1722440D03*
Y1717903D03*
X505315Y1730911D03*
Y1726377D03*
Y1721840D03*
Y1716737D03*
X521362Y1057361D03*
X525061Y1063770D03*
X532462D03*
X521362Y1076587D03*
X519512Y1073383D03*
X523211Y1066974D03*
X534311D03*
X531151Y1578182D03*
X519091D03*
X526891D03*
X531151Y1590094D03*
X519091D03*
X526891D03*
X532191Y1614292D03*
Y1602380D03*
X524391Y1614292D03*
Y1602380D03*
X520131D03*
Y1614292D03*
X528937Y1675383D03*
Y1679920D03*
X521063Y1679320D03*
X528937Y1684454D03*
Y1689556D03*
Y1694093D03*
Y1698627D03*
X521063Y1688391D03*
Y1693493D03*
Y1698030D03*
Y1683857D03*
X528937Y1703729D03*
Y1708266D03*
Y1712800D03*
X521063Y1707666D03*
Y1712203D03*
Y1702564D03*
X528937Y1726974D03*
Y1722440D03*
Y1717903D03*
X521063Y1730911D03*
Y1726377D03*
Y1721840D03*
Y1716737D03*
X543129Y928283D03*
X539429D03*
X537578Y925079D03*
X535729Y928283D03*
X548678Y925079D03*
X537578Y944304D03*
X548678D03*
X536161Y1057361D03*
X549422Y1064850D03*
X541711Y1073383D03*
X545411Y1066974D03*
X536161Y1076587D03*
X536162Y1070178D03*
X538011Y1073383D03*
X547262Y1070178D03*
X543211Y1578182D03*
X538951D03*
X543211Y1590094D03*
X538951D03*
X548511Y1614292D03*
Y1602380D03*
X536451D03*
Y1614292D03*
X544251Y1602380D03*
Y1614292D03*
X544685Y1675383D03*
Y1679920D03*
X536811Y1679320D03*
X544685Y1684454D03*
Y1689556D03*
Y1694093D03*
Y1698627D03*
X536811Y1688391D03*
Y1693493D03*
Y1698030D03*
Y1683857D03*
X544685Y1703729D03*
Y1708266D03*
Y1712800D03*
X536811Y1707666D03*
Y1712203D03*
Y1702564D03*
X544685Y1726974D03*
Y1722440D03*
Y1717903D03*
X536811Y1730911D03*
Y1726377D03*
Y1721840D03*
Y1716737D03*
X555271Y1578182D03*
X563071D03*
X551011D03*
X555271Y1590094D03*
X563071D03*
X551011D03*
X560571Y1602380D03*
X556311Y1614292D03*
Y1602380D03*
X552559Y1679320D03*
X564370Y1675383D03*
Y1679920D03*
X552559Y1688391D03*
Y1693493D03*
Y1698030D03*
Y1683857D03*
X564370Y1684454D03*
Y1689556D03*
Y1694093D03*
Y1698627D03*
X552559Y1707666D03*
Y1712203D03*
Y1702564D03*
X564370Y1703729D03*
Y1708266D03*
Y1712800D03*
X552559Y1730911D03*
Y1726377D03*
Y1721840D03*
Y1716737D03*
X564370Y1726974D03*
Y1722440D03*
Y1717903D03*
X579391Y1578182D03*
X567331D03*
X575131D03*
X579391Y1590094D03*
X567331D03*
X575131D03*
X580431Y1614292D03*
X572631D03*
Y1602380D03*
X568371D03*
Y1614292D03*
X580118Y1675383D03*
Y1679920D03*
X572244Y1679320D03*
X580118Y1684454D03*
Y1689556D03*
Y1694093D03*
Y1698627D03*
X572244Y1688391D03*
Y1693493D03*
Y1698030D03*
Y1683857D03*
X580118Y1703729D03*
Y1708266D03*
Y1712800D03*
X572244Y1707666D03*
Y1712203D03*
Y1702564D03*
X580118Y1726974D03*
Y1722440D03*
Y1717903D03*
X572244Y1730911D03*
Y1726377D03*
Y1721840D03*
Y1716737D03*
X599251Y1578182D03*
X591451D03*
X587191D03*
X599251Y1590094D03*
X591451D03*
X587191D03*
X596751Y1614292D03*
Y1602380D03*
X584691D03*
Y1614292D03*
X592491Y1602380D03*
Y1614292D03*
X595866Y1675383D03*
Y1679920D03*
X587992Y1679320D03*
X595866Y1684454D03*
Y1689556D03*
Y1694093D03*
Y1698627D03*
X587992Y1688391D03*
Y1693493D03*
Y1698030D03*
Y1683857D03*
X595866Y1703729D03*
Y1708266D03*
Y1712800D03*
X587992Y1707666D03*
Y1712203D03*
Y1702564D03*
X595866Y1726974D03*
Y1722440D03*
Y1717903D03*
X587992Y1730911D03*
Y1726377D03*
Y1721840D03*
Y1716737D03*
X615571Y1578182D03*
X603511D03*
X611311D03*
X615571Y1590094D03*
X603511D03*
X611311D03*
X608811Y1602380D03*
Y1614292D03*
X604551Y1602380D03*
Y1614292D03*
X611614Y1675383D03*
Y1679920D03*
X603740Y1679320D03*
X611614Y1684454D03*
Y1689556D03*
Y1694093D03*
Y1698627D03*
X603740Y1688391D03*
Y1693493D03*
Y1698030D03*
Y1683857D03*
X611614Y1703729D03*
Y1708266D03*
Y1712800D03*
X603740Y1707666D03*
Y1712203D03*
Y1702564D03*
X611614Y1726974D03*
Y1722440D03*
Y1717903D03*
X603740Y1730911D03*
Y1726377D03*
Y1721840D03*
Y1716737D03*
X629599Y770144D03*
X620899D03*
X629599Y783530D03*
X620899D03*
X629599Y776837D03*
X620899D03*
X620846Y800263D03*
X629599D03*
Y793570D03*
X620899D03*
Y820341D03*
X629599D03*
X620076Y813648D03*
X630593D03*
X619632Y806955D03*
X630792D03*
X620899Y830381D03*
X629599D03*
X620005Y850459D03*
X630754D03*
X620899Y843766D03*
X629599D03*
Y837074D03*
X620899D03*
Y867192D03*
X629599D03*
X620058Y857152D03*
X630481D03*
X620899Y880577D03*
X629599D03*
X620899Y873885D03*
X629599D03*
X630756Y893963D03*
X620899D03*
X629599Y887270D03*
X620899D03*
Y910696D03*
X629599D03*
Y917389D03*
X620899D03*
X629599Y904003D03*
X620899D03*
X630399Y930697D03*
X619905Y930774D03*
X620899Y924081D03*
X629599D03*
Y947507D03*
X620899D03*
X619964Y940814D03*
X630777D03*
X629599Y964239D03*
X620899D03*
X629599Y954200D03*
X620899D03*
Y977625D03*
X629599D03*
Y970932D03*
X620899D03*
Y991011D03*
X629599D03*
Y984318D03*
X620899D03*
Y1031168D03*
X629599D03*
X620899Y1017782D03*
X629599D03*
X620899Y1024475D03*
X629599D03*
X620899Y1044554D03*
X629599D03*
X620899Y1037861D03*
X629599D03*
X620899Y1057940D03*
X629599D03*
Y1051247D03*
X620899D03*
Y1078018D03*
X629599D03*
X630399Y1071326D03*
X619999D03*
X620899Y1064633D03*
X629599D03*
X620899Y1088058D03*
X629599D03*
Y1094751D03*
X620899D03*
Y1108137D03*
X629599D03*
Y1101444D03*
X620899D03*
X630363Y1124674D03*
X620369Y1124969D03*
X630399Y1114829D03*
X620099D03*
X620899Y1131562D03*
X629599D03*
Y1144948D03*
X620899D03*
X629599Y1138255D03*
X620899D03*
X620511Y1161680D03*
X629833Y1161581D03*
X629599Y1151641D03*
X620899D03*
X629599Y1175066D03*
X620899D03*
X629599Y1168373D03*
X620899D03*
X630623Y1188452D03*
X620899D03*
X629599Y1181759D03*
X620899D03*
X629599Y1205184D03*
X620899D03*
Y1198491D03*
X629599D03*
X620899Y1225263D03*
X629599D03*
Y1218570D03*
X620899D03*
X629599Y1211877D03*
X620899D03*
X629599Y1241995D03*
X620899D03*
X630922Y1235302D03*
X620036D03*
X620899Y1248688D03*
X629599D03*
X625246Y1273164D03*
X627646D03*
X627631Y1578182D03*
X623371D03*
X627631Y1590094D03*
X623371D03*
X628671Y1602380D03*
Y1614292D03*
X620871D03*
Y1602380D03*
X616611Y1614292D03*
Y1602380D03*
X619488Y1679320D03*
Y1688391D03*
Y1693493D03*
Y1698030D03*
Y1683857D03*
Y1707666D03*
Y1712203D03*
Y1702564D03*
Y1730911D03*
Y1726377D03*
Y1721840D03*
Y1716737D03*
X637041Y766798D03*
X645741D03*
Y773491D03*
X637041D03*
X645741Y780184D03*
X637041D03*
Y803609D03*
X645741D03*
X637041Y796916D03*
X645741D03*
Y790223D03*
X637041D03*
X636221Y810302D03*
X646844D03*
X646774Y816995D03*
X637041D03*
X645741Y833727D03*
X637041D03*
Y827034D03*
X645741D03*
X637041Y847113D03*
X645801D03*
X637041Y840420D03*
X645741D03*
X646819Y853806D03*
X636332Y853955D03*
X645918Y863845D03*
X636266D03*
X637041Y877231D03*
X645741D03*
X637041Y870538D03*
X645741D03*
Y883924D03*
X637041D03*
Y900656D03*
X645741D03*
X637041Y890617D03*
X645741D03*
X637041Y914042D03*
X645741D03*
Y907349D03*
X637041D03*
X646393Y927526D03*
X636026Y927428D03*
X645741Y920735D03*
X637041D03*
X645741Y944160D03*
X637041D03*
X636170Y937467D03*
X646703D03*
X645741Y960892D03*
X637041D03*
Y950853D03*
X645741D03*
X637041Y980971D03*
X645741D03*
X637041Y974278D03*
X645741D03*
X637041Y967585D03*
X645741D03*
X637041Y987664D03*
X645741D03*
X637041Y1027822D03*
X645741D03*
Y1017782D03*
X637041D03*
X645741Y1047900D03*
X637041D03*
Y1041207D03*
X645741D03*
X637041Y1034515D03*
X645741D03*
X637041Y1061286D03*
X645741D03*
Y1054593D03*
X637041D03*
X636141Y1074672D03*
X646541D03*
X645741Y1067979D03*
X636841D03*
X637041Y1091404D03*
X645741D03*
Y1084711D03*
X636241D03*
X645741Y1111483D03*
X637041D03*
X645741Y1098097D03*
X637041D03*
X645741Y1104790D03*
X637041D03*
Y1121522D03*
X645741D03*
X637041Y1128915D03*
X645741Y1128215D03*
X646584Y1135108D03*
X635744Y1134908D03*
X645741Y1141601D03*
X637041D03*
X645741Y1148294D03*
X637041D03*
X645741Y1158333D03*
X637041D03*
Y1171719D03*
X645741D03*
Y1165026D03*
X637041D03*
Y1185105D03*
X645741D03*
Y1178412D03*
X637041D03*
X645741Y1208530D03*
X637041D03*
X645741Y1201837D03*
X637041D03*
Y1195144D03*
X645741D03*
X636005Y1221916D03*
X646570D03*
X645741Y1215223D03*
X637041D03*
X645741Y1238648D03*
X637041D03*
X635995Y1231862D03*
X646539Y1231955D03*
X645741Y1245341D03*
X637041D03*
X634213Y1258679D03*
X642746Y1273364D03*
X639946D03*
X647491Y1578088D03*
X639691Y1578182D03*
X635431D03*
X647491Y1590094D03*
X639691D03*
X635431D03*
X644991Y1614292D03*
Y1602380D03*
X632931D03*
Y1614292D03*
X640731D03*
Y1602380D03*
X650599Y770144D03*
X659299D03*
X650599Y783530D03*
X659299D03*
X650599Y776837D03*
X659299D03*
Y800263D03*
X650599D03*
Y793570D03*
X659299D03*
Y806955D03*
X650599D03*
X660432Y813648D03*
X650599D03*
X660199Y820341D03*
X650599D03*
X659299Y830381D03*
X650599D03*
X659299Y850459D03*
X650599D03*
X659299Y843766D03*
X650599D03*
Y837074D03*
X659299D03*
Y857152D03*
X650599D03*
X649563Y867192D03*
X660299D03*
X659299Y873885D03*
X650599D03*
Y880577D03*
X659299D03*
X650599Y893963D03*
X659299D03*
X650599Y887270D03*
X659299D03*
Y917389D03*
X650599D03*
X659299Y910696D03*
X650599D03*
Y904003D03*
X659299D03*
X660504Y924081D03*
X650599D03*
X660174Y930774D03*
X649661D03*
X659299Y947507D03*
X650599D03*
X659299Y940814D03*
X650599D03*
X659299Y964239D03*
X650599D03*
Y954200D03*
X659299D03*
Y977625D03*
X650599D03*
X659299Y970932D03*
X650599D03*
X659299Y991011D03*
X650599D03*
X659299Y984318D03*
X650599D03*
X659299Y1031168D03*
X650599D03*
X659299Y1017782D03*
X650599D03*
X659299Y1024475D03*
X650599D03*
X659299Y1044554D03*
X650599D03*
X659299Y1037861D03*
X650599D03*
X659299Y1051247D03*
X650599D03*
Y1057940D03*
X659299D03*
X660099Y1078018D03*
X649799D03*
X659299Y1071326D03*
X650599D03*
X659299Y1064633D03*
X650599D03*
X659299Y1094751D03*
X650599D03*
X660099Y1088058D03*
X649799D03*
X650599Y1108137D03*
X659299D03*
X650599Y1101444D03*
X659299D03*
X660199Y1124869D03*
X649932Y1124640D03*
X659299Y1114829D03*
X650599D03*
X659299Y1130762D03*
X650599D03*
X659299Y1138255D03*
X650599D03*
X659299Y1144948D03*
X650599D03*
X659299Y1151641D03*
X650599D03*
Y1161680D03*
X659299D03*
X650599Y1175066D03*
X659299D03*
X650599Y1168373D03*
X659299D03*
X650599Y1188452D03*
X659299D03*
X650599Y1181759D03*
X659299D03*
X650599Y1205184D03*
X659299D03*
X650599Y1198491D03*
X659299D03*
X660070Y1225263D03*
X649913D03*
X659299Y1218570D03*
X650599D03*
X659299Y1211877D03*
X650599D03*
X659299Y1241995D03*
X650599D03*
X660234Y1235302D03*
X649701D03*
X650599Y1248688D03*
X659299D03*
X659546Y1257664D03*
X656446Y1273364D03*
X653646D03*
X651751Y1578182D03*
X659551D03*
X651751Y1590094D03*
X659551D03*
X657051Y1602380D03*
Y1614292D03*
X652791Y1602286D03*
Y1614292D03*
X680299Y770144D03*
X675441Y766798D03*
X666741D03*
X680299Y783530D03*
Y776837D03*
X666741Y773491D03*
X675441D03*
X666741Y780184D03*
X675441D03*
Y803609D03*
X666741D03*
X680299Y800263D03*
Y793570D03*
X666741Y796916D03*
X675441D03*
X666741Y790223D03*
X675441D03*
X676403Y816995D03*
X665803D03*
X675441Y810302D03*
X666741D03*
X680299Y820341D03*
Y813648D03*
Y806955D03*
X675441Y833727D03*
X666741D03*
X676625Y827034D03*
X665876D03*
X680299Y830381D03*
X675441Y847113D03*
X666741D03*
X680299Y850459D03*
Y843766D03*
Y837074D03*
X666741Y840420D03*
X675441D03*
X676417Y853806D03*
X665890D03*
X680299Y867192D03*
Y857152D03*
X665916Y863845D03*
X676600D03*
X675441Y877231D03*
X666741D03*
X675441Y870538D03*
X666741D03*
Y883924D03*
X675441D03*
X680299Y880577D03*
Y873885D03*
X666741Y900656D03*
X675441D03*
X680299Y893963D03*
Y887270D03*
X666741Y890617D03*
X675441D03*
Y914042D03*
X666741D03*
X680299Y917389D03*
Y910696D03*
Y904003D03*
X666741Y907349D03*
X675441D03*
X676488Y927428D03*
X665896D03*
X675441Y920735D03*
X666741D03*
X680299Y930774D03*
Y924081D03*
X675441Y944160D03*
X666741D03*
X676359Y937467D03*
X665923D03*
X680299Y947507D03*
Y940814D03*
Y964239D03*
X675441Y960892D03*
X666741D03*
X680299Y954200D03*
X666741Y950853D03*
X675441D03*
Y980971D03*
X666741D03*
X680299Y970932D03*
X675441Y974278D03*
X666741D03*
X675441Y967585D03*
X666741D03*
X680299Y977625D03*
X675441Y987664D03*
X666741D03*
X680299Y991011D03*
Y984318D03*
Y1031168D03*
Y1024475D03*
X675441Y1027822D03*
X666741D03*
X675441Y1017782D03*
X666741D03*
X680299D03*
X675441Y1047900D03*
X666741D03*
X680299Y1037861D03*
X675441Y1041207D03*
X666741D03*
X675441Y1034515D03*
X666741D03*
X680299Y1044554D03*
Y1057940D03*
Y1051247D03*
X675441Y1054593D03*
X666741D03*
Y1061286D03*
X675441D03*
X676341Y1074672D03*
X665841D03*
X675441Y1067979D03*
X666741D03*
X680299Y1078018D03*
Y1071326D03*
Y1064633D03*
X675441Y1091404D03*
X666741D03*
X676241Y1084711D03*
X665941D03*
X680299Y1094751D03*
Y1088058D03*
X666741Y1111483D03*
X675441D03*
X680299Y1108137D03*
Y1101444D03*
X666741Y1104790D03*
X675441D03*
X666741Y1098097D03*
X675441D03*
X666741Y1128215D03*
X675441D03*
X680299Y1124869D03*
Y1114829D03*
X666741Y1121522D03*
X675441D03*
X680299Y1144948D03*
Y1138255D03*
Y1131562D03*
X666741Y1141601D03*
X675441D03*
X666741Y1134908D03*
X675441D03*
X676652Y1148294D03*
X665602D03*
X676241Y1158333D03*
X665941D03*
X680299Y1161680D03*
Y1151641D03*
X675441Y1165026D03*
X666741D03*
X680299Y1175066D03*
Y1168373D03*
X666741Y1171719D03*
X675441D03*
X680299Y1188452D03*
Y1181759D03*
X666741Y1185105D03*
X675441D03*
X666741Y1178412D03*
X675441D03*
X680299Y1205184D03*
Y1198491D03*
X666741Y1208530D03*
X675441D03*
X666741Y1201837D03*
X675441D03*
X666741Y1195144D03*
X675441D03*
X680299Y1218570D03*
Y1225263D03*
X676448Y1221916D03*
X665651D03*
X675441Y1215223D03*
X666741D03*
X680299Y1211877D03*
X675441Y1238648D03*
X666741D03*
X676462Y1231955D03*
X665912D03*
X680299Y1241995D03*
Y1235302D03*
X675441Y1245341D03*
X666741D03*
X676046Y1257964D03*
X680299Y1248688D03*
X672446Y1273364D03*
X669646D03*
X664851Y1602380D03*
Y1614292D03*
X696441Y766798D03*
X688999Y770144D03*
X696441Y773491D03*
Y780184D03*
X688999Y783530D03*
Y776837D03*
X696441Y803609D03*
Y796916D03*
Y790223D03*
X688999Y800263D03*
Y793570D03*
X696441Y816995D03*
Y810302D03*
X689888Y820341D03*
X688999Y813648D03*
Y806955D03*
X696441Y833727D03*
Y827034D03*
X688999Y830381D03*
X696441Y847113D03*
X688999Y850459D03*
X696441Y840420D03*
X688999Y843766D03*
Y837074D03*
X696441Y863845D03*
Y853806D03*
X688999Y867192D03*
X689896Y857152D03*
X696441Y883924D03*
Y877231D03*
Y870538D03*
X688999Y880577D03*
Y873885D03*
X696441Y900656D03*
Y890617D03*
X688999Y893963D03*
Y887270D03*
X696441Y914042D03*
Y907349D03*
X688999Y917389D03*
Y910696D03*
Y904003D03*
X696441Y927428D03*
Y920735D03*
X690104Y930774D03*
X688999Y924081D03*
X696441Y944160D03*
Y937467D03*
X688999Y947507D03*
Y940814D03*
X696441Y960892D03*
Y950853D03*
X688999Y964239D03*
Y954200D03*
X696441Y980971D03*
Y974278D03*
Y967585D03*
X688999Y970932D03*
Y977625D03*
X696441Y987664D03*
X688999Y991011D03*
Y984318D03*
X696441Y1027822D03*
Y1017782D03*
X688999Y1031168D03*
Y1024475D03*
Y1017782D03*
X696441Y1047900D03*
Y1041207D03*
Y1034515D03*
X688999Y1037861D03*
Y1044554D03*
X696441Y1054593D03*
Y1061286D03*
X688999Y1057940D03*
X696441Y1074672D03*
Y1067979D03*
X688999Y1077118D03*
Y1071326D03*
Y1064633D03*
X696441Y1091404D03*
Y1084711D03*
X688999Y1094751D03*
Y1088058D03*
X696441Y1111483D03*
Y1104790D03*
Y1098097D03*
X688999Y1108137D03*
Y1101444D03*
X696441Y1128215D03*
Y1121522D03*
X688999Y1124869D03*
Y1114829D03*
X696441Y1141601D03*
Y1134908D03*
X688999Y1144948D03*
Y1138255D03*
Y1131562D03*
X696441Y1158333D03*
Y1148294D03*
X688999Y1161680D03*
X689999Y1151641D03*
X696441Y1171719D03*
Y1165026D03*
X688999Y1175066D03*
Y1168373D03*
X696441Y1185105D03*
Y1178412D03*
X688999Y1188452D03*
Y1181759D03*
X696441Y1208530D03*
Y1201837D03*
Y1195144D03*
X688999Y1205184D03*
Y1198491D03*
X696441Y1221916D03*
Y1215223D03*
X688999Y1218570D03*
X689799Y1225263D03*
X688999Y1211877D03*
X696441Y1238648D03*
Y1231955D03*
X688999Y1241995D03*
Y1235302D03*
X688916Y1256964D03*
X696441Y1245341D03*
X688999Y1248688D03*
X686146Y1273364D03*
X683346D03*
X709999Y770144D03*
X705141Y766798D03*
X709999Y783530D03*
Y776837D03*
X705141Y773491D03*
Y780184D03*
X709999Y800263D03*
Y793570D03*
X705141Y803609D03*
Y796916D03*
Y790223D03*
X709999Y820341D03*
Y813648D03*
Y806955D03*
X705141Y816995D03*
Y810302D03*
X709999Y830381D03*
X705141Y833727D03*
Y827034D03*
Y847113D03*
X709999Y850459D03*
Y843766D03*
Y837074D03*
X705141Y840420D03*
Y863845D03*
Y853806D03*
X709999Y867192D03*
Y857152D03*
X705141Y883924D03*
Y877231D03*
Y870538D03*
X709999Y880577D03*
Y873885D03*
X705141Y900656D03*
Y890617D03*
X709999Y893963D03*
Y887270D03*
X705141Y914042D03*
Y907349D03*
X709999Y917389D03*
Y910696D03*
Y904003D03*
X705141Y927428D03*
Y920735D03*
X709999Y930774D03*
Y924081D03*
X705141Y944160D03*
Y937467D03*
X709999Y947507D03*
Y940814D03*
X705141Y960892D03*
Y950853D03*
X709999Y964239D03*
Y954200D03*
X705141Y980971D03*
Y974278D03*
Y967585D03*
X709999Y977625D03*
Y970932D03*
X705141Y987664D03*
X709999Y991011D03*
Y984318D03*
X705141Y1027822D03*
Y1017782D03*
X709999Y1031168D03*
Y1024475D03*
Y1017782D03*
X705141Y1047900D03*
Y1041207D03*
Y1034515D03*
X709999Y1044554D03*
Y1037861D03*
X705141Y1054593D03*
Y1061286D03*
X709999Y1057940D03*
Y1051247D03*
X705141Y1074672D03*
Y1067979D03*
X709999Y1078018D03*
Y1071326D03*
Y1064633D03*
X705141Y1091404D03*
Y1084711D03*
X709999Y1094751D03*
Y1088058D03*
X705141Y1111483D03*
Y1104790D03*
Y1098097D03*
X709999Y1108137D03*
Y1101444D03*
X705141Y1128215D03*
Y1121522D03*
X709999Y1124869D03*
Y1114829D03*
X705141Y1141601D03*
Y1134908D03*
X709999Y1144948D03*
Y1138255D03*
Y1131562D03*
X705141Y1158333D03*
Y1148294D03*
X709999Y1161680D03*
Y1151641D03*
X705141Y1171719D03*
Y1165026D03*
X709999Y1175066D03*
Y1168373D03*
X705141Y1185105D03*
Y1178412D03*
X709999Y1188452D03*
Y1181759D03*
X705141Y1208530D03*
Y1201837D03*
Y1195144D03*
X709999Y1205184D03*
Y1198491D03*
X705141Y1221916D03*
Y1215223D03*
X709999Y1225263D03*
Y1218570D03*
Y1211877D03*
X705141Y1238648D03*
Y1231955D03*
X709999Y1241995D03*
Y1235302D03*
X705141Y1245341D03*
X709999Y1248688D03*
X713046Y1273364D03*
X702146D03*
X699346D03*
X726141Y766798D03*
X718699Y770144D03*
X726141Y773491D03*
Y780184D03*
X718699Y783530D03*
Y776837D03*
X726141Y803609D03*
Y796916D03*
Y790223D03*
X718699Y800263D03*
Y793570D03*
X726141Y816995D03*
Y810302D03*
X718699Y820341D03*
Y813648D03*
Y806955D03*
X726141Y833727D03*
Y827034D03*
X718699Y830381D03*
X726141Y847113D03*
Y840420D03*
X718699Y850459D03*
Y843766D03*
Y837074D03*
X726141Y863845D03*
Y853806D03*
X718699Y867192D03*
Y857152D03*
X726141Y883924D03*
Y877231D03*
Y870538D03*
X718699Y880577D03*
Y873885D03*
X726141Y900656D03*
Y890617D03*
X718699Y893963D03*
Y887270D03*
X726141Y914042D03*
Y907349D03*
X718699Y917389D03*
Y910696D03*
Y904003D03*
X726141Y927428D03*
Y920735D03*
X718699Y930774D03*
Y924081D03*
X726141Y944160D03*
Y937467D03*
X718699Y947507D03*
Y940814D03*
X726141Y960892D03*
Y950853D03*
X718699Y964239D03*
Y954200D03*
X726141Y980971D03*
Y974278D03*
Y967585D03*
X718699Y977625D03*
Y970932D03*
X726141Y987664D03*
X718699Y991011D03*
Y984318D03*
X726141Y1027822D03*
Y1017782D03*
X718699Y1031168D03*
Y1024475D03*
Y1017782D03*
X726141Y1047900D03*
Y1041207D03*
Y1034515D03*
X718699Y1044554D03*
Y1037861D03*
X726141Y1061286D03*
Y1054593D03*
X718699Y1057940D03*
Y1051247D03*
X726141Y1074672D03*
Y1067979D03*
X718699Y1078018D03*
Y1071326D03*
Y1064633D03*
X726141Y1091404D03*
Y1084711D03*
X718699Y1094751D03*
Y1088058D03*
X726141Y1111483D03*
Y1104790D03*
Y1098097D03*
X718699Y1108137D03*
Y1101444D03*
X726141Y1128215D03*
Y1121522D03*
X718699Y1124869D03*
Y1114829D03*
X726141Y1141601D03*
Y1134908D03*
X718699Y1144948D03*
Y1138255D03*
Y1131562D03*
X726141Y1158333D03*
Y1148294D03*
X718699Y1161680D03*
Y1151641D03*
X726141Y1171719D03*
Y1165026D03*
X718699Y1175066D03*
Y1168373D03*
X726141Y1185105D03*
Y1178412D03*
X718699Y1188452D03*
Y1181759D03*
X726141Y1208530D03*
Y1201837D03*
Y1195144D03*
X718699Y1205184D03*
Y1198491D03*
X726141Y1221916D03*
Y1215223D03*
X718699Y1225263D03*
Y1218570D03*
Y1211877D03*
X726141Y1238648D03*
Y1231955D03*
X718699Y1241995D03*
Y1235302D03*
X726141Y1245341D03*
X719046Y1257064D03*
X718699Y1248688D03*
X729046Y1273364D03*
X715846D03*
X739699Y770144D03*
X734841Y766798D03*
X739699Y783530D03*
Y776837D03*
X734841Y773491D03*
Y780184D03*
X739699Y800263D03*
Y793570D03*
X734841Y803609D03*
Y796916D03*
Y790223D03*
X739699Y820341D03*
Y813648D03*
Y806955D03*
X734841Y816995D03*
Y810302D03*
X739699Y830381D03*
X734841Y833727D03*
Y827034D03*
X739699Y850459D03*
Y843766D03*
Y837074D03*
X734841Y847113D03*
Y840420D03*
X739699Y867192D03*
Y857152D03*
X734841Y863845D03*
Y853806D03*
X739699Y880577D03*
Y873885D03*
X734841Y883924D03*
Y877231D03*
Y870538D03*
X739699Y893963D03*
Y887270D03*
X734841Y900656D03*
Y890617D03*
X739699Y917389D03*
Y910696D03*
Y904003D03*
X734841Y914042D03*
Y907349D03*
X739699Y930774D03*
Y924081D03*
X734841Y927428D03*
Y920735D03*
X739699Y947507D03*
Y940814D03*
X734841Y944160D03*
Y937467D03*
X739699Y964239D03*
Y954200D03*
X734841Y960892D03*
Y950853D03*
X739699Y977625D03*
Y970932D03*
X734841Y980971D03*
Y974278D03*
Y967585D03*
X739699Y991011D03*
Y984318D03*
X734841Y987664D03*
X739699Y1031168D03*
Y1024475D03*
Y1017782D03*
X734841Y1027822D03*
Y1017782D03*
X739699Y1044554D03*
Y1037861D03*
X734841Y1047900D03*
Y1041207D03*
Y1034515D03*
X739699Y1057940D03*
Y1051247D03*
X734841Y1061286D03*
Y1054593D03*
X739699Y1078018D03*
Y1071326D03*
Y1064633D03*
X734841Y1074672D03*
Y1067979D03*
X739699Y1094751D03*
Y1088058D03*
X734841Y1091404D03*
Y1084711D03*
X739699Y1108137D03*
Y1101444D03*
X734841Y1111483D03*
Y1104790D03*
Y1098097D03*
X739699Y1124869D03*
Y1114829D03*
X734841Y1128215D03*
Y1121522D03*
X739699Y1144948D03*
Y1138255D03*
Y1131562D03*
X734841Y1141601D03*
Y1134908D03*
X739699Y1161680D03*
Y1151641D03*
X734841Y1158333D03*
Y1148294D03*
X739699Y1175066D03*
Y1168373D03*
X734841Y1171719D03*
Y1165026D03*
X739699Y1188452D03*
Y1181759D03*
X734841Y1185105D03*
Y1178412D03*
X739699Y1205184D03*
Y1198491D03*
X734841Y1208530D03*
Y1201837D03*
Y1195144D03*
X739699Y1225263D03*
Y1218570D03*
Y1211877D03*
X734841Y1221916D03*
Y1215223D03*
X739699Y1241995D03*
Y1235302D03*
X734841Y1238648D03*
Y1231955D03*
X739699Y1248688D03*
X734841Y1245341D03*
X745546Y1273364D03*
X742746D03*
X731372Y1273464D03*
X755841Y766798D03*
X748399Y770144D03*
X755841Y780184D03*
Y773491D03*
X748399Y783530D03*
Y776837D03*
X755841Y803609D03*
Y796916D03*
Y790223D03*
X748399Y800263D03*
Y793570D03*
X755841Y816995D03*
Y810302D03*
X748399Y820341D03*
Y813648D03*
Y806955D03*
X755841Y833727D03*
Y827034D03*
X748399Y830381D03*
X755841Y847113D03*
Y840420D03*
X748399Y850459D03*
Y843766D03*
Y837074D03*
X755841Y863845D03*
Y853806D03*
X748399Y867192D03*
Y857152D03*
X755841Y883924D03*
Y877231D03*
Y870538D03*
X748399Y880577D03*
Y873885D03*
X755841Y900656D03*
Y890617D03*
X748399Y893963D03*
Y887270D03*
X755841Y914042D03*
Y907349D03*
X748399Y917389D03*
Y910696D03*
Y904003D03*
X755841Y927428D03*
Y920735D03*
X748399Y930774D03*
Y924081D03*
X755841Y944160D03*
Y937467D03*
X748399Y947507D03*
Y940814D03*
X755841Y960892D03*
Y950853D03*
X748399Y964239D03*
Y954200D03*
X755841Y980971D03*
Y974278D03*
Y967585D03*
X748399Y977625D03*
Y970932D03*
X755841Y987664D03*
X748399Y991011D03*
Y984318D03*
X755841Y1027822D03*
Y1017782D03*
X748399Y1031168D03*
Y1024475D03*
Y1017782D03*
X755841Y1047900D03*
Y1041207D03*
Y1034515D03*
X748399Y1044554D03*
Y1037861D03*
X755841Y1054593D03*
Y1061286D03*
X748399Y1057940D03*
X755841Y1067979D03*
Y1074672D03*
X748399Y1078018D03*
Y1071326D03*
Y1064633D03*
X755841Y1084711D03*
Y1091404D03*
X748399Y1094751D03*
Y1088058D03*
X755841Y1111483D03*
Y1104790D03*
Y1098097D03*
X748399Y1108137D03*
Y1101444D03*
X755841Y1128215D03*
Y1121522D03*
X748399Y1124869D03*
Y1114829D03*
X755841Y1141601D03*
Y1134908D03*
X748399Y1144948D03*
Y1138255D03*
Y1131562D03*
X755841Y1158333D03*
Y1148294D03*
X748399Y1161680D03*
Y1151641D03*
X755841Y1171719D03*
Y1165026D03*
X748399Y1175066D03*
Y1168373D03*
X755841Y1185105D03*
Y1178412D03*
X748399Y1188452D03*
Y1181759D03*
X755841Y1208530D03*
Y1201837D03*
Y1195144D03*
X748399Y1205184D03*
Y1198491D03*
X755841Y1221916D03*
Y1215223D03*
X748399Y1225263D03*
Y1218570D03*
Y1211877D03*
X755841Y1238648D03*
Y1231955D03*
X748399Y1241995D03*
Y1235302D03*
X755841Y1245341D03*
X748283Y1256964D03*
X748399Y1248688D03*
X758746Y1273364D03*
X761546D03*
X769399Y770144D03*
X778099D03*
X764541Y766798D03*
X769399Y783530D03*
X778099D03*
X769399Y776837D03*
X778099D03*
X764541Y780184D03*
Y773491D03*
X769399Y800263D03*
X778099D03*
X769399Y793570D03*
X778099D03*
X764541Y803609D03*
Y796916D03*
Y790223D03*
X769399Y820341D03*
X778099D03*
X769399Y813648D03*
X778099D03*
X769399Y806955D03*
X778099D03*
X764541Y816995D03*
Y810302D03*
X769399Y830381D03*
X778099D03*
X764541Y833727D03*
Y827034D03*
X769399Y850459D03*
X778099D03*
Y843766D03*
X769399D03*
Y837074D03*
X778099D03*
X764541Y847113D03*
Y840420D03*
X778099Y867192D03*
X769399D03*
Y857152D03*
X778099D03*
X764541Y863845D03*
Y853806D03*
X769399Y880577D03*
X778099D03*
X769399Y873885D03*
X778099D03*
X764541Y883924D03*
Y877231D03*
Y870538D03*
X778099Y893963D03*
X769399D03*
Y887270D03*
X778099D03*
X764541Y900656D03*
Y890617D03*
X769399Y917389D03*
X778099D03*
X769399Y910696D03*
X778099D03*
X769399Y904003D03*
X778099D03*
X764541Y914042D03*
Y907349D03*
X769399Y930774D03*
X778099D03*
X769399Y924081D03*
X778099D03*
X764541Y927428D03*
Y920735D03*
X769399Y947507D03*
X778099D03*
X769399Y940814D03*
X778099D03*
X764541Y944160D03*
Y937467D03*
X769399Y964239D03*
X778099D03*
X769399Y954200D03*
X778099D03*
X764541Y960892D03*
Y950853D03*
X769399Y977625D03*
X778099D03*
X769399Y970932D03*
X778099D03*
X764541Y980971D03*
Y974278D03*
Y967585D03*
X769399Y991011D03*
X778099D03*
X769399Y984318D03*
X778099D03*
X764541Y987664D03*
X769399Y1031168D03*
X778099D03*
X769399Y1024475D03*
X778099D03*
X769399Y1017782D03*
X778099D03*
X764541Y1027822D03*
Y1017782D03*
X778099Y1044554D03*
X769399D03*
Y1037861D03*
X778099D03*
X764541Y1047900D03*
Y1041207D03*
Y1034515D03*
X769399Y1057940D03*
X778099D03*
X769399Y1051247D03*
X778099D03*
X764541Y1054593D03*
Y1061286D03*
X778099Y1078018D03*
X769399D03*
X778099Y1071326D03*
X769399D03*
Y1064633D03*
X778099D03*
X764541Y1067979D03*
Y1074672D03*
X778099Y1094751D03*
X769399D03*
X778099Y1088058D03*
X769399D03*
X764541Y1084711D03*
Y1091404D03*
X778099Y1108137D03*
X769399D03*
X778099Y1101444D03*
X769399D03*
X764541Y1111483D03*
Y1104790D03*
Y1098097D03*
X778099Y1124869D03*
X769399D03*
X778099Y1114829D03*
X769399D03*
X764541Y1128215D03*
Y1121522D03*
X778099Y1144948D03*
X769399D03*
X778099Y1138255D03*
X769399D03*
X778099Y1131562D03*
X769399D03*
X764541Y1141601D03*
Y1134908D03*
X778099Y1161680D03*
X769399D03*
X778099Y1151641D03*
X769399D03*
X764541Y1158333D03*
Y1148294D03*
X778099Y1175066D03*
X769399D03*
X778099Y1168373D03*
X769399D03*
X764541Y1171719D03*
Y1165026D03*
X778099Y1188452D03*
X769399D03*
X778099Y1181759D03*
X769399D03*
X764541Y1185105D03*
Y1178412D03*
X769399Y1205184D03*
X778099D03*
Y1198491D03*
X769399D03*
X764541Y1208530D03*
Y1201837D03*
Y1195144D03*
X778099Y1225263D03*
X769399D03*
X778099Y1218570D03*
X769399D03*
Y1211877D03*
X778099D03*
X764541Y1221916D03*
Y1215223D03*
X778099Y1241995D03*
X769399D03*
X778099Y1235302D03*
X769399D03*
X764541Y1238648D03*
Y1231955D03*
X778346Y1257264D03*
X778099Y1248688D03*
X769399D03*
X764541Y1245341D03*
X772446Y1273364D03*
X775246D03*
X785541Y766798D03*
X794241D03*
X785541Y773491D03*
X794241D03*
X785541Y780184D03*
X794241D03*
X785541Y803609D03*
X794241D03*
X785541Y790223D03*
X794241D03*
X785541Y796916D03*
X794241D03*
X785541Y816995D03*
X794241D03*
X785541Y810302D03*
X794241D03*
X785541Y833727D03*
X794241D03*
X785541Y827034D03*
X794241D03*
X785541Y840420D03*
X794241D03*
X785541Y847113D03*
X794241D03*
X785541Y853806D03*
X794241D03*
X785541Y863845D03*
X794241D03*
X785541Y883924D03*
X794241D03*
X785541Y870538D03*
X794241D03*
X785541Y877231D03*
X794241D03*
X785541Y900656D03*
X794241D03*
X785541Y890617D03*
X794241D03*
X785541Y907349D03*
X794241D03*
X785541Y914042D03*
X794241D03*
X785541Y920735D03*
X794241D03*
X785541Y927428D03*
X794241D03*
X785541Y937467D03*
X794241D03*
X785541Y944160D03*
X794241D03*
X785541Y960892D03*
X794241D03*
X785541Y950853D03*
X794241D03*
X785541Y980971D03*
X794241D03*
X785541Y974278D03*
X794241D03*
X785541Y967585D03*
X794241D03*
X785541Y987664D03*
X794241D03*
X785541Y1027822D03*
X794241D03*
X785541Y1017782D03*
X794241D03*
X785541Y1047900D03*
X794241D03*
X785541Y1041207D03*
X794241D03*
X785541Y1034515D03*
X794241D03*
X785541Y1054593D03*
X794241D03*
X785541Y1061286D03*
X794241D03*
X785541Y1074672D03*
X794241D03*
X785541Y1067979D03*
X794241D03*
X785541Y1091404D03*
X794241D03*
X785541Y1084711D03*
X794241D03*
X785541Y1111483D03*
X794241D03*
X785541Y1104790D03*
X794241D03*
X785541Y1098097D03*
X794241D03*
X785541Y1128215D03*
X794241D03*
X785541Y1121522D03*
X794241D03*
X785541Y1141601D03*
X794241D03*
X785541Y1134908D03*
X794241D03*
X785541Y1158333D03*
X794241D03*
X785541Y1148294D03*
X794241D03*
X785541Y1171719D03*
X794241D03*
X785541Y1165026D03*
X794241D03*
X785541Y1178412D03*
X794241D03*
X785541Y1185105D03*
X794241D03*
X785541Y1208530D03*
X794241D03*
X785541Y1195144D03*
X794241D03*
X785541Y1201837D03*
X794241D03*
X785541Y1221916D03*
X794241D03*
X785541Y1215223D03*
X794241D03*
X785541Y1238648D03*
X794241D03*
X785541Y1231955D03*
X794241D03*
X785541Y1245341D03*
X794241D03*
X788446Y1273364D03*
X791246D03*
X799099Y770144D03*
X807799D03*
X799099Y783530D03*
X807799D03*
X799099Y776837D03*
X807799D03*
X799099Y800263D03*
X807799D03*
X799099Y793570D03*
X807799D03*
X799099Y820341D03*
X807799D03*
X799099Y806955D03*
X807799D03*
X799099Y813648D03*
X807799D03*
X799099Y830381D03*
X807799D03*
X799099Y850459D03*
X807799D03*
X799099Y837074D03*
X807799D03*
X799099Y843766D03*
X807799D03*
X799099Y867192D03*
X807799D03*
X799099Y857152D03*
X807799D03*
X799099Y873885D03*
X807799D03*
X799099Y880577D03*
X807799D03*
X799099Y887270D03*
X807799D03*
X799099Y893963D03*
X807799D03*
X799099Y917389D03*
X807799D03*
X799099Y904003D03*
X807799D03*
X799099Y910696D03*
X807799D03*
X799099Y930774D03*
X807799D03*
X799099Y924081D03*
X807799D03*
X799099Y947507D03*
X807799D03*
X799099Y940814D03*
X807799D03*
X799099Y964239D03*
X807799D03*
X799099Y954200D03*
X807799D03*
X799099Y970932D03*
X807799D03*
X799099Y977625D03*
X807799D03*
X799099Y991011D03*
X807799D03*
X799099Y984318D03*
X807799D03*
X799099Y1031168D03*
X807799D03*
X799099Y1024475D03*
X807799D03*
X799099Y1017782D03*
X807799D03*
X799099Y1037861D03*
X807799D03*
X799099Y1044554D03*
X807799D03*
X799099Y1057940D03*
X807799D03*
X799099Y1051247D03*
X807799D03*
X799099Y1078018D03*
X807799D03*
X799099Y1071326D03*
X807799D03*
X799099Y1064633D03*
X807799D03*
X799099Y1094751D03*
X807799D03*
X799099Y1088058D03*
X807799D03*
X799099Y1108137D03*
X807799D03*
X799099Y1101444D03*
X807799D03*
X799099Y1124869D03*
X807799D03*
X799099Y1114829D03*
X807799D03*
X799099Y1144948D03*
X807799D03*
X799099Y1138255D03*
X807799D03*
X799099Y1131562D03*
X807799D03*
X799099Y1161680D03*
X807799D03*
X799099Y1151641D03*
X807799D03*
X799099Y1175066D03*
X807799D03*
X799099Y1168373D03*
X807799D03*
X799099Y1188452D03*
X807799D03*
X799099Y1181759D03*
X807799D03*
X799099Y1205184D03*
X807799D03*
X799099Y1198491D03*
X807799D03*
X799099Y1225263D03*
X807799D03*
X799099Y1211877D03*
X807799D03*
X799099Y1218570D03*
X807799D03*
X799099Y1241995D03*
X807799D03*
X799099Y1235302D03*
X807799D03*
X799099Y1248688D03*
X807799D03*
X808046Y1257664D03*
X804946Y1273364D03*
X802146D03*
X815241Y766798D03*
X823941D03*
X815241Y773491D03*
X823941D03*
X815241Y780184D03*
X823941D03*
X815241Y803609D03*
X823941D03*
X815241Y790223D03*
X823941D03*
X815241Y796916D03*
X823941D03*
X815241Y816995D03*
X823941D03*
X815241Y810302D03*
X823941D03*
X815241Y833727D03*
X823941D03*
X815241Y827034D03*
X823941D03*
X815241Y840420D03*
X823941D03*
X815241Y847113D03*
X823941D03*
X815241Y853806D03*
X823941D03*
X815241Y863845D03*
X823941D03*
X815241Y883924D03*
X823941D03*
X815241Y870538D03*
X823941D03*
X815241Y877231D03*
X823941D03*
X815241Y900656D03*
X823941D03*
X815241Y890617D03*
X823941D03*
X815241Y907349D03*
X823941D03*
X815241Y914042D03*
X823941D03*
X815241Y920735D03*
X823941D03*
X815241Y927428D03*
X823941D03*
X815241Y937467D03*
X823941D03*
X815241Y944160D03*
X823941D03*
X815241Y960892D03*
X823941D03*
X815241Y950853D03*
X823941D03*
X815241Y980971D03*
X823941D03*
X815241Y974278D03*
X823941D03*
X815241Y967585D03*
X823941D03*
X815241Y987664D03*
X823941D03*
X815241Y1027822D03*
X823941D03*
X815241Y1017782D03*
X823941D03*
X815241Y1047900D03*
X823941D03*
X815241Y1041207D03*
X823941D03*
X815241Y1034515D03*
X823941D03*
X815241Y1054593D03*
X823941D03*
X815241Y1061286D03*
X823941D03*
X815241Y1074672D03*
X823941D03*
X815241Y1067979D03*
X823941D03*
X815241Y1091404D03*
X823941D03*
X815241Y1084711D03*
X823941D03*
X815241Y1111483D03*
X823941D03*
X815241Y1104790D03*
X823941D03*
X815241Y1098097D03*
X823941D03*
X815241Y1128215D03*
X823941D03*
X815241Y1121522D03*
X823941D03*
X815241Y1141601D03*
X823941D03*
X815241Y1134908D03*
X823941D03*
X815241Y1158333D03*
X823941D03*
X815241Y1148294D03*
X823941D03*
X815241Y1171719D03*
X823941D03*
X815241Y1165026D03*
X823941D03*
X815241Y1178412D03*
X823941D03*
X815241Y1185105D03*
X823941D03*
X815241Y1208530D03*
X823941D03*
X815241Y1195144D03*
X823941D03*
X815241Y1201837D03*
X823941D03*
X815241Y1221916D03*
X823941D03*
X815241Y1215223D03*
X823941D03*
X815241Y1238648D03*
X823941D03*
X815241Y1231955D03*
X823941D03*
X815241Y1245341D03*
X823941D03*
X820946Y1273364D03*
X818146D03*
X828799Y770144D03*
X837499D03*
X828799Y783530D03*
X837499D03*
X828799Y776837D03*
X837499D03*
Y800263D03*
X828799D03*
X837499Y793570D03*
X828799D03*
Y820341D03*
X837499D03*
X828799Y813648D03*
X837499D03*
X828799Y806955D03*
X837499D03*
X828799Y830381D03*
X837499D03*
X828799Y850459D03*
X837499D03*
X828799Y843766D03*
X837499D03*
X828799Y837074D03*
X837499D03*
X828799Y867192D03*
X837499D03*
X828799Y857152D03*
X837499D03*
X828799Y880577D03*
X837499D03*
X828799Y873885D03*
X837499D03*
X828799Y893963D03*
X837499D03*
X828799Y887270D03*
X837499D03*
X828799Y917389D03*
X837499D03*
Y904003D03*
X828799D03*
X837499Y910696D03*
X828799D03*
Y930774D03*
X837499D03*
X828799Y924081D03*
X837499D03*
X828799Y947507D03*
X837499D03*
X828799Y940814D03*
X837499D03*
X828799Y964239D03*
X837499D03*
X828799Y954200D03*
X837499D03*
X828799Y977625D03*
X837499D03*
X828799Y970932D03*
X837499D03*
X828799Y991011D03*
X837499D03*
X828799Y984318D03*
X837499D03*
X828799Y1031168D03*
X837499D03*
X828799Y1024475D03*
X837499D03*
X828799Y1017782D03*
X837499D03*
X828799Y1044554D03*
X837499D03*
X828799Y1037861D03*
X837499D03*
X828799Y1057940D03*
X837499D03*
X828799Y1051247D03*
X837499D03*
X828799Y1078018D03*
X837499D03*
X828799Y1071326D03*
X837499D03*
X828799Y1064633D03*
X837499D03*
X828799Y1094751D03*
X837499D03*
Y1088058D03*
X828799D03*
X837499Y1108137D03*
X828799D03*
Y1101444D03*
X837499D03*
Y1124869D03*
X828799D03*
X837499Y1114829D03*
X828799D03*
X837499Y1144948D03*
X828799D03*
X837499Y1138255D03*
X828799D03*
X837499Y1131562D03*
X828799D03*
X837499Y1161680D03*
X828799D03*
X837499Y1151641D03*
X828799D03*
X837499Y1175066D03*
X828799D03*
X837499Y1168373D03*
X828799D03*
Y1188452D03*
X837499D03*
Y1181759D03*
X828799D03*
X837499Y1205184D03*
X828799D03*
X837499Y1198491D03*
X828799D03*
X837499Y1225263D03*
X828799D03*
X837499Y1218570D03*
X828799D03*
X837499Y1211877D03*
X828799D03*
X837499Y1241995D03*
X828799D03*
X837499Y1235302D03*
X828799D03*
X837499Y1248688D03*
X828799D03*
X837846Y1256964D03*
X839246Y1273064D03*
X842046D03*
X831846Y1273364D03*
X834646D03*
X844941Y766798D03*
X853641D03*
X844941Y780184D03*
X853641D03*
X844941Y773491D03*
X853641D03*
X844941Y803609D03*
X853641D03*
X844941Y796916D03*
X853641D03*
X844941Y790223D03*
X853641D03*
X844941Y816995D03*
X853641D03*
X844941Y810302D03*
X853641D03*
X844941Y833727D03*
X853641D03*
X844941Y827034D03*
X853641D03*
X844941Y847113D03*
X853641D03*
X844941Y840420D03*
X853641D03*
X844941Y863845D03*
X853641D03*
X844941Y853806D03*
X853641D03*
X844941Y883924D03*
X853641D03*
X844941Y877231D03*
X853641D03*
X844941Y870538D03*
X853641D03*
X844941Y900656D03*
X853641D03*
X844941Y890617D03*
X853641D03*
X844941Y914042D03*
X853641D03*
X844941Y907349D03*
X853641D03*
X844941Y927428D03*
X853641D03*
X844941Y920735D03*
X853641D03*
X844941Y944160D03*
X853641D03*
X844941Y937467D03*
X853641D03*
X844941Y960892D03*
X853641D03*
X844941Y950853D03*
X853641D03*
X844941Y980971D03*
X853641D03*
X844941Y974278D03*
X853641D03*
X844941Y967585D03*
X853641D03*
X844941Y987664D03*
X853641D03*
X844941Y1027822D03*
X853641D03*
X844941Y1017782D03*
X853641D03*
X844941Y1047900D03*
X853641D03*
X844941Y1041207D03*
X853641D03*
X844941Y1034515D03*
X853641D03*
X844941Y1061286D03*
X853641D03*
X844941Y1054593D03*
X853641D03*
X844941Y1074672D03*
X853641D03*
X844941Y1067979D03*
X853641D03*
X844941Y1091404D03*
X853641D03*
X844941Y1084711D03*
X853641D03*
X844941Y1111483D03*
X853641D03*
X844941Y1104790D03*
X853641D03*
X844941Y1098097D03*
X853641D03*
X844941Y1128215D03*
X853641D03*
X844941Y1121522D03*
X853641D03*
X844941Y1141601D03*
X853641D03*
X844941Y1134908D03*
X853641D03*
X844941Y1158333D03*
X853641D03*
X844941Y1148294D03*
X853641D03*
X844941Y1171719D03*
X853641D03*
X844941Y1165026D03*
X853641D03*
X844941Y1185105D03*
X853641D03*
X844941Y1178412D03*
X853641D03*
X844941Y1208530D03*
X853641D03*
X844941Y1201837D03*
X853641D03*
X844941Y1195144D03*
X853641D03*
X844941Y1221916D03*
X853641D03*
X844941Y1215223D03*
X853641D03*
X844941Y1238648D03*
X853641D03*
X844941Y1231955D03*
X853641D03*
X844941Y1245341D03*
X853641D03*
X1003841Y770144D03*
Y783530D03*
Y776837D03*
Y800263D03*
Y793570D03*
Y820341D03*
Y813648D03*
Y806955D03*
Y830381D03*
Y850459D03*
Y843766D03*
Y837074D03*
Y867192D03*
Y857152D03*
Y880577D03*
Y873885D03*
Y893963D03*
Y887270D03*
Y917389D03*
Y910696D03*
Y904003D03*
Y930774D03*
Y924081D03*
Y947507D03*
Y940814D03*
Y964239D03*
Y954200D03*
Y977625D03*
Y970932D03*
Y991011D03*
Y984318D03*
Y1031168D03*
Y1024475D03*
Y1017782D03*
Y1044554D03*
Y1037861D03*
Y1057940D03*
Y1051247D03*
Y1078018D03*
Y1071326D03*
Y1064633D03*
Y1094751D03*
Y1088058D03*
Y1108137D03*
Y1101444D03*
Y1124869D03*
Y1114829D03*
Y1144948D03*
Y1138255D03*
Y1131562D03*
Y1161680D03*
Y1151641D03*
Y1175066D03*
Y1168373D03*
Y1188452D03*
Y1181759D03*
Y1205184D03*
Y1198491D03*
Y1225263D03*
Y1218570D03*
Y1211877D03*
Y1241995D03*
Y1235302D03*
Y1248688D03*
X1019983Y766798D03*
X1012541Y770144D03*
X1019983Y780184D03*
Y773491D03*
X1012541Y783530D03*
Y776837D03*
X1019983Y803609D03*
Y796916D03*
Y790223D03*
X1012541Y800263D03*
Y793570D03*
X1019983Y816995D03*
Y810302D03*
X1012541Y820341D03*
Y813648D03*
Y806955D03*
X1019983Y833727D03*
Y827034D03*
X1012541Y830381D03*
X1019983Y847113D03*
Y840420D03*
X1012541Y850459D03*
Y843766D03*
Y837074D03*
X1019983Y863845D03*
Y853806D03*
X1012541Y867192D03*
Y857152D03*
X1019983Y883924D03*
Y877231D03*
Y870538D03*
X1012541Y880577D03*
Y873885D03*
X1019983Y900656D03*
Y890617D03*
X1012541Y893963D03*
Y887270D03*
X1019983Y914042D03*
Y907349D03*
X1012541Y917389D03*
Y910696D03*
Y904003D03*
X1019983Y927428D03*
Y920735D03*
X1012541Y930774D03*
Y924081D03*
X1019983Y944160D03*
Y937467D03*
X1012541Y947507D03*
Y940814D03*
X1019983Y960892D03*
Y950853D03*
X1012541Y964239D03*
Y954200D03*
X1019983Y980971D03*
Y974278D03*
Y967585D03*
X1012541Y977625D03*
Y970932D03*
X1019983Y987664D03*
X1012541Y991011D03*
Y984318D03*
X1019983Y1027822D03*
Y1017782D03*
X1012541Y1031168D03*
Y1024475D03*
Y1017782D03*
X1019983Y1047900D03*
Y1041207D03*
Y1034515D03*
X1012541Y1044554D03*
Y1037861D03*
X1019983Y1061286D03*
Y1054593D03*
X1012541Y1057940D03*
Y1051247D03*
X1019983Y1067979D03*
Y1074672D03*
X1012541Y1078018D03*
Y1071326D03*
Y1064633D03*
X1019983Y1091404D03*
Y1084711D03*
X1012541Y1094751D03*
Y1088058D03*
X1019983Y1111483D03*
Y1104790D03*
Y1098097D03*
X1012541Y1108137D03*
Y1101444D03*
X1019983Y1128215D03*
Y1121522D03*
X1012541Y1124869D03*
Y1114829D03*
X1019983Y1141601D03*
Y1134908D03*
X1012541Y1144948D03*
Y1138255D03*
Y1131562D03*
X1019983Y1158333D03*
Y1148294D03*
X1012541Y1161680D03*
Y1151641D03*
X1019983Y1171719D03*
Y1165026D03*
X1012541Y1175066D03*
Y1168373D03*
X1019983Y1185105D03*
Y1178412D03*
X1012541Y1188452D03*
Y1181759D03*
X1019983Y1208530D03*
Y1201837D03*
Y1195144D03*
X1012541Y1205184D03*
Y1198491D03*
X1019983Y1221916D03*
Y1215223D03*
X1012541Y1225263D03*
Y1218570D03*
Y1211877D03*
X1019983Y1238648D03*
Y1231955D03*
X1012541Y1241995D03*
Y1235302D03*
X1012543Y1257198D03*
X1019983Y1245341D03*
X1012541Y1248688D03*
X1017111Y1273299D03*
X1014111D03*
X1033541Y770144D03*
X1028683Y766798D03*
X1033541Y783530D03*
Y776837D03*
X1028683Y780184D03*
Y773491D03*
X1033541Y800263D03*
Y793570D03*
X1028683Y803609D03*
Y796916D03*
Y790223D03*
X1033541Y820341D03*
Y813648D03*
Y806955D03*
X1028683Y816995D03*
Y810302D03*
X1033541Y830381D03*
X1028683Y833727D03*
Y827034D03*
X1033541Y850459D03*
Y843766D03*
Y837074D03*
X1028683Y847113D03*
Y840420D03*
X1033541Y867192D03*
Y857152D03*
X1028683Y863845D03*
Y853806D03*
X1033541Y880577D03*
Y873885D03*
X1028683Y883924D03*
Y877231D03*
Y870538D03*
X1033541Y893963D03*
Y887270D03*
X1028683Y900656D03*
Y890617D03*
X1033541Y917389D03*
Y910696D03*
Y904003D03*
X1028683Y914042D03*
Y907349D03*
X1033541Y930774D03*
Y924081D03*
X1028683Y927428D03*
Y920735D03*
X1033541Y947507D03*
Y940814D03*
X1028683Y944160D03*
Y937467D03*
X1033541Y964239D03*
Y954200D03*
X1028683Y960892D03*
Y950853D03*
X1033541Y977625D03*
Y970932D03*
X1028683Y980971D03*
Y974278D03*
Y967585D03*
X1033541Y991011D03*
Y984318D03*
X1028683Y987664D03*
X1033541Y1031168D03*
Y1017782D03*
Y1024475D03*
X1028683Y1027822D03*
Y1017782D03*
X1033541Y1044554D03*
Y1037861D03*
X1028683Y1047900D03*
Y1041207D03*
Y1034515D03*
X1033541Y1057940D03*
Y1051247D03*
X1028683Y1061286D03*
Y1054593D03*
X1033541Y1078018D03*
Y1071326D03*
Y1064633D03*
X1028683Y1067979D03*
Y1074672D03*
X1033541Y1094751D03*
Y1088058D03*
X1028683Y1091404D03*
Y1084711D03*
X1033541Y1108137D03*
Y1101444D03*
X1028683Y1111483D03*
Y1104790D03*
Y1098097D03*
X1033541Y1114829D03*
Y1124869D03*
X1028683Y1128215D03*
Y1121522D03*
X1033541Y1144948D03*
Y1138255D03*
Y1131562D03*
X1028683Y1141601D03*
Y1134908D03*
X1033541Y1161680D03*
Y1151641D03*
X1028683Y1158333D03*
Y1148294D03*
X1033541Y1175066D03*
Y1168373D03*
X1028683Y1171719D03*
Y1165026D03*
X1033541Y1188452D03*
Y1181759D03*
X1028683Y1185105D03*
Y1178412D03*
X1033541Y1205184D03*
Y1198491D03*
X1028683Y1208530D03*
Y1201837D03*
Y1195144D03*
X1033541Y1225263D03*
Y1218570D03*
Y1211877D03*
X1028683Y1221916D03*
Y1215223D03*
X1033541Y1241995D03*
Y1235302D03*
X1028683Y1238648D03*
Y1231955D03*
X1033541Y1248688D03*
X1028683Y1245341D03*
X1036588Y1273344D03*
X1022888D03*
X1025688D03*
X1049683Y766798D03*
X1042241Y770144D03*
X1049683Y780184D03*
Y773491D03*
X1042241Y783530D03*
Y776837D03*
X1049683Y803609D03*
Y796916D03*
Y790223D03*
X1042241Y800263D03*
Y793570D03*
X1049683Y816995D03*
Y810302D03*
X1042241Y820341D03*
Y813648D03*
Y806955D03*
X1049683Y833727D03*
Y827034D03*
X1042241Y830381D03*
X1049683Y847113D03*
Y840420D03*
X1042241Y850459D03*
Y843766D03*
Y837074D03*
X1049683Y863845D03*
Y853806D03*
X1042241Y867192D03*
Y857152D03*
X1049683Y883924D03*
Y877231D03*
Y870538D03*
X1042241Y880577D03*
Y873885D03*
X1049683Y900656D03*
Y890617D03*
X1042241Y893963D03*
Y887270D03*
X1049683Y914042D03*
Y907349D03*
X1042241Y917389D03*
Y910696D03*
Y904003D03*
X1049683Y927428D03*
Y920735D03*
X1042241Y930774D03*
Y924081D03*
X1049683Y944160D03*
Y937467D03*
X1042241Y947507D03*
Y940814D03*
X1049683Y960892D03*
Y950853D03*
X1042241Y964239D03*
Y954200D03*
X1049683Y980971D03*
Y974278D03*
Y967585D03*
X1042241Y977625D03*
Y970932D03*
X1049683Y987664D03*
X1042241Y991011D03*
Y984318D03*
X1049683Y1027822D03*
Y1017782D03*
X1042241Y1031168D03*
Y1017782D03*
Y1024475D03*
X1049683Y1047900D03*
Y1041207D03*
Y1034515D03*
X1042241Y1044554D03*
Y1037861D03*
X1049683Y1061286D03*
Y1054593D03*
X1042241Y1057940D03*
Y1051247D03*
X1049683Y1074672D03*
Y1067979D03*
X1042241Y1078018D03*
Y1071326D03*
Y1064633D03*
X1049683Y1091404D03*
Y1084711D03*
X1042241Y1094751D03*
Y1088058D03*
X1049683Y1111483D03*
Y1104790D03*
Y1098097D03*
X1042241Y1108137D03*
Y1101444D03*
Y1114829D03*
X1049683Y1128215D03*
Y1121522D03*
X1042241Y1124869D03*
X1049683Y1141601D03*
Y1134908D03*
X1042241Y1144948D03*
Y1138255D03*
Y1131562D03*
Y1161680D03*
X1049683Y1158333D03*
Y1148294D03*
X1042241Y1151641D03*
X1049683Y1171719D03*
Y1165026D03*
X1042241Y1175066D03*
Y1168373D03*
X1049683Y1185105D03*
Y1178412D03*
X1042241Y1188452D03*
Y1181759D03*
X1049683Y1208530D03*
Y1201837D03*
Y1195144D03*
X1042241Y1205184D03*
Y1198491D03*
X1049683Y1215223D03*
Y1221916D03*
X1042241Y1225263D03*
Y1218570D03*
Y1211877D03*
X1049683Y1238648D03*
Y1231955D03*
X1042241Y1241995D03*
Y1235302D03*
X1042331Y1257488D03*
X1049683Y1245341D03*
X1042241Y1248688D03*
X1052588Y1273344D03*
X1039388D03*
X1063241Y770144D03*
X1058383Y766798D03*
X1063241Y783530D03*
Y776837D03*
X1058383Y780184D03*
Y773491D03*
X1063241Y800263D03*
Y793570D03*
X1058383Y803609D03*
Y796916D03*
Y790223D03*
X1063241Y820341D03*
Y813648D03*
Y806955D03*
X1058383Y816995D03*
Y810302D03*
X1063241Y830381D03*
X1058383Y833727D03*
Y827034D03*
X1063241Y850459D03*
Y843766D03*
Y837074D03*
X1058383Y847113D03*
Y840420D03*
X1063241Y867192D03*
Y857152D03*
X1058383Y863845D03*
Y853806D03*
X1063241Y880577D03*
Y873885D03*
X1058383Y883924D03*
Y877231D03*
Y870538D03*
X1063241Y893963D03*
Y887270D03*
X1058383Y900656D03*
Y890617D03*
X1063241Y917389D03*
Y910696D03*
Y904003D03*
X1058383Y914042D03*
Y907349D03*
X1063241Y930774D03*
Y924081D03*
X1058383Y927428D03*
Y920735D03*
X1063241Y947507D03*
Y940814D03*
X1058383Y944160D03*
Y937467D03*
X1063241Y964239D03*
Y954200D03*
X1058383Y960892D03*
Y950853D03*
X1063241Y977625D03*
Y970932D03*
X1058383Y980971D03*
Y974278D03*
Y967585D03*
X1063241Y991011D03*
Y984318D03*
X1058383Y987664D03*
X1063241Y1031168D03*
Y1024475D03*
Y1017782D03*
X1058383Y1027822D03*
Y1017782D03*
X1063241Y1044554D03*
Y1037861D03*
X1058383Y1047900D03*
Y1041207D03*
Y1034515D03*
X1063241Y1057940D03*
Y1051247D03*
X1058383Y1061286D03*
Y1054593D03*
X1063241Y1078018D03*
Y1071326D03*
Y1064633D03*
X1058383Y1074672D03*
Y1067979D03*
X1063241Y1094751D03*
Y1088058D03*
X1058383Y1091404D03*
Y1084711D03*
X1063241Y1108137D03*
Y1101444D03*
X1058383Y1111483D03*
Y1104790D03*
Y1098097D03*
X1063241Y1124869D03*
Y1114829D03*
X1058383Y1128215D03*
Y1121522D03*
X1063241Y1144948D03*
Y1138255D03*
Y1131562D03*
X1058383Y1141601D03*
Y1134908D03*
X1063241Y1161680D03*
Y1151641D03*
X1058383Y1158333D03*
Y1148294D03*
X1063241Y1175066D03*
Y1168373D03*
X1058383Y1171719D03*
Y1165026D03*
X1063241Y1188452D03*
Y1181759D03*
X1058383Y1185105D03*
Y1178412D03*
X1063241Y1205184D03*
Y1198491D03*
X1058383Y1208530D03*
Y1201837D03*
Y1195144D03*
X1063241Y1225263D03*
Y1218570D03*
Y1211877D03*
X1058383Y1215223D03*
Y1221916D03*
X1063241Y1241995D03*
Y1235302D03*
X1058383Y1238648D03*
Y1231955D03*
X1063241Y1248688D03*
X1058383Y1245341D03*
X1069088Y1273344D03*
X1066288D03*
X1055388D03*
X1079383Y766798D03*
X1071941Y770144D03*
X1079383Y780184D03*
Y773491D03*
X1071941Y783530D03*
Y776837D03*
X1079383Y803609D03*
Y796916D03*
Y790223D03*
X1071941Y800263D03*
Y793570D03*
X1079383Y816995D03*
Y810302D03*
X1071941Y820341D03*
Y813648D03*
Y806955D03*
X1079383Y833727D03*
Y827034D03*
X1071941Y830381D03*
X1079383Y847113D03*
Y840420D03*
X1071941Y850459D03*
Y843766D03*
Y837074D03*
X1079383Y863845D03*
Y853806D03*
X1071941Y867192D03*
Y857152D03*
X1079383Y883924D03*
Y877231D03*
Y870538D03*
X1071941Y880577D03*
Y873885D03*
X1079383Y900656D03*
Y890617D03*
X1071941Y893963D03*
Y887270D03*
X1079383Y914042D03*
Y907349D03*
X1071941Y917389D03*
Y910696D03*
Y904003D03*
X1079383Y927428D03*
Y920735D03*
X1071941Y930774D03*
Y924081D03*
X1079383Y944160D03*
Y937467D03*
X1071941Y947507D03*
Y940814D03*
X1079383Y960892D03*
Y950853D03*
X1071941Y964239D03*
Y954200D03*
X1079383Y980971D03*
Y974278D03*
Y967585D03*
X1071941Y977625D03*
Y970932D03*
X1079383Y987664D03*
X1071941Y991011D03*
Y984318D03*
X1079383Y1027822D03*
Y1017782D03*
X1071941Y1031168D03*
Y1024475D03*
Y1017782D03*
X1079383Y1047900D03*
Y1041207D03*
Y1034515D03*
X1071941Y1044554D03*
Y1037861D03*
X1079383Y1061286D03*
Y1054593D03*
X1071941Y1057940D03*
Y1051247D03*
X1079383Y1074672D03*
Y1067979D03*
X1071941Y1078018D03*
Y1071326D03*
Y1064633D03*
X1079383Y1091404D03*
Y1084711D03*
X1071941Y1094751D03*
Y1088058D03*
X1079383Y1111483D03*
Y1104790D03*
Y1098097D03*
X1071941Y1108137D03*
Y1101444D03*
X1079383Y1128215D03*
Y1121522D03*
X1071941Y1124869D03*
Y1114829D03*
X1079383Y1141601D03*
Y1134908D03*
X1071941Y1144948D03*
Y1138255D03*
Y1131562D03*
X1079383Y1158333D03*
Y1148294D03*
X1071941Y1161680D03*
Y1151641D03*
X1079383Y1171719D03*
Y1165026D03*
X1071941Y1175066D03*
Y1168373D03*
X1079383Y1185105D03*
Y1178412D03*
X1071941Y1188452D03*
Y1181759D03*
X1079383Y1208530D03*
Y1201837D03*
Y1195144D03*
X1071941Y1205184D03*
Y1198491D03*
X1079383Y1221916D03*
Y1215223D03*
X1071941Y1225263D03*
Y1218570D03*
Y1211877D03*
X1079383Y1238648D03*
Y1231955D03*
X1071941Y1241995D03*
Y1235302D03*
X1071991Y1257262D03*
X1079383Y1245341D03*
X1071941Y1248688D03*
X1085088Y1273344D03*
X1082288D03*
X1092941Y770144D03*
X1101641D03*
X1088083Y766798D03*
X1092941Y783530D03*
X1101641D03*
X1092941Y776837D03*
X1101641D03*
X1088083Y780184D03*
Y773491D03*
X1101641Y800263D03*
X1092941D03*
X1101641Y793570D03*
X1092941D03*
X1088083Y803609D03*
Y796916D03*
Y790223D03*
X1101641Y820341D03*
X1092941D03*
X1101641Y813648D03*
X1092941D03*
X1101641Y806955D03*
X1092941D03*
X1088083Y816995D03*
Y810302D03*
X1101641Y830381D03*
X1092941D03*
X1088083Y833727D03*
Y827034D03*
X1101641Y850459D03*
X1092941D03*
X1101641Y843766D03*
X1092941D03*
X1101641Y837074D03*
X1092941D03*
X1088083Y847113D03*
Y840420D03*
X1101641Y867192D03*
X1092941D03*
X1101641Y857152D03*
X1092941D03*
X1088083Y863845D03*
Y853806D03*
X1101641Y880577D03*
X1092941D03*
X1101641Y873885D03*
X1092941D03*
X1088083Y883924D03*
Y877231D03*
Y870538D03*
X1101641Y893963D03*
X1092941D03*
X1101641Y887270D03*
X1092941D03*
X1088083Y900656D03*
Y890617D03*
X1101641Y917389D03*
X1092941D03*
X1101641Y910696D03*
X1092941D03*
X1101641Y904003D03*
X1092941D03*
X1088083Y914042D03*
Y907349D03*
X1101641Y930774D03*
X1092941D03*
X1101641Y924081D03*
X1092941D03*
X1088083Y927428D03*
Y920735D03*
X1101641Y947507D03*
X1092941D03*
X1101641Y940814D03*
X1092941D03*
X1088083Y944160D03*
Y937467D03*
X1101641Y964239D03*
X1092941D03*
X1101641Y954200D03*
X1092941D03*
X1088083Y960892D03*
Y950853D03*
X1101641Y977625D03*
X1092941D03*
X1101641Y970932D03*
X1092941D03*
X1088083Y980971D03*
Y974278D03*
Y967585D03*
X1101641Y991011D03*
X1092941D03*
X1101641Y984318D03*
X1092941D03*
X1088083Y987664D03*
X1101641Y1031168D03*
X1092941D03*
X1101641Y1024475D03*
X1092941D03*
X1101641Y1017782D03*
X1092941D03*
X1088083Y1027822D03*
Y1017782D03*
X1101641Y1044554D03*
X1092941D03*
X1101641Y1037861D03*
X1092941D03*
X1088083Y1047900D03*
Y1041207D03*
Y1034515D03*
X1101641Y1057940D03*
X1092941D03*
X1101641Y1051247D03*
X1092941D03*
X1088083Y1061286D03*
Y1054593D03*
X1101641Y1078018D03*
X1092941D03*
X1101641Y1071326D03*
X1092941D03*
X1101641Y1064633D03*
X1092941D03*
X1088083Y1074672D03*
Y1067979D03*
X1101641Y1094751D03*
X1092941D03*
X1101641Y1088058D03*
X1092941D03*
X1088083Y1091404D03*
Y1084711D03*
X1101641Y1108137D03*
X1092941D03*
X1101641Y1101444D03*
X1092941D03*
X1088083Y1111483D03*
Y1104790D03*
Y1098097D03*
X1101641Y1124869D03*
X1092941D03*
X1101641Y1114829D03*
X1092941D03*
X1088083Y1128215D03*
Y1121522D03*
X1101641Y1144948D03*
X1092941D03*
X1101641Y1138255D03*
X1092941D03*
X1101641Y1131562D03*
X1092941D03*
X1088083Y1141601D03*
Y1134908D03*
X1092941Y1161680D03*
X1101641D03*
Y1151641D03*
X1092941D03*
X1088083Y1158333D03*
Y1148294D03*
X1101641Y1175066D03*
X1092941D03*
X1101641Y1168373D03*
X1092941D03*
X1088083Y1171719D03*
Y1165026D03*
X1101641Y1181759D03*
X1092941D03*
Y1188452D03*
X1101641D03*
X1088083Y1185105D03*
Y1178412D03*
X1092941Y1205184D03*
X1101641D03*
X1092941Y1198491D03*
X1101641D03*
X1088083Y1208530D03*
Y1201837D03*
Y1195144D03*
X1101641Y1225263D03*
X1092941D03*
X1101641Y1218570D03*
X1092941D03*
Y1211877D03*
X1101641D03*
X1088083Y1221916D03*
Y1215223D03*
X1101641Y1241995D03*
X1092941D03*
X1101641Y1235302D03*
X1092941D03*
X1088083Y1238648D03*
Y1231955D03*
X1101554Y1257102D03*
X1101641Y1248688D03*
X1092941D03*
X1088083Y1245341D03*
X1098788Y1273344D03*
X1095988D03*
X1109083Y766798D03*
X1117783D03*
Y780184D03*
X1109083D03*
X1117783Y773491D03*
X1109083D03*
X1117783Y803609D03*
X1109083D03*
X1117783Y796916D03*
X1109083D03*
Y790223D03*
X1117783D03*
Y816995D03*
X1109083D03*
X1117783Y810302D03*
X1109083D03*
X1117783Y833727D03*
X1109083D03*
X1117783Y827034D03*
X1109083D03*
X1117783Y847113D03*
X1109083D03*
X1117783Y840420D03*
X1109083D03*
X1117783Y863845D03*
X1109083D03*
X1117783Y853806D03*
X1109083D03*
X1117783Y883924D03*
X1109083D03*
X1117783Y877231D03*
X1109083D03*
X1117783Y870538D03*
X1109083D03*
X1117783Y900656D03*
X1109083D03*
X1117783Y890617D03*
X1109083D03*
X1117783Y914042D03*
X1109083D03*
X1117783Y907349D03*
X1109083D03*
X1117783Y927428D03*
X1109083D03*
X1117783Y920735D03*
X1109083D03*
X1117783Y944160D03*
X1109083D03*
X1117783Y937467D03*
X1109083D03*
X1117783Y960892D03*
X1109083D03*
X1117783Y950853D03*
X1109083D03*
X1117783Y980971D03*
X1109083D03*
X1117783Y974278D03*
X1109083D03*
X1117783Y967585D03*
X1109083D03*
X1117783Y987664D03*
X1109083D03*
X1117783Y1027822D03*
X1109083D03*
X1117783Y1017782D03*
X1109083D03*
X1117783Y1047900D03*
X1109083D03*
X1117783Y1041207D03*
X1109083D03*
X1117783Y1034515D03*
X1109083D03*
X1117783Y1061286D03*
X1109083D03*
X1117783Y1054593D03*
X1109083D03*
X1117783Y1074672D03*
X1109083D03*
X1117783Y1067979D03*
X1109083D03*
X1117783Y1091404D03*
X1109083D03*
X1117783Y1084711D03*
X1109083D03*
X1117783Y1111483D03*
X1109083D03*
X1117783Y1104790D03*
X1109083D03*
X1117783Y1098097D03*
X1109083D03*
X1117783Y1128215D03*
X1109083D03*
X1117783Y1121522D03*
X1109083D03*
X1117783Y1141601D03*
X1109083D03*
X1117783Y1134908D03*
X1109083D03*
X1117783Y1158333D03*
X1109083D03*
X1117783Y1148294D03*
X1109083D03*
X1117783Y1171719D03*
X1109083D03*
X1117783Y1165026D03*
X1109083D03*
X1117783Y1185105D03*
X1109083D03*
X1117783Y1178412D03*
X1109083D03*
X1117783Y1208530D03*
X1109083D03*
X1117783Y1201837D03*
X1109083D03*
X1117783Y1195144D03*
X1109083D03*
X1117783Y1221916D03*
X1109083D03*
X1117783Y1215223D03*
X1109083D03*
X1117783Y1238648D03*
X1109083D03*
X1117783Y1231955D03*
X1109083D03*
X1117783Y1245341D03*
X1109083D03*
X1111988Y1273344D03*
X1114788D03*
X1131341Y770144D03*
X1122641D03*
X1131341Y783530D03*
X1122641D03*
X1131341Y776837D03*
X1122641D03*
X1131341Y800263D03*
X1122641D03*
X1131341Y793570D03*
X1122641D03*
X1131341Y820341D03*
X1122641D03*
X1131341Y813648D03*
X1122641D03*
X1131341Y806955D03*
X1122641D03*
X1131341Y830381D03*
X1122641D03*
X1131341Y850459D03*
X1122641D03*
X1131341Y843766D03*
X1122641D03*
X1131341Y837074D03*
X1122641D03*
X1131341Y867192D03*
X1122641D03*
X1131341Y857152D03*
X1122641D03*
X1131341Y880577D03*
X1122641D03*
X1131341Y873885D03*
X1122641D03*
X1131341Y893963D03*
X1122641D03*
X1131341Y887270D03*
X1122641D03*
X1131341Y917389D03*
X1122641D03*
X1131341Y910696D03*
X1122641D03*
X1131341Y904003D03*
X1122641D03*
X1131341Y930774D03*
X1122641D03*
X1131341Y924081D03*
X1122641D03*
Y947507D03*
X1131341D03*
Y940814D03*
X1122641D03*
X1131341Y964239D03*
X1122641D03*
X1131341Y954200D03*
X1122641D03*
X1131341Y977625D03*
X1122641D03*
X1131341Y970932D03*
X1122641D03*
X1131341Y991011D03*
X1122641D03*
X1131341Y984318D03*
X1122641D03*
X1131341Y1031168D03*
X1122641D03*
X1131341Y1024475D03*
X1122641D03*
X1131341Y1017782D03*
X1122641D03*
X1131341Y1044554D03*
X1122641D03*
X1131341Y1037861D03*
X1122641D03*
X1131341Y1057940D03*
X1122641D03*
X1131341Y1051247D03*
X1122641D03*
X1131341Y1078018D03*
X1122641D03*
X1131341Y1071326D03*
X1122641D03*
X1131341Y1064633D03*
X1122641D03*
X1131341Y1094751D03*
X1122641D03*
X1131341Y1088058D03*
X1122641D03*
X1131341Y1108137D03*
X1122641D03*
X1131341Y1101444D03*
X1122641D03*
X1131341Y1124869D03*
X1122641D03*
X1131341Y1114829D03*
X1122641D03*
X1131341Y1144948D03*
X1122641D03*
X1131341Y1138255D03*
X1122641D03*
X1131341Y1131562D03*
X1122641D03*
X1131341Y1161680D03*
X1122641D03*
X1131341Y1151641D03*
X1122641D03*
X1131341Y1175066D03*
X1122641D03*
X1131341Y1168373D03*
X1122641D03*
X1131341Y1188452D03*
X1122641D03*
X1131341Y1181759D03*
X1122641D03*
X1131341Y1205184D03*
X1122641D03*
X1131341Y1198491D03*
X1122641D03*
X1131341Y1225263D03*
X1122641D03*
X1131341Y1218570D03*
X1122641D03*
X1131341Y1211877D03*
X1122641D03*
X1131341Y1241995D03*
X1122641D03*
X1131341Y1235302D03*
X1122641D03*
X1131434Y1257291D03*
X1122641Y1248688D03*
X1131341D03*
X1126188Y1273344D03*
X1128988D03*
X1152341Y770144D03*
X1147483Y766798D03*
X1138783D03*
X1152341Y783530D03*
Y776837D03*
X1147483Y780184D03*
X1138783D03*
Y773491D03*
X1147483D03*
X1152341Y800263D03*
X1147483Y803609D03*
X1138783D03*
X1152341Y793570D03*
X1147483Y796916D03*
X1138783D03*
X1147483Y790223D03*
X1138783D03*
X1152341Y820341D03*
X1147483Y816995D03*
X1138783D03*
X1152341Y813648D03*
Y806955D03*
X1147483Y810302D03*
X1138783D03*
X1147483Y833727D03*
X1138783D03*
X1152341Y830381D03*
X1147483Y827034D03*
X1138783D03*
X1152341Y850459D03*
Y843766D03*
Y837074D03*
X1147483Y847113D03*
X1138783D03*
X1147483Y840420D03*
X1138783D03*
X1152341Y867192D03*
Y857152D03*
X1147483Y863845D03*
X1138783D03*
X1147483Y853806D03*
X1138783D03*
X1152341Y880577D03*
Y873885D03*
X1147483Y883924D03*
X1138783D03*
X1147483Y877231D03*
X1138783D03*
X1147483Y870538D03*
X1138783D03*
X1152341Y893963D03*
Y887270D03*
X1138783Y900656D03*
X1147483D03*
X1138783Y890617D03*
X1147483D03*
X1152341Y917389D03*
Y910696D03*
Y904003D03*
X1147483Y914042D03*
X1138783D03*
X1147483Y907349D03*
X1138783D03*
X1152341Y930774D03*
Y924081D03*
X1147483Y927428D03*
X1138783D03*
X1147483Y920735D03*
X1138783D03*
X1152341Y947507D03*
Y940814D03*
X1147483Y944160D03*
X1138783D03*
X1147483Y937467D03*
X1138783D03*
X1152341Y964239D03*
Y954200D03*
X1147483Y960892D03*
X1138783D03*
X1147483Y950853D03*
X1138783D03*
X1152341Y977625D03*
Y970932D03*
X1147483Y980971D03*
X1138783D03*
X1147483Y974278D03*
X1138783D03*
X1147483Y967585D03*
X1138783D03*
X1152341Y991011D03*
Y984318D03*
X1147483Y987664D03*
X1138783D03*
X1152341Y1031168D03*
Y1024475D03*
Y1017782D03*
X1147483Y1027822D03*
X1138783D03*
X1147483Y1017782D03*
X1138783D03*
X1152341Y1044554D03*
Y1037861D03*
X1138783Y1047900D03*
X1147483D03*
Y1041207D03*
X1138783D03*
X1147483Y1034515D03*
X1138783D03*
X1152341Y1057940D03*
Y1051247D03*
X1147483Y1061286D03*
X1138783D03*
X1147483Y1054593D03*
X1138783D03*
X1152341Y1078018D03*
Y1071326D03*
Y1064633D03*
X1147483Y1074672D03*
X1138783D03*
X1147483Y1067979D03*
X1138783D03*
X1152341Y1094751D03*
Y1088058D03*
X1147483Y1091404D03*
X1138783D03*
X1147483Y1084711D03*
X1138783D03*
X1152341Y1108137D03*
Y1101444D03*
X1147483Y1111483D03*
X1138783D03*
X1147483Y1104790D03*
X1138783D03*
X1147483Y1098097D03*
X1138783D03*
X1152341Y1124869D03*
Y1114829D03*
X1147483Y1128215D03*
X1138783D03*
X1147483Y1121522D03*
X1138783D03*
X1152341Y1144948D03*
Y1138255D03*
Y1131562D03*
X1147483Y1141601D03*
X1138783D03*
X1147483Y1134908D03*
X1138783D03*
X1152341Y1161680D03*
Y1151641D03*
X1147483Y1158333D03*
X1138783D03*
Y1148294D03*
X1147483D03*
X1152341Y1175066D03*
Y1168373D03*
X1147483Y1171719D03*
X1138783D03*
X1147483Y1165026D03*
X1138783D03*
X1152341Y1188452D03*
Y1181759D03*
X1147483Y1185105D03*
X1138783D03*
X1147483Y1178412D03*
X1138783D03*
X1152341Y1205184D03*
Y1198491D03*
X1147483Y1208530D03*
X1138783D03*
X1147483Y1201837D03*
X1138783D03*
X1147483Y1195144D03*
X1138783D03*
X1152341Y1225263D03*
Y1218570D03*
Y1211877D03*
X1147483Y1221916D03*
X1138783D03*
X1147483Y1215223D03*
X1138783D03*
X1152341Y1241995D03*
Y1235302D03*
X1147483Y1238648D03*
X1138783D03*
X1147483Y1231955D03*
X1138783D03*
X1152341Y1248688D03*
X1147483Y1245341D03*
X1138783D03*
X1152381Y1269684D03*
X1147681D03*
X1138201Y1270277D03*
X1168483Y766798D03*
X1161041Y770144D03*
X1168483Y780184D03*
Y773491D03*
X1161041Y783530D03*
Y776837D03*
X1168483Y803609D03*
Y796916D03*
Y790223D03*
X1161041Y800263D03*
Y793570D03*
X1168483Y816995D03*
Y810302D03*
X1161041Y820341D03*
Y813648D03*
Y806955D03*
X1168483Y833727D03*
X1167633Y827034D03*
X1161041Y830381D03*
X1168483Y847113D03*
Y840420D03*
X1161041Y850459D03*
Y843766D03*
Y837074D03*
X1167633Y863845D03*
X1161041Y867192D03*
X1168483Y853806D03*
X1161041Y857152D03*
X1168483Y883924D03*
Y877231D03*
Y870538D03*
X1161041Y880577D03*
Y873885D03*
X1168483Y900656D03*
Y890617D03*
X1161041Y893963D03*
Y887270D03*
X1168483Y914042D03*
Y907349D03*
X1161041Y917389D03*
Y910696D03*
Y904003D03*
X1167633Y927428D03*
X1168483Y920735D03*
X1161041Y930774D03*
Y924081D03*
X1168483Y937467D03*
Y944160D03*
X1161041Y947507D03*
Y940814D03*
X1168483Y960892D03*
Y950853D03*
X1161041Y964239D03*
Y954200D03*
X1168483Y974278D03*
Y980971D03*
Y967585D03*
X1161041Y977625D03*
Y970932D03*
X1168483Y987664D03*
X1161041Y991011D03*
Y984318D03*
X1168483Y1027822D03*
Y1017782D03*
X1161041Y1031168D03*
Y1024475D03*
Y1017782D03*
X1168483Y1047900D03*
Y1041207D03*
Y1034515D03*
X1161041Y1044554D03*
Y1037861D03*
X1168483Y1054593D03*
Y1061286D03*
X1161041Y1057940D03*
Y1051247D03*
X1168483Y1074672D03*
Y1067979D03*
X1161041Y1078018D03*
Y1071326D03*
Y1064633D03*
X1168483Y1091404D03*
X1167633Y1084711D03*
X1161041Y1094751D03*
Y1088058D03*
X1168483Y1111483D03*
Y1104790D03*
Y1098097D03*
X1161041Y1108137D03*
Y1101444D03*
X1168483Y1128215D03*
Y1121522D03*
X1161041Y1124869D03*
Y1114829D03*
X1168483Y1141601D03*
Y1134908D03*
X1161041Y1144948D03*
Y1138255D03*
Y1131562D03*
X1167633Y1158333D03*
X1168483Y1148294D03*
X1161041Y1161680D03*
Y1151641D03*
X1168483Y1171719D03*
Y1165026D03*
X1161041Y1175066D03*
Y1168373D03*
X1168483Y1185105D03*
Y1178412D03*
X1161041Y1188452D03*
Y1181759D03*
X1168483Y1208530D03*
Y1201837D03*
Y1195144D03*
X1161041Y1205184D03*
Y1198491D03*
X1168483Y1221916D03*
Y1215223D03*
X1161041Y1225263D03*
Y1218570D03*
Y1211877D03*
X1168483Y1238648D03*
X1167633Y1231955D03*
X1161041Y1241995D03*
Y1235302D03*
X1161065Y1258871D03*
X1168483Y1245341D03*
X1161041Y1248688D03*
X1161781Y1269684D03*
X1182041Y770144D03*
X1177183Y766798D03*
X1182041Y783530D03*
Y776837D03*
X1177183Y780184D03*
Y773491D03*
X1182041Y800263D03*
Y793570D03*
X1177183Y803609D03*
Y796916D03*
Y790223D03*
X1182041Y813648D03*
Y806955D03*
X1181191Y820341D03*
X1177183Y816995D03*
Y810302D03*
X1181191Y830381D03*
X1177183Y833727D03*
Y827034D03*
X1182041Y850459D03*
Y837074D03*
Y843766D03*
X1177183Y847113D03*
Y840420D03*
X1181191Y867192D03*
X1177183Y863845D03*
X1181191Y857152D03*
X1177183Y853806D03*
X1182041Y873885D03*
Y880577D03*
X1177183Y883924D03*
Y877231D03*
Y870538D03*
X1182041Y893963D03*
Y887270D03*
X1177183Y900656D03*
Y890617D03*
X1182041Y917389D03*
Y910696D03*
Y904003D03*
X1177183Y914042D03*
Y907349D03*
X1181191Y930774D03*
Y924081D03*
X1177183Y927428D03*
Y920735D03*
X1182041Y940814D03*
Y947507D03*
X1177183Y937467D03*
Y944160D03*
X1182041Y964239D03*
Y954200D03*
X1177183Y960892D03*
Y950853D03*
X1182041Y970932D03*
Y977625D03*
X1177183Y974278D03*
Y980971D03*
Y967585D03*
X1182041Y991011D03*
Y984318D03*
X1177183Y987664D03*
X1182041Y1031168D03*
Y1017782D03*
Y1024475D03*
X1177183Y1027822D03*
Y1017782D03*
X1182041Y1044554D03*
Y1037861D03*
X1177183Y1047900D03*
Y1041207D03*
Y1034515D03*
X1182041Y1057940D03*
Y1051247D03*
X1177183Y1054593D03*
Y1061286D03*
X1181191Y1078018D03*
X1182041Y1071326D03*
Y1064633D03*
X1177183Y1074672D03*
Y1067979D03*
X1182041Y1094751D03*
X1181191Y1088058D03*
X1177183Y1091404D03*
Y1084711D03*
X1182041Y1101444D03*
Y1108137D03*
X1177183Y1111483D03*
Y1104790D03*
Y1098097D03*
X1182041Y1114829D03*
Y1124869D03*
X1177183Y1128215D03*
Y1121522D03*
X1182041Y1144948D03*
Y1138255D03*
Y1131562D03*
X1177183Y1141601D03*
Y1134908D03*
X1181191Y1161680D03*
Y1151641D03*
X1177183Y1158333D03*
Y1148294D03*
X1182041Y1168373D03*
Y1175066D03*
X1177183Y1171719D03*
Y1165026D03*
X1182041Y1188452D03*
Y1181759D03*
X1177183Y1185105D03*
Y1178412D03*
X1182041Y1205184D03*
Y1198491D03*
X1177183Y1208530D03*
Y1201837D03*
Y1195144D03*
X1181191Y1225263D03*
X1182041Y1211877D03*
Y1218570D03*
X1177183Y1221916D03*
Y1215223D03*
X1182041Y1241995D03*
X1181191Y1235302D03*
X1177183Y1238648D03*
Y1231955D03*
X1182041Y1248688D03*
X1177183Y1245341D03*
X1176867Y1270029D03*
X1198183Y766798D03*
X1190741Y770144D03*
X1198183Y780184D03*
Y773491D03*
X1190741Y783530D03*
Y776837D03*
X1198183Y803609D03*
Y796916D03*
Y790223D03*
X1190741Y800263D03*
Y793570D03*
X1197333Y816995D03*
X1198183Y810302D03*
X1190741Y813648D03*
Y806955D03*
X1191591Y820341D03*
X1198183Y833727D03*
X1197333Y827034D03*
X1191591Y830381D03*
X1198183Y847113D03*
Y840420D03*
X1190741Y850459D03*
Y837074D03*
Y843766D03*
X1197333Y863845D03*
X1191591Y867192D03*
X1198183Y853806D03*
X1191591Y857152D03*
X1198183Y877231D03*
X1197333Y870538D03*
X1198183Y883924D03*
X1190741Y873885D03*
Y880577D03*
X1198183Y900656D03*
Y890617D03*
X1190741Y893963D03*
Y887270D03*
X1198183Y914042D03*
Y907349D03*
X1190741Y917389D03*
Y910696D03*
Y904003D03*
X1197383Y927428D03*
X1198183Y920735D03*
X1191591Y930774D03*
Y924081D03*
X1198183Y944160D03*
X1197333Y937467D03*
X1190741Y940814D03*
Y947507D03*
X1198183Y960892D03*
Y950853D03*
X1190741Y964239D03*
Y954200D03*
X1198183Y980971D03*
Y974278D03*
Y967585D03*
X1190741Y970932D03*
Y977625D03*
X1198183Y987664D03*
X1190741Y991011D03*
Y984318D03*
X1198183Y1027822D03*
Y1017782D03*
X1190741Y1031168D03*
Y1017782D03*
Y1024475D03*
X1198183Y1047900D03*
Y1041207D03*
Y1034515D03*
X1190741Y1044554D03*
Y1037861D03*
X1198183Y1054593D03*
Y1061286D03*
X1190741Y1057940D03*
Y1051247D03*
X1197333Y1074672D03*
X1198183Y1067979D03*
X1191591Y1078018D03*
X1190741Y1071326D03*
Y1064633D03*
X1198183Y1091404D03*
X1197333Y1084711D03*
X1190741Y1094751D03*
X1191591Y1088058D03*
X1198183Y1111483D03*
Y1098097D03*
Y1104790D03*
X1190741Y1101444D03*
Y1108137D03*
X1198183Y1128215D03*
Y1121522D03*
X1190741Y1114829D03*
Y1124869D03*
X1198183Y1141601D03*
X1197333Y1134908D03*
X1190741Y1144948D03*
Y1138255D03*
Y1131562D03*
X1198183Y1158333D03*
X1197333Y1148294D03*
X1191591Y1161680D03*
Y1151641D03*
X1198183Y1165026D03*
Y1171719D03*
X1190741Y1168373D03*
Y1175066D03*
X1198183Y1185105D03*
Y1178412D03*
X1190741Y1188452D03*
Y1181759D03*
X1198183Y1208530D03*
Y1201837D03*
Y1195144D03*
X1190741Y1205184D03*
Y1198491D03*
X1198183Y1221916D03*
Y1215223D03*
X1191591Y1225263D03*
X1190741Y1211877D03*
Y1218570D03*
X1197333Y1238648D03*
Y1231955D03*
X1190741Y1241995D03*
X1191591Y1235302D03*
X1198183Y1245341D03*
X1190966Y1258711D03*
X1190741Y1248688D03*
X1191538Y1270004D03*
X1194572Y1578182D03*
Y1590094D03*
X1199872Y1614292D03*
Y1602380D03*
X1211741Y770144D03*
X1206883Y766798D03*
X1211741Y783530D03*
Y776837D03*
X1206883Y780184D03*
Y773491D03*
X1211741Y800263D03*
Y793570D03*
X1206883Y803609D03*
Y796916D03*
Y790223D03*
X1210891Y820341D03*
Y813648D03*
X1211741Y806955D03*
X1207148Y817554D03*
X1206883Y810302D03*
X1211741Y830381D03*
X1206883Y833727D03*
X1207733Y827034D03*
X1211741Y850459D03*
Y837074D03*
Y843766D03*
X1206883Y847113D03*
Y840420D03*
X1210891Y867492D03*
X1207733Y863845D03*
X1210891Y857152D03*
X1206883Y853806D03*
X1211741Y874185D03*
Y880577D03*
X1206883Y877231D03*
X1207201Y871084D03*
X1206883Y883924D03*
X1211741Y893963D03*
Y887270D03*
X1206883Y900656D03*
Y890617D03*
X1211741Y917389D03*
Y910696D03*
Y904003D03*
X1206883Y914042D03*
Y907349D03*
X1211741Y930774D03*
Y924081D03*
X1207683Y927428D03*
X1206883Y920735D03*
X1211741Y947507D03*
X1211001Y940814D03*
X1206883Y944660D03*
X1207733Y937467D03*
X1211741Y964239D03*
Y954200D03*
X1206883Y960892D03*
Y950853D03*
X1211741Y977625D03*
Y970932D03*
X1206883Y980971D03*
Y974278D03*
Y967585D03*
X1211741Y991011D03*
X1206883Y987664D03*
X1211741Y984318D03*
Y1031168D03*
X1206883Y1027822D03*
Y1017782D03*
X1211741D03*
Y1024475D03*
Y1044554D03*
Y1037861D03*
X1206883Y1047900D03*
Y1041207D03*
Y1034515D03*
X1211741Y1051247D03*
Y1057940D03*
X1206883Y1054593D03*
Y1061286D03*
X1210891Y1078018D03*
X1211741Y1064633D03*
Y1071326D03*
X1207733Y1074672D03*
X1206883Y1067979D03*
X1211741Y1094751D03*
X1210891Y1088058D03*
X1206883Y1091404D03*
Y1084711D03*
X1211741Y1108137D03*
Y1101444D03*
X1206883Y1111483D03*
Y1098097D03*
Y1104790D03*
X1210891Y1124869D03*
X1211741Y1114829D03*
X1206883Y1128215D03*
Y1121522D03*
X1211741Y1144948D03*
Y1138255D03*
X1210891Y1131562D03*
X1206883Y1141601D03*
X1207733Y1134908D03*
X1211741Y1151641D03*
Y1161680D03*
X1206883Y1158333D03*
X1207733Y1148294D03*
X1211741Y1175066D03*
Y1168373D03*
X1206883Y1165026D03*
Y1171719D03*
X1211741Y1188452D03*
Y1181759D03*
X1206883Y1185105D03*
Y1178412D03*
X1211741Y1205184D03*
Y1198491D03*
X1206883Y1208530D03*
Y1201837D03*
Y1195144D03*
X1210891Y1225263D03*
X1211741Y1218570D03*
Y1211877D03*
X1206883Y1221916D03*
Y1215223D03*
X1211741Y1241995D03*
X1211328Y1234977D03*
X1207733Y1238648D03*
Y1231955D03*
X1206883Y1245341D03*
X1211741Y1248688D03*
X1204608Y1273119D03*
X1202043Y1273123D03*
X1202372Y1578182D03*
X1214432D03*
X1206632D03*
X1202372Y1590094D03*
X1214432D03*
X1206632D03*
X1207672Y1602380D03*
Y1614292D03*
X1211932D03*
Y1602380D03*
X1227883Y766798D03*
X1220441Y770144D03*
X1227883Y780184D03*
Y773491D03*
X1220441Y783530D03*
Y776837D03*
X1227883Y803609D03*
Y796916D03*
Y790223D03*
X1220441Y800263D03*
Y793570D03*
X1227033Y816995D03*
X1227883Y810302D03*
X1221291Y820341D03*
Y813648D03*
X1220441Y806955D03*
X1227883Y833727D03*
X1227033Y827034D03*
X1220441Y830381D03*
X1227883Y847113D03*
Y840420D03*
X1220441Y850459D03*
Y837074D03*
Y843766D03*
X1227033Y863845D03*
X1221291Y867192D03*
X1227033Y853806D03*
X1221291Y857152D03*
X1227883Y870538D03*
Y883924D03*
Y877231D03*
X1220441Y873885D03*
Y880577D03*
X1227033Y900656D03*
X1227883Y890617D03*
X1220441Y893963D03*
Y887270D03*
X1227883Y914042D03*
Y907349D03*
X1220441Y917389D03*
Y910696D03*
Y904003D03*
X1227033Y927428D03*
X1227883Y920735D03*
X1221291Y930774D03*
X1220441Y924081D03*
X1227883Y944160D03*
X1227033Y937467D03*
X1220441Y947507D03*
X1221291Y940814D03*
X1227883Y960892D03*
Y950853D03*
X1220441Y964239D03*
Y954200D03*
X1227883Y974278D03*
Y967585D03*
X1220441Y977625D03*
Y970932D03*
X1227883Y980971D03*
Y987664D03*
X1220441Y991011D03*
Y984318D03*
X1227883Y1027822D03*
X1220441Y1031168D03*
X1227883Y1017782D03*
X1220441D03*
Y1024475D03*
X1227883Y1047900D03*
Y1041207D03*
Y1034515D03*
X1220441Y1044554D03*
Y1037861D03*
X1227883Y1061286D03*
Y1054593D03*
X1220441Y1051247D03*
Y1057940D03*
X1227033Y1074672D03*
Y1067979D03*
X1221291Y1078018D03*
X1220441Y1064633D03*
Y1071326D03*
X1227883Y1091404D03*
Y1084711D03*
X1220441Y1094751D03*
X1221291Y1088058D03*
X1227883Y1104790D03*
X1227033Y1111483D03*
X1227883Y1098097D03*
X1220441Y1108137D03*
Y1101444D03*
X1227883Y1128215D03*
X1227033Y1121522D03*
X1221291Y1124869D03*
X1220441Y1114829D03*
X1227883Y1134908D03*
Y1141601D03*
X1220441Y1144948D03*
Y1138255D03*
X1221291Y1131562D03*
X1227883Y1158333D03*
Y1148294D03*
X1220441Y1151641D03*
Y1161680D03*
X1227883Y1171719D03*
Y1165026D03*
X1220441Y1175066D03*
Y1168373D03*
X1227883Y1185105D03*
Y1178412D03*
X1220441Y1188452D03*
Y1181759D03*
X1227883Y1208530D03*
Y1201837D03*
X1227033Y1195144D03*
X1220441Y1205184D03*
Y1198491D03*
X1227033Y1221916D03*
X1227883Y1215223D03*
X1221291Y1225263D03*
X1220441Y1218570D03*
Y1211877D03*
X1227883Y1238648D03*
X1227033Y1231955D03*
X1220441Y1241995D03*
X1221291Y1235302D03*
X1220441Y1248688D03*
X1227883Y1245341D03*
X1220601Y1269684D03*
X1220931Y1260093D03*
X1233327Y1274515D03*
X1231377Y1275855D03*
X1218692Y1578182D03*
X1226492D03*
X1230752D03*
X1218692Y1590094D03*
X1226492D03*
X1230752D03*
X1219732Y1614292D03*
Y1602380D03*
X1231792Y1614292D03*
Y1602380D03*
X1223992D03*
Y1614292D03*
X1236583Y766798D03*
Y780184D03*
Y773491D03*
Y803609D03*
Y796916D03*
Y790223D03*
X1237433Y816995D03*
X1236583Y810302D03*
Y833727D03*
X1237433Y827034D03*
X1236583Y847113D03*
Y840420D03*
X1237433Y863845D03*
Y853806D03*
X1236583Y870538D03*
Y883924D03*
Y877231D03*
Y900656D03*
Y890617D03*
Y914042D03*
Y907349D03*
X1237433Y927428D03*
X1236583Y920735D03*
Y944160D03*
X1237433Y937467D03*
X1236583Y960892D03*
Y950853D03*
Y974278D03*
Y967585D03*
Y980971D03*
Y987664D03*
Y1027822D03*
Y1017782D03*
Y1047900D03*
Y1041207D03*
Y1034515D03*
Y1061286D03*
Y1054593D03*
X1237433Y1074672D03*
Y1067979D03*
X1236583Y1091404D03*
Y1084711D03*
Y1104790D03*
X1237433Y1111483D03*
X1236583Y1098097D03*
Y1128215D03*
X1237433Y1121522D03*
X1236583Y1134908D03*
Y1141601D03*
Y1158333D03*
Y1148294D03*
Y1171719D03*
Y1165026D03*
Y1185105D03*
Y1178412D03*
Y1208530D03*
Y1201837D03*
Y1195144D03*
X1237433Y1221916D03*
X1236583Y1215223D03*
Y1238648D03*
X1237433Y1231955D03*
X1236583Y1245341D03*
X1238552Y1578182D03*
X1242812D03*
X1238552Y1590094D03*
X1242812D03*
X1236052Y1602380D03*
Y1614292D03*
X1243852D03*
Y1602380D03*
X1248112D03*
Y1614292D03*
X1241142Y1675383D03*
Y1679920D03*
X1249016Y1679320D03*
X1241142Y1684454D03*
Y1689556D03*
Y1694093D03*
Y1698627D03*
X1249016Y1688391D03*
Y1693493D03*
Y1698030D03*
Y1683857D03*
X1241142Y1703729D03*
Y1708266D03*
Y1712800D03*
X1249016Y1707666D03*
Y1712203D03*
Y1702564D03*
X1241142Y1726974D03*
Y1722440D03*
Y1717903D03*
X1249016Y1730911D03*
Y1726377D03*
Y1721840D03*
Y1716737D03*
X1250612Y1578182D03*
X1262672D03*
X1254872D03*
X1250612Y1590094D03*
X1262672D03*
X1254872D03*
X1255912Y1614292D03*
Y1602380D03*
X1260172D03*
Y1614292D03*
X1256890Y1675383D03*
Y1679920D03*
X1264764Y1679320D03*
X1256890Y1684454D03*
Y1689556D03*
Y1694093D03*
Y1698627D03*
X1264764Y1688391D03*
Y1693493D03*
Y1698030D03*
Y1683857D03*
X1256890Y1703729D03*
Y1708266D03*
Y1712800D03*
X1264764Y1707666D03*
Y1712203D03*
Y1702564D03*
X1256890Y1726974D03*
Y1722440D03*
Y1717903D03*
X1264764Y1730911D03*
Y1726377D03*
Y1721840D03*
Y1716737D03*
X1266932Y1578182D03*
X1274732D03*
X1278992D03*
X1266932Y1590094D03*
X1274732D03*
X1278992D03*
X1267972Y1614292D03*
Y1602380D03*
X1272232D03*
Y1614292D03*
X1280032D03*
Y1602380D03*
X1272638Y1675383D03*
Y1679920D03*
X1280512Y1679320D03*
X1272638Y1684454D03*
Y1689556D03*
Y1694093D03*
Y1698627D03*
X1280512Y1688391D03*
Y1693493D03*
Y1698030D03*
Y1683857D03*
X1272638Y1703729D03*
Y1708266D03*
Y1712800D03*
X1280512Y1707666D03*
Y1712203D03*
Y1702564D03*
X1272638Y1726974D03*
Y1722440D03*
Y1717903D03*
X1280512Y1730911D03*
Y1726377D03*
Y1721840D03*
Y1716737D03*
X1286792Y1578182D03*
X1298852D03*
X1291052D03*
X1286792Y1590094D03*
X1298852D03*
X1291052D03*
X1284292Y1602380D03*
Y1614292D03*
X1292092D03*
Y1602380D03*
X1296352D03*
Y1614292D03*
X1296260Y1679320D03*
X1288386Y1675383D03*
Y1679920D03*
X1296260Y1688391D03*
Y1693493D03*
Y1698030D03*
Y1683857D03*
X1288386Y1684454D03*
Y1689556D03*
Y1694093D03*
Y1698627D03*
X1296260Y1707666D03*
Y1712203D03*
Y1702564D03*
X1288386Y1703729D03*
Y1708266D03*
Y1712800D03*
X1296260Y1730911D03*
Y1726377D03*
Y1721840D03*
Y1716737D03*
X1288386Y1726974D03*
Y1722440D03*
Y1717903D03*
X1314353Y1124651D03*
X1303112Y1578182D03*
X1310912D03*
X1315172D03*
X1303112Y1590094D03*
X1310912D03*
X1315172D03*
X1304152Y1602380D03*
Y1614292D03*
X1308412Y1602380D03*
Y1614292D03*
X1308071Y1675383D03*
Y1679920D03*
Y1684454D03*
Y1689556D03*
Y1694093D03*
Y1698627D03*
Y1703729D03*
Y1708266D03*
Y1712800D03*
Y1726974D03*
Y1722440D03*
Y1717903D03*
X1328721Y854584D03*
X1323171Y870606D03*
Y889832D03*
X1319849Y1091513D03*
X1318053Y1124651D03*
X1321753Y1131060D03*
X1322972Y1578182D03*
X1327232D03*
X1322972Y1590094D03*
X1327232D03*
X1316212Y1614292D03*
Y1602380D03*
X1328272D03*
Y1614292D03*
X1320472Y1602380D03*
Y1614292D03*
X1323819Y1675383D03*
Y1679920D03*
X1315945Y1679320D03*
X1323819Y1684454D03*
Y1689556D03*
Y1694093D03*
Y1698627D03*
X1315945Y1688391D03*
Y1693493D03*
Y1698030D03*
Y1683857D03*
X1323819Y1703729D03*
Y1708266D03*
Y1712800D03*
X1315945Y1707666D03*
Y1712203D03*
Y1702564D03*
X1323819Y1726974D03*
Y1722440D03*
Y1717903D03*
X1315945Y1730911D03*
Y1726377D03*
Y1721840D03*
Y1716737D03*
X1336121Y880219D03*
Y899445D03*
X1347220D03*
X1336121Y918670D03*
X1341671Y941100D03*
X1336121Y937896D03*
X1347220D03*
X1345804Y1006093D03*
X1342104Y1076587D03*
X1335032Y1578182D03*
X1347092D03*
X1339292D03*
X1335032Y1590094D03*
X1347092D03*
X1339292D03*
X1340332Y1602380D03*
Y1614292D03*
X1332532Y1602380D03*
Y1614292D03*
X1344592Y1602380D03*
Y1614292D03*
X1339567Y1675383D03*
Y1679920D03*
X1331693Y1679320D03*
X1347441D03*
X1339567Y1684454D03*
Y1689556D03*
Y1694093D03*
Y1698627D03*
X1331693Y1688391D03*
Y1693493D03*
Y1698030D03*
Y1683857D03*
X1347441Y1688391D03*
Y1693493D03*
Y1698030D03*
Y1683857D03*
X1339567Y1703729D03*
Y1708266D03*
Y1712800D03*
X1331693Y1707666D03*
Y1712203D03*
Y1702564D03*
X1347441Y1707666D03*
Y1712203D03*
Y1702564D03*
X1339567Y1726974D03*
Y1722440D03*
Y1717903D03*
X1331693Y1730911D03*
Y1726377D03*
Y1721840D03*
Y1716737D03*
X1347441Y1730911D03*
Y1726377D03*
Y1721840D03*
Y1716737D03*
X1354620Y931488D03*
X1355053Y1060565D03*
X1351352Y1578182D03*
X1359152D03*
X1363412D03*
X1351352Y1590094D03*
X1359152D03*
X1363412D03*
X1352392Y1602380D03*
Y1614292D03*
X1356652Y1602380D03*
Y1614292D03*
X1363189Y1679320D03*
X1355315Y1675383D03*
Y1679920D03*
X1363189Y1688391D03*
Y1693493D03*
Y1698030D03*
Y1683857D03*
X1355315Y1684454D03*
Y1689556D03*
Y1694093D03*
Y1698627D03*
X1363189Y1707666D03*
Y1712203D03*
Y1702564D03*
X1355315Y1703729D03*
Y1708266D03*
Y1712800D03*
X1363189Y1730911D03*
Y1726377D03*
Y1721840D03*
Y1716737D03*
X1355315Y1726974D03*
Y1722440D03*
Y1717903D03*
X1373120Y899445D03*
Y931488D03*
Y937896D03*
X1371212Y1578088D03*
X1375472Y1578182D03*
X1371212Y1590094D03*
X1375472D03*
X1364452Y1602380D03*
Y1614292D03*
X1376512Y1602286D03*
Y1614292D03*
X1368712Y1602380D03*
Y1614292D03*
X1393716Y985579D03*
X1391326D03*
Y1014539D03*
X1393716D03*
X1393903Y1115039D03*
X1392053Y1118243D03*
X1390203Y1121447D03*
X1388353Y1124651D03*
Y1118243D03*
X1390204Y1134264D03*
X1388354Y1131060D03*
X1383272Y1578182D03*
Y1590094D03*
X1380772Y1602380D03*
Y1614292D03*
X1388572D03*
Y1602380D03*
X1411971Y851380D03*
Y864197D03*
Y877014D03*
Y889832D03*
Y902649D03*
X1404571Y921875D03*
X1410121Y944304D03*
Y957122D03*
Y950713D03*
Y963530D03*
Y976347D03*
Y969939D03*
Y982756D03*
X1410553Y1009297D03*
Y1002888D03*
Y1028523D03*
Y1022114D03*
Y1015705D03*
X1405004Y1044544D03*
X1410553Y1034931D03*
X1406854Y1047749D03*
X1399453D03*
X1408703Y1050952D03*
X1401304Y1057361D03*
X1410553Y1060565D03*
Y1054157D03*
X1408703Y1076587D03*
X1406853Y1073383D03*
X1403153D03*
Y1066974D03*
X1401304Y1076587D03*
X1399453Y1066974D03*
X1410553Y1073383D03*
Y1066974D03*
X1403154Y1079791D03*
X1410553D03*
X1408703Y1089404D03*
Y1082995D03*
X1405003D03*
X1401304Y1089404D03*
X1410553Y1092608D03*
Y1086200D03*
X1408703Y1095813D03*
X1405003D03*
X1403153Y1099017D03*
X1401303Y1102221D03*
X1399453Y1105426D03*
X1397604Y1108630D03*
X1410553Y1105426D03*
X1399453Y1111834D03*
X1410553D03*
X1399453Y1124651D03*
Y1118243D03*
X1397604Y1115039D03*
X1410553Y1124651D03*
Y1118243D03*
X1399454Y1137469D03*
X1399453Y1131060D03*
X1410554Y1137769D03*
X1410553Y1131060D03*
X1426771Y851380D03*
Y877014D03*
X1413820Y912262D03*
X1423070Y941100D03*
X1423071Y947509D03*
Y960326D03*
Y953917D03*
Y966735D03*
Y979552D03*
Y973143D03*
X1423503Y1006093D03*
Y999684D03*
Y1012501D03*
Y1025318D03*
Y1018910D03*
Y1031727D03*
X1429053Y1041340D03*
X1423503Y1038136D03*
X1429053Y1092608D03*
X1427204Y1089404D03*
X1427203Y1095812D03*
X1429053Y1099017D03*
X1423503Y1108630D03*
Y1102221D03*
Y1121447D03*
Y1115039D03*
Y1127856D03*
Y1134264D03*
X1432320Y912262D03*
X1437871Y921875D03*
X1438402Y942151D03*
X1440702D03*
X1443002D03*
X1430564Y949138D03*
X1440015Y956539D03*
X1430564Y951438D03*
X1442413Y956539D03*
X1430534Y963828D03*
Y966128D03*
X1440015Y971139D03*
X1442413Y971099D03*
X1430404Y981208D03*
Y978908D03*
X1440015Y985579D03*
X1430604Y995298D03*
Y992998D03*
X1442413Y985579D03*
X1440015Y1014539D03*
Y1000059D03*
X1430584Y1009408D03*
Y1007108D03*
X1442413Y1014539D03*
Y1000059D03*
X1436454Y1105426D03*
X1434604Y1102221D03*
X1432753Y1099017D03*
X1440154Y1105426D03*
X1438304Y1108630D03*
X1440154Y1111834D03*
X1434604Y1121447D03*
Y1115039D03*
X1443854Y1124651D03*
X1443853Y1118243D03*
X1442004Y1121447D03*
Y1115039D03*
X1434604Y1127856D03*
Y1134264D03*
X1450820Y899445D03*
Y912262D03*
X1445703Y1115039D03*
X1447553Y1118243D03*
X1445704Y1127856D03*
X1445703Y1140973D03*
X1447554Y1137469D03*
Y1131060D03*
X1460095Y1578182D03*
Y1590094D03*
X1465620Y912262D03*
X1471604Y1108630D03*
X1469753Y1111834D03*
X1472155Y1578182D03*
X1467895D03*
X1472155Y1590094D03*
X1467895D03*
X1477455Y1602380D03*
Y1614292D03*
X1473195D03*
Y1602380D03*
X1465395D03*
Y1614292D03*
X1484120Y937896D03*
X1485971Y947509D03*
X1491953Y1086200D03*
X1492015Y1578182D03*
X1484215D03*
X1479955D03*
X1492015Y1590094D03*
X1484215D03*
X1479955D03*
X1489515Y1614292D03*
Y1602380D03*
X1485255D03*
Y1614292D03*
X1508335Y1578182D03*
X1496275D03*
X1504075D03*
X1508335Y1590094D03*
X1496275D03*
X1504075D03*
X1501575Y1614292D03*
Y1602380D03*
X1509375D03*
Y1614292D03*
X1497315Y1602380D03*
Y1614292D03*
X1505315Y1675383D03*
Y1679920D03*
Y1684454D03*
Y1689556D03*
Y1694093D03*
Y1698627D03*
Y1703729D03*
Y1708266D03*
Y1712800D03*
Y1726974D03*
Y1722440D03*
Y1717903D03*
X1511871Y928283D03*
X1519271D03*
X1515571D03*
X1524820Y925079D03*
X1513720D03*
X1524820Y944304D03*
X1513720D03*
X1520395Y1578182D03*
X1516135D03*
X1520395Y1590094D03*
X1516135D03*
X1525695Y1614292D03*
Y1602380D03*
X1521435D03*
Y1614292D03*
X1513635D03*
Y1602380D03*
X1521063Y1675383D03*
Y1679920D03*
X1513189Y1679320D03*
X1521063Y1684454D03*
Y1689556D03*
Y1694093D03*
Y1698627D03*
X1513189Y1688391D03*
Y1693493D03*
Y1698030D03*
Y1683857D03*
X1521063Y1703729D03*
Y1708266D03*
Y1712800D03*
X1513189Y1707666D03*
Y1712203D03*
Y1702564D03*
X1521063Y1726974D03*
Y1722440D03*
Y1717903D03*
X1513189Y1730911D03*
Y1726377D03*
Y1721840D03*
Y1716737D03*
X1540255Y1578182D03*
X1532455D03*
X1528195D03*
X1540255Y1590094D03*
X1532455D03*
X1528195D03*
X1537755Y1614292D03*
Y1602380D03*
X1533495D03*
Y1614292D03*
X1536811Y1675383D03*
Y1679920D03*
X1528937Y1679320D03*
X1536811Y1684454D03*
Y1689556D03*
Y1694093D03*
Y1698627D03*
X1528937Y1688391D03*
Y1693493D03*
Y1698030D03*
Y1683857D03*
X1536811Y1703729D03*
Y1708266D03*
Y1712800D03*
X1528937Y1707666D03*
Y1712203D03*
Y1702564D03*
X1536811Y1726974D03*
Y1722440D03*
Y1717903D03*
X1528937Y1730911D03*
Y1726377D03*
Y1721840D03*
Y1716737D03*
X1556575Y1578182D03*
X1544515D03*
X1552315D03*
X1556575Y1590094D03*
X1544515D03*
X1552315D03*
X1549815Y1614292D03*
Y1602380D03*
X1557615D03*
Y1614292D03*
X1545555Y1602380D03*
Y1614292D03*
X1552559Y1675383D03*
Y1679920D03*
X1544685Y1679320D03*
X1552559Y1684454D03*
Y1689556D03*
Y1694093D03*
Y1698627D03*
X1544685Y1688391D03*
Y1693493D03*
Y1698030D03*
Y1683857D03*
X1552559Y1703729D03*
Y1708266D03*
Y1712800D03*
X1544685Y1707666D03*
Y1712203D03*
Y1702564D03*
X1552559Y1726974D03*
Y1722440D03*
Y1717903D03*
X1544685Y1730911D03*
Y1726377D03*
Y1721840D03*
Y1716737D03*
X1568635Y1578182D03*
X1564375D03*
X1568635Y1590094D03*
X1564375D03*
X1573935Y1614292D03*
Y1602380D03*
X1569675Y1614292D03*
Y1602380D03*
X1561875Y1614292D03*
Y1602380D03*
X1560433Y1679320D03*
X1572244Y1675383D03*
Y1679920D03*
X1560433Y1688391D03*
Y1693493D03*
Y1698030D03*
Y1683857D03*
X1572244Y1684454D03*
Y1689556D03*
Y1694093D03*
Y1698627D03*
X1560433Y1707666D03*
Y1712203D03*
Y1702564D03*
X1572244Y1703729D03*
Y1708266D03*
Y1712800D03*
X1560433Y1730911D03*
Y1726377D03*
Y1721840D03*
Y1716737D03*
X1572244Y1726974D03*
Y1722440D03*
Y1717903D03*
X1588495Y1578182D03*
X1580695D03*
X1576435D03*
X1588495Y1590094D03*
X1580695D03*
X1576435D03*
X1585995Y1614292D03*
Y1602380D03*
X1581735D03*
Y1614292D03*
X1587992Y1675383D03*
Y1679920D03*
X1580118Y1679320D03*
X1587992Y1684454D03*
Y1689556D03*
Y1694093D03*
Y1698627D03*
X1580118Y1688391D03*
Y1693493D03*
Y1698030D03*
Y1683857D03*
X1587992Y1703729D03*
Y1708266D03*
Y1712800D03*
X1580118Y1707666D03*
Y1712203D03*
Y1702564D03*
X1587992Y1726974D03*
Y1722440D03*
Y1717903D03*
X1580118Y1730911D03*
Y1726377D03*
Y1721840D03*
Y1716737D03*
X1597041Y770144D03*
X1605741D03*
Y776837D03*
X1597041D03*
X1605741Y783530D03*
X1597041D03*
X1605741Y793570D03*
X1597041D03*
X1596988Y800263D03*
X1605741D03*
X1595774Y806955D03*
X1606934D03*
X1596218Y813648D03*
X1606735D03*
X1597041Y820341D03*
X1605741D03*
X1597041Y830381D03*
X1605741D03*
Y837074D03*
X1597041D03*
Y843766D03*
X1605741D03*
X1596147Y850459D03*
X1606896D03*
X1596200Y857152D03*
X1606623D03*
X1597041Y867192D03*
X1605741D03*
X1597041Y873885D03*
X1605741D03*
X1597041Y880577D03*
X1605741D03*
X1597041Y887270D03*
X1605741D03*
X1606898Y893963D03*
X1597041D03*
X1605741Y904003D03*
X1597041D03*
Y917389D03*
X1605741D03*
X1597041Y910696D03*
X1605741D03*
X1597041Y924081D03*
X1605741D03*
X1606541Y930697D03*
X1596047Y930774D03*
X1596106Y940814D03*
X1606919D03*
X1605741Y947507D03*
X1597041D03*
X1605741Y954200D03*
X1597041D03*
Y964239D03*
X1605741D03*
X1597041Y977625D03*
X1605741D03*
Y970932D03*
X1597041D03*
Y984318D03*
X1605741D03*
X1597041Y991011D03*
X1605741D03*
X1597041Y1024475D03*
X1605741D03*
X1597041Y1017782D03*
X1605741D03*
X1597041Y1031168D03*
X1605741D03*
X1597041Y1037861D03*
X1605741D03*
X1597041Y1044554D03*
X1605741D03*
Y1051247D03*
X1597041D03*
Y1057940D03*
X1605741D03*
X1597041Y1064633D03*
X1605741D03*
X1606541Y1071326D03*
X1596141D03*
X1597041Y1078018D03*
X1605741D03*
Y1094751D03*
X1597041D03*
Y1088058D03*
X1605741D03*
Y1101444D03*
X1597041D03*
Y1108137D03*
X1605741D03*
X1606541Y1114829D03*
X1596241D03*
X1596511Y1124969D03*
X1606505Y1124674D03*
X1605741Y1138255D03*
X1597041D03*
X1605741Y1144948D03*
X1597041D03*
Y1131562D03*
X1605741D03*
Y1151641D03*
X1597041D03*
X1596653Y1161680D03*
X1605975Y1161581D03*
X1605741Y1168373D03*
X1597041D03*
X1605741Y1175066D03*
X1597041D03*
X1605741Y1181759D03*
X1597041D03*
X1606765Y1188452D03*
X1597041D03*
Y1198491D03*
X1605741D03*
Y1205184D03*
X1597041D03*
Y1211877D03*
X1605741D03*
X1597041Y1218570D03*
X1605741D03*
X1597041Y1225263D03*
X1605741D03*
X1607064Y1235302D03*
X1596178D03*
X1605741Y1241995D03*
X1597041D03*
Y1248688D03*
X1605741D03*
X1603788Y1273144D03*
X1601388D03*
X1604815Y1578182D03*
X1592755D03*
X1600555D03*
X1604815Y1590094D03*
X1592755D03*
X1600555D03*
X1598055Y1614292D03*
Y1602380D03*
X1605855Y1614292D03*
Y1602380D03*
X1593795Y1614292D03*
Y1602380D03*
X1603740Y1675383D03*
Y1679920D03*
X1595866Y1679320D03*
X1603740Y1684454D03*
Y1689556D03*
Y1694093D03*
Y1698627D03*
X1595866Y1688391D03*
Y1693493D03*
Y1698030D03*
Y1683857D03*
X1603740Y1703729D03*
Y1708266D03*
Y1712800D03*
X1595866Y1707666D03*
Y1712203D03*
Y1702564D03*
X1603740Y1726974D03*
Y1722440D03*
Y1717903D03*
X1595866Y1730911D03*
Y1726377D03*
Y1721840D03*
Y1716737D03*
X1613183Y766798D03*
X1621883D03*
Y773491D03*
X1613183D03*
X1621883Y780184D03*
X1613183D03*
X1621883Y790223D03*
X1613183D03*
Y796916D03*
X1621883D03*
X1613183Y803609D03*
X1621883D03*
X1622916Y816995D03*
X1613183D03*
X1612363Y810302D03*
X1622986D03*
X1613183Y827034D03*
X1621883D03*
Y833727D03*
X1613183D03*
Y840420D03*
X1621883D03*
X1613183Y847113D03*
X1621943D03*
X1622060Y863845D03*
X1612408D03*
X1612474Y853955D03*
X1622961Y853806D03*
X1621883Y883924D03*
X1613183D03*
Y870538D03*
X1621883D03*
X1613183Y877231D03*
X1621883D03*
X1613183Y890617D03*
X1621883D03*
X1613183Y900656D03*
X1621883D03*
Y907349D03*
X1613183D03*
Y914042D03*
X1621883D03*
Y920735D03*
X1613183D03*
X1622535Y927526D03*
X1612168Y927428D03*
X1622845Y937467D03*
X1612312D03*
X1621883Y944160D03*
X1613183D03*
X1621883Y950853D03*
X1613183D03*
X1621883Y960892D03*
X1613183D03*
Y974278D03*
X1621883D03*
X1613183Y980971D03*
X1621883D03*
X1613183Y967585D03*
X1621883D03*
X1613183Y987664D03*
X1621883D03*
Y1017782D03*
X1613183D03*
Y1027822D03*
X1621883D03*
X1613183Y1034515D03*
X1621883D03*
X1613183Y1041207D03*
X1621883D03*
X1613183Y1047900D03*
X1621883D03*
Y1054593D03*
X1613183D03*
Y1061286D03*
X1621883D03*
Y1067979D03*
X1612983D03*
X1612283Y1074672D03*
X1622683D03*
X1621883Y1084711D03*
X1612383D03*
X1613183Y1091404D03*
X1621883D03*
Y1104790D03*
X1613183D03*
X1621883Y1098097D03*
X1613183D03*
X1621883Y1111483D03*
X1613183D03*
Y1128915D03*
X1621883Y1128215D03*
X1613183Y1121522D03*
X1621883D03*
Y1141601D03*
X1613183D03*
X1622726Y1135108D03*
X1611886Y1134908D03*
X1621883Y1158333D03*
X1613183D03*
X1621883Y1148294D03*
X1613183D03*
X1621883Y1165026D03*
X1613183D03*
Y1171719D03*
X1621883D03*
Y1178412D03*
X1613183D03*
X1621883Y1185105D03*
X1613183D03*
Y1195144D03*
X1621883D03*
Y1201837D03*
X1613183D03*
X1621883Y1208530D03*
X1613183D03*
X1621883Y1215223D03*
X1613183D03*
X1612147Y1221916D03*
X1622712D03*
X1612137Y1231862D03*
X1622681Y1231955D03*
X1621883Y1238648D03*
X1613183D03*
X1610150Y1257172D03*
X1621883Y1245341D03*
X1613183D03*
X1618888Y1273344D03*
X1616088D03*
X1616875Y1578182D03*
X1612615D03*
X1616875Y1590094D03*
X1612615D03*
X1622175Y1614292D03*
Y1602380D03*
X1617915Y1614292D03*
Y1602380D03*
X1610115Y1614292D03*
Y1602380D03*
X1619488Y1675383D03*
Y1679920D03*
X1611614Y1679320D03*
X1619488Y1684454D03*
Y1689556D03*
Y1694093D03*
Y1698627D03*
X1611614Y1688391D03*
Y1693493D03*
Y1698030D03*
Y1683857D03*
X1619488Y1703729D03*
Y1708266D03*
Y1712800D03*
X1611614Y1707666D03*
Y1712203D03*
Y1702564D03*
X1619488Y1726974D03*
Y1722440D03*
Y1717903D03*
X1611614Y1730911D03*
Y1726377D03*
Y1721840D03*
Y1716737D03*
X1626741Y770144D03*
X1635441D03*
X1626741Y776837D03*
X1635441D03*
X1626741Y783530D03*
X1635441D03*
X1626741Y793570D03*
X1635441D03*
Y800263D03*
X1626741D03*
X1636341Y820341D03*
X1626741D03*
X1636574Y813648D03*
X1626741D03*
X1635441Y806955D03*
X1626741D03*
X1635441Y830381D03*
X1626741D03*
X1635441Y837074D03*
X1626741D03*
Y843766D03*
X1635441D03*
Y850459D03*
X1626741D03*
X1625705Y867192D03*
X1636441D03*
X1635441Y857152D03*
X1626741D03*
Y880577D03*
X1635441D03*
Y873885D03*
X1626741D03*
Y887270D03*
X1635441D03*
X1626741Y893963D03*
X1635441D03*
X1626741Y904003D03*
X1635441D03*
Y910696D03*
X1626741D03*
X1635441Y917389D03*
X1626741D03*
X1636316Y930774D03*
X1625803D03*
X1636646Y924081D03*
X1626741D03*
X1635441Y940814D03*
X1626741D03*
X1635441Y947507D03*
X1626741D03*
X1635441Y954200D03*
X1626741D03*
Y964239D03*
X1635441D03*
Y977625D03*
X1626741D03*
X1635441Y970932D03*
X1626741D03*
X1635441Y984318D03*
X1626741D03*
Y991011D03*
X1635441D03*
Y1024475D03*
X1626741D03*
X1635441Y1017782D03*
X1626741D03*
X1635441Y1031168D03*
X1626741D03*
X1635441Y1037861D03*
X1626741D03*
X1635441Y1044554D03*
X1626741D03*
Y1057940D03*
X1635441D03*
Y1051247D03*
X1626741D03*
X1635441Y1064633D03*
X1626741D03*
X1635441Y1071326D03*
X1626741D03*
X1636241Y1078018D03*
X1625941D03*
Y1088058D03*
X1636241D03*
X1635441Y1094751D03*
X1626741D03*
Y1101444D03*
X1635441D03*
X1626741Y1108137D03*
X1635441D03*
X1626074Y1124640D03*
X1636341Y1124869D03*
X1635441Y1114829D03*
X1626741D03*
X1635441Y1144948D03*
X1626741D03*
X1635441Y1138255D03*
X1626741D03*
X1635441Y1130762D03*
X1626741D03*
Y1161680D03*
X1635441D03*
Y1151641D03*
X1626741D03*
Y1168373D03*
X1635441D03*
X1626741Y1175066D03*
X1635441D03*
X1626741Y1181759D03*
X1635441D03*
X1626741Y1188452D03*
X1635441D03*
X1626741Y1198491D03*
X1635441D03*
X1626741Y1205184D03*
X1635441D03*
Y1211877D03*
X1626741D03*
X1635441Y1218570D03*
X1626741D03*
X1636212Y1225263D03*
X1626055D03*
X1636376Y1235302D03*
X1625843D03*
X1635441Y1241995D03*
X1626741D03*
X1635688Y1257664D03*
X1626741Y1248688D03*
X1635441D03*
X1629788Y1273344D03*
X1632588D03*
X1625729Y1266766D03*
X1636735Y1578088D03*
X1628935Y1578182D03*
X1624675D03*
X1636735Y1590094D03*
X1628935D03*
X1624675D03*
X1634235Y1614292D03*
Y1602380D03*
X1629975Y1614292D03*
Y1602380D03*
X1627362Y1679320D03*
Y1688391D03*
Y1693493D03*
Y1698030D03*
Y1683857D03*
Y1707666D03*
Y1712203D03*
Y1702564D03*
Y1730911D03*
Y1726377D03*
Y1721840D03*
Y1716737D03*
X1651583Y766798D03*
X1642883D03*
X1656441Y770144D03*
Y776837D03*
X1642883Y773491D03*
X1651583D03*
X1642883Y780184D03*
X1651583D03*
X1656441Y783530D03*
Y793570D03*
X1642883Y790223D03*
X1651583D03*
X1642883Y796916D03*
X1651583D03*
X1656441Y800263D03*
X1651583Y803609D03*
X1642883D03*
X1656441Y806955D03*
Y813648D03*
Y820341D03*
X1651583Y810302D03*
X1642883D03*
X1652545Y816995D03*
X1641945D03*
X1656441Y830381D03*
X1652767Y827034D03*
X1642018D03*
X1651583Y833727D03*
X1642883D03*
X1656441Y837074D03*
Y843766D03*
X1642883Y840420D03*
X1651583D03*
X1656441Y850459D03*
X1651583Y847113D03*
X1642883D03*
X1642058Y863845D03*
X1652742D03*
X1656441Y857152D03*
Y867192D03*
X1652559Y853806D03*
X1642032D03*
X1656441Y873885D03*
Y880577D03*
X1642883Y883924D03*
X1651583D03*
Y870538D03*
X1642883D03*
X1651583Y877231D03*
X1642883D03*
X1656441Y887270D03*
Y893963D03*
X1642883Y890617D03*
X1651583D03*
X1642883Y900656D03*
X1651583D03*
X1656441Y904003D03*
Y910696D03*
X1642883Y907349D03*
X1651583D03*
X1656441Y917389D03*
X1651583Y914042D03*
X1642883D03*
X1656441Y924081D03*
Y930774D03*
X1652630Y927428D03*
X1642038D03*
X1651583Y920735D03*
X1642883D03*
X1656441Y940814D03*
Y947507D03*
X1652501Y937467D03*
X1642065D03*
X1651583Y944160D03*
X1642883D03*
X1656441Y954200D03*
X1642883Y950853D03*
X1651583D03*
Y960892D03*
X1642883D03*
X1656441Y964239D03*
Y977625D03*
Y970932D03*
X1651583Y967585D03*
X1642883D03*
X1651583Y974278D03*
X1642883D03*
X1651583Y980971D03*
X1642883D03*
X1656441Y984318D03*
Y991011D03*
X1651583Y987664D03*
X1642883D03*
X1651583Y1017782D03*
X1642883D03*
X1656441D03*
Y1024475D03*
X1651583Y1027822D03*
X1642883D03*
X1656441Y1031168D03*
Y1044554D03*
Y1037861D03*
X1651583Y1034515D03*
X1642883D03*
X1651583Y1041207D03*
X1642883D03*
X1651583Y1047900D03*
X1642883D03*
Y1061286D03*
X1651583D03*
X1656441Y1051247D03*
Y1057940D03*
X1651583Y1054593D03*
X1642883D03*
X1656441Y1064633D03*
Y1071326D03*
Y1078018D03*
X1652483Y1074672D03*
X1641983D03*
X1651583Y1067979D03*
X1642883D03*
X1656441Y1088058D03*
Y1094751D03*
X1652383Y1084711D03*
X1642083D03*
X1651583Y1091404D03*
X1642883D03*
X1656441Y1101444D03*
Y1108137D03*
X1642883Y1098097D03*
X1651583D03*
X1642883Y1104790D03*
X1651583D03*
X1642883Y1111483D03*
X1651583D03*
X1656441Y1114829D03*
Y1124869D03*
X1642883Y1121522D03*
X1651583D03*
X1642883Y1128215D03*
X1651583D03*
X1656441Y1131562D03*
Y1138255D03*
X1642883Y1134908D03*
X1651583D03*
X1642883Y1141601D03*
X1651583D03*
X1656441Y1144948D03*
Y1151641D03*
Y1161680D03*
X1652383Y1158333D03*
X1642083D03*
X1652794Y1148294D03*
X1641744D03*
X1656441Y1168373D03*
Y1175066D03*
X1642883Y1171719D03*
X1651583D03*
Y1165026D03*
X1642883D03*
X1656441Y1181759D03*
Y1188452D03*
X1651583Y1178412D03*
X1642883D03*
X1651583Y1185105D03*
X1642883D03*
X1656441Y1198491D03*
Y1205184D03*
X1642883Y1195144D03*
X1651583D03*
X1642883Y1201837D03*
X1651583D03*
X1642883Y1208530D03*
X1651583D03*
X1656441Y1211877D03*
X1652590Y1221916D03*
X1641793D03*
X1656441Y1225263D03*
Y1218570D03*
X1651583Y1215223D03*
X1642883D03*
X1656441Y1235302D03*
Y1241995D03*
X1652604Y1231955D03*
X1642054D03*
X1651583Y1238648D03*
X1642883D03*
X1656441Y1248688D03*
X1651583Y1245341D03*
X1642883D03*
X1648588Y1273344D03*
X1645788D03*
X1640995Y1578182D03*
X1648795D03*
X1640995Y1590094D03*
X1648795D03*
X1646295Y1614292D03*
Y1602380D03*
X1654095Y1614292D03*
Y1602380D03*
X1642035Y1614292D03*
Y1602286D03*
X1665141Y770144D03*
X1672583Y766798D03*
X1665141Y776837D03*
Y783530D03*
X1672583Y773491D03*
Y780184D03*
X1665141Y793570D03*
Y800263D03*
X1672583Y790223D03*
Y796916D03*
Y803609D03*
X1665141Y806955D03*
Y813648D03*
X1666030Y820341D03*
X1672583Y810302D03*
Y816995D03*
X1665141Y830381D03*
X1672583Y827034D03*
Y833727D03*
X1665141Y837074D03*
Y843766D03*
X1672583Y840420D03*
X1665141Y850459D03*
X1672583Y847113D03*
X1666038Y857152D03*
X1665141Y867192D03*
X1672583Y853806D03*
Y863845D03*
X1665141Y873885D03*
Y880577D03*
X1672583Y870538D03*
Y877231D03*
Y883924D03*
X1665141Y887270D03*
Y893963D03*
X1672583Y890617D03*
Y900656D03*
X1665141Y904003D03*
Y910696D03*
Y917389D03*
X1672583Y907349D03*
Y914042D03*
X1665141Y924081D03*
X1666246Y930774D03*
X1672583Y920735D03*
Y927428D03*
X1665141Y940814D03*
Y947507D03*
X1672583Y937467D03*
Y944160D03*
X1665141Y954200D03*
Y964239D03*
X1672583Y950853D03*
Y960892D03*
X1665141Y977625D03*
Y970932D03*
X1672583Y967585D03*
Y974278D03*
Y980971D03*
X1665141Y984318D03*
Y991011D03*
X1672583Y987664D03*
X1665141Y1017782D03*
Y1024475D03*
Y1031168D03*
X1672583Y1017782D03*
Y1027822D03*
X1665141Y1044554D03*
Y1037861D03*
X1672583Y1034515D03*
Y1041207D03*
Y1047900D03*
X1665141Y1057940D03*
X1672583Y1061286D03*
Y1054593D03*
X1665141Y1064633D03*
Y1071326D03*
Y1077118D03*
X1672583Y1067979D03*
Y1074672D03*
X1665141Y1088058D03*
Y1094751D03*
X1672583Y1084711D03*
Y1091404D03*
X1665141Y1101444D03*
Y1108137D03*
X1672583Y1098097D03*
Y1104790D03*
Y1111483D03*
X1665141Y1114829D03*
Y1124869D03*
X1672583Y1121522D03*
Y1128215D03*
X1665141Y1131562D03*
Y1138255D03*
Y1144948D03*
X1672583Y1134908D03*
Y1141601D03*
X1666141Y1151641D03*
X1665141Y1161680D03*
X1672583Y1148294D03*
Y1158333D03*
X1665141Y1168373D03*
Y1175066D03*
X1672583Y1165026D03*
Y1171719D03*
X1665141Y1181759D03*
Y1188452D03*
X1672583Y1178412D03*
Y1185105D03*
X1665141Y1198491D03*
Y1205184D03*
X1672583Y1195144D03*
Y1201837D03*
Y1208530D03*
X1665141Y1211877D03*
X1665941Y1225263D03*
X1665141Y1218570D03*
X1672583Y1215223D03*
Y1221916D03*
X1665141Y1235302D03*
Y1241995D03*
X1672583Y1231955D03*
Y1238648D03*
X1665141Y1248688D03*
X1672583Y1245341D03*
X1665688Y1257964D03*
X1659488Y1273344D03*
X1662288D03*
X1681283Y766798D03*
X1686141Y770144D03*
X1681283Y773491D03*
Y780184D03*
X1686141Y776837D03*
Y783530D03*
X1681283Y790223D03*
Y796916D03*
Y803609D03*
X1686141Y793570D03*
Y800263D03*
X1681283Y810302D03*
Y816995D03*
X1686141Y806955D03*
Y813648D03*
Y820341D03*
X1681283Y827034D03*
Y833727D03*
X1686141Y830381D03*
X1681283Y840420D03*
X1686141Y837074D03*
Y843766D03*
Y850459D03*
X1681283Y847113D03*
X1686141Y857152D03*
Y867192D03*
X1681283Y853806D03*
Y863845D03*
X1686141Y873885D03*
Y880577D03*
X1681283Y870538D03*
Y877231D03*
Y883924D03*
X1686141Y887270D03*
Y893963D03*
X1681283Y890617D03*
Y900656D03*
X1686141Y904003D03*
Y910696D03*
Y917389D03*
X1681283Y907349D03*
Y914042D03*
X1686141Y924081D03*
Y930774D03*
X1681283Y920735D03*
Y927428D03*
X1686141Y940814D03*
Y947507D03*
X1681283Y937467D03*
Y944160D03*
X1686141Y954200D03*
Y964239D03*
X1681283Y950853D03*
Y960892D03*
X1686141Y970932D03*
Y977625D03*
X1681283Y967585D03*
Y974278D03*
Y980971D03*
X1686141Y984318D03*
Y991011D03*
X1681283Y987664D03*
X1686141Y1017782D03*
Y1024475D03*
Y1031168D03*
X1681283Y1017782D03*
Y1027822D03*
X1686141Y1037861D03*
Y1044554D03*
X1681283Y1034515D03*
Y1041207D03*
Y1047900D03*
X1686141Y1051247D03*
Y1057940D03*
X1681283Y1061286D03*
Y1054593D03*
X1686141Y1064633D03*
Y1071326D03*
Y1078018D03*
X1681283Y1067979D03*
Y1074672D03*
X1686141Y1088058D03*
Y1094751D03*
X1681283Y1084711D03*
Y1091404D03*
X1686141Y1101444D03*
Y1108137D03*
X1681283Y1098097D03*
Y1104790D03*
Y1111483D03*
X1686141Y1114829D03*
Y1124869D03*
X1681283Y1121522D03*
Y1128215D03*
X1686141Y1131562D03*
Y1138255D03*
Y1144948D03*
X1681283Y1134908D03*
Y1141601D03*
X1686141Y1151641D03*
Y1161680D03*
X1681283Y1148294D03*
Y1158333D03*
X1686141Y1168373D03*
Y1175066D03*
X1681283Y1165026D03*
Y1171719D03*
X1686141Y1181759D03*
Y1188452D03*
X1681283Y1178412D03*
Y1185105D03*
X1686141Y1198491D03*
Y1205184D03*
X1681283Y1195144D03*
Y1201837D03*
Y1208530D03*
X1686141Y1211877D03*
Y1218570D03*
Y1225263D03*
X1681283Y1215223D03*
Y1221916D03*
Y1231955D03*
Y1238648D03*
X1686141Y1235302D03*
Y1241995D03*
X1681283Y1245341D03*
X1686141Y1248688D03*
X1675488Y1273344D03*
X1678288D03*
X1689188D03*
X1694841Y770144D03*
X1702283Y766798D03*
X1694841Y776837D03*
Y783530D03*
X1702283Y773491D03*
Y780184D03*
X1694841Y793570D03*
Y800263D03*
X1702283Y790223D03*
Y796916D03*
Y803609D03*
X1694841Y806955D03*
Y813648D03*
Y820341D03*
X1702283Y810302D03*
Y816995D03*
X1694841Y830381D03*
X1702283Y827034D03*
Y833727D03*
X1694841Y837074D03*
Y843766D03*
Y850459D03*
X1702283Y840420D03*
Y847113D03*
X1694841Y857152D03*
Y867192D03*
X1702283Y853806D03*
Y863845D03*
X1694841Y873885D03*
Y880577D03*
X1702283Y870538D03*
Y877231D03*
Y883924D03*
X1694841Y887270D03*
Y893963D03*
X1702283Y890617D03*
Y900656D03*
X1694841Y904003D03*
Y910696D03*
Y917389D03*
X1702283Y907349D03*
Y914042D03*
X1694841Y924081D03*
Y930774D03*
X1702283Y920735D03*
Y927428D03*
X1694841Y940814D03*
Y947507D03*
X1702283Y937467D03*
Y944160D03*
X1694841Y954200D03*
Y964239D03*
X1702283Y950853D03*
Y960892D03*
X1694841Y970932D03*
Y977625D03*
X1702283Y967585D03*
Y974278D03*
Y980971D03*
X1694841Y984318D03*
Y991011D03*
X1702283Y987664D03*
X1694841Y1017782D03*
Y1024475D03*
Y1031168D03*
X1702283Y1017782D03*
Y1027822D03*
X1694841Y1037861D03*
Y1044554D03*
X1702283Y1034515D03*
Y1041207D03*
Y1047900D03*
X1694841Y1051247D03*
Y1057940D03*
X1702283Y1054593D03*
Y1061286D03*
X1694841Y1064633D03*
Y1071326D03*
Y1078018D03*
X1702283Y1067979D03*
Y1074672D03*
X1694841Y1088058D03*
Y1094751D03*
X1702283Y1084711D03*
Y1091404D03*
X1694841Y1101444D03*
Y1108137D03*
X1702283Y1098097D03*
Y1104790D03*
Y1111483D03*
X1694841Y1114829D03*
Y1124869D03*
X1702283Y1121522D03*
Y1128215D03*
X1694841Y1131562D03*
Y1138255D03*
Y1144948D03*
X1702283Y1134908D03*
Y1141601D03*
X1694841Y1151641D03*
Y1161680D03*
X1702283Y1148294D03*
Y1158333D03*
X1694841Y1168373D03*
Y1175066D03*
X1702283Y1165026D03*
Y1171719D03*
X1694841Y1181759D03*
Y1188452D03*
X1702283Y1178412D03*
Y1185105D03*
X1694841Y1198491D03*
Y1205184D03*
X1702283Y1195144D03*
Y1201837D03*
Y1208530D03*
X1694841Y1211877D03*
Y1218570D03*
Y1225263D03*
X1702283Y1215223D03*
Y1221916D03*
X1694841Y1235302D03*
Y1241995D03*
X1702283Y1231955D03*
Y1238648D03*
X1694841Y1248688D03*
X1695188Y1257064D03*
X1702283Y1245341D03*
X1691988Y1273344D03*
X1705188D03*
X1710983Y766798D03*
X1715841Y770144D03*
X1710983Y773491D03*
Y780184D03*
X1715841Y783530D03*
Y776837D03*
X1710983Y790223D03*
Y796916D03*
Y803609D03*
X1715841Y793570D03*
Y800263D03*
X1710983Y810302D03*
Y816995D03*
X1715841Y806955D03*
Y813648D03*
Y820341D03*
X1710983Y827034D03*
Y833727D03*
X1715841Y830381D03*
X1710983Y840420D03*
Y847113D03*
X1715841Y837074D03*
Y843766D03*
Y850459D03*
X1710983Y853806D03*
Y863845D03*
X1715841Y857152D03*
Y867192D03*
X1710983Y870538D03*
Y877231D03*
Y883924D03*
X1715841Y873885D03*
Y880577D03*
X1710983Y890617D03*
Y900656D03*
X1715841Y893963D03*
Y887270D03*
X1710983Y907349D03*
Y914042D03*
X1715841Y904003D03*
Y910696D03*
Y917389D03*
X1710983Y920735D03*
Y927428D03*
X1715841Y924081D03*
Y930774D03*
X1710983Y937467D03*
Y944160D03*
X1715841Y940814D03*
Y947507D03*
X1710983Y950853D03*
Y960892D03*
X1715841Y954200D03*
Y964239D03*
X1710983Y967585D03*
Y974278D03*
Y980971D03*
X1715841Y970932D03*
Y977625D03*
X1710983Y987664D03*
X1715841Y984318D03*
Y991011D03*
X1710983Y1017782D03*
Y1027822D03*
X1715841Y1017782D03*
Y1024475D03*
Y1031168D03*
X1710983Y1034515D03*
Y1041207D03*
Y1047900D03*
X1715841Y1037861D03*
Y1044554D03*
X1710983Y1054593D03*
Y1061286D03*
X1715841Y1051247D03*
Y1057940D03*
X1710983Y1067979D03*
Y1074672D03*
X1715841Y1071326D03*
Y1064633D03*
Y1078018D03*
X1710983Y1084711D03*
Y1091404D03*
X1715841Y1088058D03*
Y1094751D03*
X1710983Y1098097D03*
Y1104790D03*
Y1111483D03*
X1715841Y1101444D03*
Y1108137D03*
X1710983Y1121522D03*
Y1128215D03*
X1715841Y1114829D03*
Y1124869D03*
X1710983Y1134908D03*
Y1141601D03*
X1715841Y1131562D03*
Y1138255D03*
Y1144948D03*
X1710983Y1148294D03*
Y1158333D03*
X1715841Y1151641D03*
Y1161680D03*
X1710983Y1165026D03*
Y1171719D03*
X1715841Y1168373D03*
Y1175066D03*
X1710983Y1178412D03*
Y1185105D03*
X1715841Y1181759D03*
Y1188452D03*
X1710983Y1195144D03*
Y1201837D03*
Y1208530D03*
X1715841Y1198491D03*
Y1205184D03*
X1710983Y1215223D03*
Y1221916D03*
X1715841Y1211877D03*
Y1218570D03*
Y1225263D03*
X1710983Y1231955D03*
Y1238648D03*
X1715841Y1235302D03*
Y1241995D03*
X1710983Y1245341D03*
X1715841Y1248688D03*
X1707514Y1273444D03*
X1718888Y1273344D03*
X1721688D03*
X1731983Y766798D03*
X1724541Y770144D03*
X1731983Y773491D03*
Y780184D03*
X1724541Y783530D03*
Y776837D03*
Y793570D03*
Y800263D03*
X1731983Y790223D03*
Y796916D03*
Y803609D03*
X1724541Y806955D03*
Y813648D03*
Y820341D03*
X1731983Y810302D03*
Y816995D03*
X1724541Y830381D03*
X1731983Y827034D03*
Y833727D03*
X1724541Y837074D03*
Y843766D03*
Y850459D03*
X1731983Y840420D03*
Y847113D03*
X1724541Y857152D03*
Y867192D03*
X1731983Y853806D03*
Y863845D03*
X1724541Y873885D03*
Y880577D03*
X1731983Y870538D03*
Y877231D03*
Y883924D03*
X1724541Y893963D03*
Y887270D03*
X1731983Y890617D03*
Y900656D03*
X1724541Y904003D03*
Y910696D03*
Y917389D03*
X1731983Y907349D03*
Y914042D03*
X1724541Y924081D03*
Y930774D03*
X1731983Y920735D03*
Y927428D03*
X1724541Y940814D03*
Y947507D03*
X1731983Y937467D03*
Y944160D03*
X1724541Y954200D03*
Y964239D03*
X1731983Y950853D03*
Y960892D03*
X1724541Y970932D03*
Y977625D03*
X1731983Y967585D03*
Y974278D03*
Y980971D03*
X1724541Y984318D03*
Y991011D03*
X1731983Y987664D03*
X1724541Y1017782D03*
Y1024475D03*
Y1031168D03*
X1731983Y1017782D03*
Y1027822D03*
X1724541Y1037861D03*
Y1044554D03*
X1731983Y1034515D03*
Y1041207D03*
Y1047900D03*
X1724541Y1057940D03*
X1731983Y1054593D03*
Y1061286D03*
X1724541Y1071326D03*
Y1064633D03*
Y1078018D03*
X1731983Y1074672D03*
Y1067979D03*
X1724541Y1088058D03*
Y1094751D03*
X1731983Y1084711D03*
Y1091404D03*
X1724541Y1101444D03*
Y1108137D03*
X1731983Y1098097D03*
Y1104790D03*
Y1111483D03*
X1724541Y1114829D03*
Y1124869D03*
X1731983Y1121522D03*
Y1128215D03*
X1724541Y1131562D03*
Y1138255D03*
Y1144948D03*
X1731983Y1134908D03*
Y1141601D03*
X1724541Y1151641D03*
Y1161680D03*
X1731983Y1148294D03*
Y1158333D03*
X1724541Y1168373D03*
Y1175066D03*
X1731983Y1165026D03*
Y1171719D03*
X1724541Y1181759D03*
Y1188452D03*
X1731983Y1178412D03*
Y1185105D03*
X1724541Y1198491D03*
Y1205184D03*
X1731983Y1195144D03*
Y1201837D03*
Y1208530D03*
X1724541Y1211877D03*
Y1218570D03*
Y1225263D03*
X1731983Y1215223D03*
Y1221916D03*
X1724541Y1235302D03*
Y1241995D03*
X1731983Y1231955D03*
Y1238648D03*
X1724541Y1248688D03*
X1724588Y1257164D03*
X1731983Y1245341D03*
X1734888Y1273344D03*
X1737688D03*
X1740683Y766798D03*
X1745541Y770144D03*
X1754241D03*
X1740683Y773491D03*
Y780184D03*
X1745541Y776837D03*
X1754241D03*
X1745541Y783530D03*
X1754241D03*
X1740683Y790223D03*
Y796916D03*
Y803609D03*
X1745541Y793570D03*
X1754241D03*
X1745541Y800263D03*
X1754241D03*
X1740683Y810302D03*
Y816995D03*
X1745541Y806955D03*
X1754241D03*
X1745541Y813648D03*
X1754241D03*
X1745541Y820341D03*
X1754241D03*
X1740683Y827034D03*
Y833727D03*
X1745541Y830381D03*
X1754241D03*
X1740683Y840420D03*
Y847113D03*
X1754241Y843766D03*
X1745541D03*
Y837074D03*
X1754241D03*
X1745541Y850459D03*
X1754241D03*
X1740683Y853806D03*
Y863845D03*
X1745541Y857152D03*
X1754241D03*
Y867192D03*
X1745541D03*
X1740683Y870538D03*
Y877231D03*
Y883924D03*
X1745541Y873885D03*
X1754241D03*
X1745541Y880577D03*
X1754241D03*
X1740683Y890617D03*
Y900656D03*
X1754241Y893963D03*
X1745541D03*
Y887270D03*
X1754241D03*
X1740683Y907349D03*
Y914042D03*
X1754241Y904003D03*
X1745541D03*
X1754241Y910696D03*
X1745541D03*
X1754241Y917389D03*
X1745541D03*
X1740683Y920735D03*
Y927428D03*
X1754241Y924081D03*
X1745541D03*
X1754241Y930774D03*
X1745541D03*
X1740683Y937467D03*
Y944160D03*
X1754241Y940814D03*
X1745541D03*
X1754241Y947507D03*
X1745541D03*
X1740683Y950853D03*
Y960892D03*
X1754241Y954200D03*
X1745541D03*
X1754241Y964239D03*
X1745541D03*
X1740683Y967585D03*
Y974278D03*
Y980971D03*
X1754241Y970932D03*
X1745541D03*
X1754241Y977625D03*
X1745541D03*
X1740683Y987664D03*
X1754241Y984318D03*
X1745541D03*
X1754241Y991011D03*
X1745541D03*
X1740683Y1017782D03*
Y1027822D03*
X1754241Y1017782D03*
X1745541D03*
Y1024475D03*
X1754241D03*
X1745541Y1031168D03*
X1754241D03*
X1740683Y1034515D03*
Y1041207D03*
Y1047900D03*
X1754241Y1044554D03*
X1745541D03*
Y1037861D03*
X1754241D03*
X1740683Y1054593D03*
Y1061286D03*
X1745541Y1051247D03*
X1754241D03*
X1745541Y1057940D03*
X1754241D03*
X1740683Y1074672D03*
Y1067979D03*
X1754241Y1071326D03*
X1745541D03*
Y1064633D03*
X1754241D03*
Y1078018D03*
X1745541D03*
X1740683Y1084711D03*
Y1091404D03*
X1754241Y1088058D03*
X1745541D03*
X1754241Y1094751D03*
X1745541D03*
X1740683Y1098097D03*
Y1104790D03*
Y1111483D03*
X1754241Y1101444D03*
X1745541D03*
X1754241Y1108137D03*
X1745541D03*
X1740683Y1121522D03*
Y1128215D03*
X1754241Y1114829D03*
X1745541D03*
X1754241Y1124869D03*
X1745541D03*
X1740683Y1134908D03*
Y1141601D03*
X1754241Y1131562D03*
X1745541D03*
X1754241Y1138255D03*
X1745541D03*
X1754241Y1144948D03*
X1745541D03*
X1740683Y1148294D03*
Y1158333D03*
X1754241Y1151641D03*
X1745541D03*
X1754241Y1161680D03*
X1745541D03*
X1740683Y1165026D03*
Y1171719D03*
X1745541Y1175066D03*
X1754241D03*
Y1168373D03*
X1745541D03*
X1740683Y1178412D03*
Y1185105D03*
X1745541Y1181759D03*
X1754241D03*
Y1188452D03*
X1745541D03*
X1740683Y1195144D03*
Y1201837D03*
Y1208530D03*
X1754241Y1198491D03*
X1745541D03*
X1754241Y1205184D03*
X1745541D03*
X1740683Y1215223D03*
Y1221916D03*
X1754241Y1211877D03*
X1745541D03*
X1754241Y1218570D03*
X1745541D03*
X1754241Y1225263D03*
X1745541D03*
X1740683Y1231955D03*
Y1238648D03*
X1754241Y1235302D03*
X1745541D03*
X1754241Y1241995D03*
X1745541D03*
X1740683Y1245341D03*
X1754241Y1248688D03*
X1745541D03*
X1754488Y1257264D03*
X1751388Y1273344D03*
X1748588D03*
X1749088Y1310474D03*
X1746288D03*
X1770383Y766798D03*
X1761683D03*
X1770383Y773491D03*
X1761683D03*
Y780184D03*
X1770383D03*
X1761683Y790223D03*
X1770383D03*
X1761683Y796916D03*
X1770383D03*
X1761683Y803609D03*
X1770383D03*
X1761683Y810302D03*
X1770383D03*
X1761683Y816995D03*
X1770383D03*
X1761683Y827034D03*
X1770383D03*
X1761683Y833727D03*
X1770383D03*
X1761683Y840420D03*
X1770383D03*
X1761683Y847113D03*
X1770383D03*
X1761683Y853806D03*
X1770383D03*
X1761683Y863845D03*
X1770383D03*
X1761683Y870538D03*
X1770383D03*
X1761683Y877231D03*
X1770383D03*
X1761683Y883924D03*
X1770383D03*
X1761683Y890617D03*
X1770383D03*
X1761683Y900656D03*
X1770383D03*
X1761683Y907349D03*
X1770383D03*
X1761683Y914042D03*
X1770383D03*
Y927428D03*
X1761683D03*
Y920735D03*
X1770383D03*
X1761683Y937467D03*
X1770383D03*
X1761683Y944160D03*
X1770383D03*
X1761683Y950853D03*
X1770383D03*
X1761683Y960892D03*
X1770383D03*
X1761683Y967585D03*
X1770383D03*
X1761683Y974278D03*
X1770383D03*
X1761683Y980971D03*
X1770383D03*
X1761683Y987664D03*
X1770383D03*
X1761683Y1017782D03*
X1770383D03*
X1761683Y1027822D03*
X1770383D03*
X1761683Y1034515D03*
X1770383D03*
X1761683Y1041207D03*
X1770383D03*
X1761683Y1047900D03*
X1770383D03*
X1761683Y1054593D03*
X1770383D03*
X1761683Y1061286D03*
X1770383D03*
X1761683Y1067979D03*
X1770383D03*
X1761683Y1074672D03*
X1770383D03*
X1761683Y1084711D03*
X1770383D03*
X1761683Y1091404D03*
X1770383D03*
Y1098097D03*
X1761683D03*
Y1104790D03*
X1770383D03*
X1761683Y1111483D03*
X1770383D03*
X1761683Y1121522D03*
X1770383D03*
X1761683Y1128215D03*
X1770383D03*
X1761683Y1134908D03*
X1770383D03*
X1761683Y1141601D03*
X1770383D03*
X1761683Y1148294D03*
X1770383D03*
X1761683Y1158333D03*
X1770383D03*
X1761683Y1165026D03*
X1770383D03*
X1761683Y1171719D03*
X1770383D03*
X1761683Y1178412D03*
X1770383D03*
X1761683Y1185105D03*
X1770383D03*
X1761683Y1195144D03*
X1770383D03*
X1761683Y1201837D03*
X1770383D03*
X1761683Y1208530D03*
X1770383D03*
X1761683Y1215223D03*
X1770383D03*
X1761683Y1221916D03*
X1770383D03*
X1761683Y1231955D03*
X1770383D03*
X1761683Y1238648D03*
X1770383D03*
X1761683Y1245341D03*
X1770383D03*
X1767388Y1273344D03*
X1764588D03*
X1775241Y770144D03*
X1783941D03*
X1775241Y776837D03*
X1783941D03*
X1775241Y783530D03*
X1783941D03*
X1775241Y793570D03*
X1783941D03*
X1775241Y800263D03*
X1783941D03*
X1775241Y806955D03*
X1783941D03*
X1775241Y813648D03*
X1783941D03*
X1775241Y820341D03*
X1783941D03*
Y830381D03*
X1775241D03*
Y837074D03*
X1783941D03*
X1775241Y843766D03*
X1783941D03*
X1775241Y850459D03*
X1783941D03*
X1775241Y857152D03*
X1783941D03*
X1775241Y867192D03*
X1783941D03*
X1775241Y873885D03*
X1783941D03*
X1775241Y880577D03*
X1783941D03*
X1775241Y887270D03*
X1783941D03*
X1775241Y893963D03*
X1783941D03*
X1775241Y904003D03*
X1783941D03*
X1775241Y910696D03*
X1783941D03*
X1775241Y917389D03*
X1783941D03*
X1775241Y924081D03*
X1783941D03*
X1775241Y930774D03*
X1783941D03*
X1775241Y940814D03*
X1783941D03*
X1775241Y947507D03*
X1783941D03*
X1775241Y954200D03*
X1783941D03*
X1775241Y964239D03*
X1783941D03*
X1775241Y970932D03*
X1783941D03*
X1775241Y977625D03*
X1783941D03*
X1775241Y984318D03*
X1783941D03*
X1775241Y991011D03*
X1783941D03*
X1775241Y1017782D03*
X1783941D03*
X1775241Y1024475D03*
X1783941D03*
X1775241Y1031168D03*
X1783941D03*
X1775241Y1037861D03*
X1783941D03*
X1775241Y1044554D03*
X1783941D03*
X1775241Y1051247D03*
X1783941D03*
X1775241Y1057940D03*
X1783941D03*
X1775241Y1064633D03*
X1783941D03*
X1775241Y1071326D03*
X1783941D03*
X1775241Y1078018D03*
X1783941D03*
X1775241Y1088058D03*
X1783941D03*
X1775241Y1094751D03*
X1783941D03*
X1775241Y1101444D03*
X1783941D03*
X1775241Y1108137D03*
X1783941D03*
X1775241Y1114829D03*
X1783941D03*
X1775241Y1124869D03*
X1783941D03*
X1775241Y1131562D03*
X1783941D03*
X1775241Y1138255D03*
X1783941D03*
X1775241Y1144948D03*
X1783941D03*
Y1151641D03*
X1775241D03*
Y1161680D03*
X1783941D03*
X1775241Y1168373D03*
X1783941D03*
X1775241Y1175066D03*
X1783941D03*
X1775241Y1181759D03*
X1783941D03*
X1775241Y1188452D03*
X1783941D03*
X1775241Y1198491D03*
X1783941D03*
X1775241Y1205184D03*
X1783941D03*
X1775241Y1211877D03*
X1783941D03*
X1775241Y1218570D03*
X1783941D03*
X1775241Y1225263D03*
X1783941D03*
X1775241Y1235302D03*
X1783941D03*
X1775241Y1241995D03*
X1783941D03*
X1784188Y1257664D03*
X1775241Y1248688D03*
X1783941D03*
X1781088Y1273344D03*
X1778288D03*
X1791383Y766798D03*
X1800083D03*
X1791383Y773491D03*
X1800083D03*
X1791383Y780184D03*
X1800083D03*
X1791383Y790223D03*
X1800083D03*
X1791383Y796916D03*
X1800083D03*
X1791383Y803609D03*
X1800083D03*
X1791383Y810302D03*
X1800083D03*
X1791383Y816995D03*
X1800083D03*
X1791383Y827034D03*
X1800083D03*
Y833727D03*
X1791383D03*
Y840420D03*
X1800083D03*
X1791383Y847113D03*
X1800083D03*
X1791383Y853806D03*
X1800083D03*
X1791383Y863845D03*
X1800083D03*
X1791383Y870538D03*
X1800083D03*
X1791383Y877231D03*
X1800083D03*
X1791383Y883924D03*
X1800083D03*
X1791383Y890617D03*
X1800083D03*
X1791383Y900656D03*
X1800083D03*
X1791383Y907349D03*
X1800083D03*
X1791383Y914042D03*
X1800083D03*
X1791383Y920735D03*
X1800083D03*
X1791383Y927428D03*
X1800083D03*
X1791383Y937467D03*
X1800083D03*
X1791383Y944160D03*
X1800083D03*
Y950853D03*
X1791383D03*
Y960892D03*
X1800083D03*
X1791383Y967585D03*
X1800083D03*
X1791383Y974278D03*
X1800083D03*
X1791383Y980971D03*
X1800083D03*
X1791383Y987664D03*
X1800083D03*
X1791383Y1017782D03*
X1800083D03*
X1791383Y1027822D03*
X1800083D03*
X1791383Y1034515D03*
X1800083D03*
X1791383Y1041207D03*
X1800083D03*
X1791383Y1047900D03*
X1800083D03*
X1791383Y1054593D03*
X1800083D03*
X1791383Y1061286D03*
X1800083D03*
X1791383Y1067979D03*
X1800083D03*
X1791383Y1074672D03*
X1800083D03*
X1791383Y1084711D03*
X1800083D03*
X1791383Y1091404D03*
X1800083D03*
X1791383Y1098097D03*
X1800083D03*
X1791383Y1104790D03*
X1800083D03*
X1791383Y1111483D03*
X1800083D03*
X1791383Y1121522D03*
X1800083D03*
X1791383Y1128215D03*
X1800083D03*
Y1134908D03*
X1791383D03*
Y1141601D03*
X1800083D03*
X1791383Y1148294D03*
X1800083D03*
X1791383Y1158333D03*
X1800083D03*
X1791383Y1165026D03*
X1800083D03*
X1791383Y1171719D03*
X1800083D03*
X1791383Y1178412D03*
X1800083D03*
X1791383Y1185105D03*
X1800083D03*
X1791383Y1195144D03*
X1800083D03*
X1791383Y1201837D03*
X1800083D03*
X1791383Y1208530D03*
X1800083D03*
X1791383Y1215223D03*
X1800083D03*
X1791383Y1221916D03*
X1800083D03*
X1791383Y1231955D03*
X1800083D03*
X1791383Y1238648D03*
X1800083D03*
X1791383Y1245341D03*
X1800083D03*
X1797088Y1273344D03*
X1794288D03*
X1804941Y770144D03*
X1813641D03*
X1804941Y776837D03*
X1813641D03*
X1804941Y783530D03*
X1813641D03*
X1804941Y793570D03*
X1813641D03*
X1804941Y800263D03*
X1813641D03*
X1804941Y806955D03*
X1813641D03*
X1804941Y813648D03*
X1813641D03*
X1804941Y820341D03*
X1813641D03*
X1804941Y830381D03*
X1813641D03*
X1804941Y843766D03*
X1813641D03*
X1804941Y837074D03*
X1813641D03*
X1804941Y850459D03*
X1813641D03*
X1804941Y857152D03*
X1813641D03*
Y867192D03*
X1804941D03*
Y873885D03*
X1813641D03*
X1804941Y880577D03*
X1813641D03*
X1804941Y887270D03*
X1813641D03*
X1804941Y893963D03*
X1813641D03*
X1804941Y904003D03*
X1813641D03*
X1804941Y910696D03*
X1813641D03*
X1804941Y917389D03*
X1813641D03*
X1804941Y924081D03*
X1813641D03*
X1804941Y930774D03*
X1813641D03*
X1804941Y940814D03*
X1813641D03*
X1804941Y947507D03*
X1813641D03*
X1804941Y954200D03*
X1813641D03*
X1804941Y964239D03*
X1813641D03*
X1804941Y970932D03*
X1813641D03*
X1804941Y977625D03*
X1813641D03*
X1804941Y984318D03*
X1813641D03*
X1804941Y991011D03*
X1813641D03*
X1804941Y1017782D03*
X1813641D03*
X1804941Y1024475D03*
X1813641D03*
X1804941Y1031168D03*
X1813641D03*
X1804941Y1037861D03*
X1813641D03*
X1804941Y1044554D03*
X1813641D03*
Y1057940D03*
X1804941D03*
Y1051247D03*
X1813641D03*
X1804941Y1064633D03*
X1813641D03*
Y1071326D03*
X1804941D03*
X1813641Y1078018D03*
X1804941D03*
X1813641Y1088058D03*
X1804941D03*
X1813641Y1094751D03*
X1804941D03*
X1813641Y1101444D03*
X1804941D03*
X1813641Y1108137D03*
X1804941D03*
X1813641Y1114829D03*
X1804941D03*
X1813641Y1124869D03*
X1804941D03*
X1813641Y1131562D03*
X1804941D03*
X1813641Y1138255D03*
X1804941D03*
X1813641Y1144948D03*
X1804941D03*
X1813641Y1151641D03*
X1804941D03*
X1813641Y1161680D03*
X1804941D03*
X1813641Y1168373D03*
X1804941D03*
X1813641Y1175066D03*
X1804941D03*
X1813641Y1181759D03*
X1804941D03*
X1813641Y1188452D03*
X1804941D03*
X1813641Y1198491D03*
X1804941D03*
X1813641Y1205184D03*
X1804941D03*
X1813641Y1211877D03*
X1804941D03*
X1813641Y1218570D03*
X1804941D03*
X1813641Y1225263D03*
X1804941D03*
X1813641Y1235302D03*
X1804941D03*
X1813641Y1241995D03*
X1804941D03*
X1813641Y1248688D03*
X1804941D03*
X1819054Y1253986D03*
X1818188Y1273044D03*
X1810788Y1273344D03*
X1807988D03*
X1815388Y1273044D03*
X1829783Y766798D03*
X1821083D03*
X1829783Y773491D03*
X1821083D03*
X1829783Y780184D03*
X1821083D03*
X1829783Y790223D03*
X1821083D03*
X1829783Y796916D03*
X1821083D03*
X1829783Y803609D03*
X1821083D03*
X1829783Y810302D03*
X1821083D03*
X1829783Y816995D03*
X1821083D03*
X1829783Y827034D03*
X1821083D03*
X1829783Y833727D03*
X1821083D03*
Y847113D03*
X1829783D03*
Y840420D03*
X1821083D03*
X1829783Y853806D03*
X1821083D03*
X1829783Y863845D03*
X1821083D03*
X1829783Y870538D03*
X1821083D03*
X1829783Y877231D03*
X1821083D03*
X1829783Y883924D03*
X1821083D03*
X1829783Y890617D03*
X1821083D03*
X1829783Y900656D03*
X1821083D03*
X1829783Y907349D03*
X1821083D03*
X1829783Y914042D03*
X1821083D03*
X1829783Y920735D03*
X1821083D03*
X1829783Y927428D03*
X1821083D03*
X1829783Y937467D03*
X1821083D03*
X1829783Y944160D03*
X1821083D03*
X1829783Y950853D03*
X1821083D03*
X1829783Y960892D03*
X1821083D03*
X1829783Y967585D03*
X1821083D03*
X1829783Y974278D03*
X1821083D03*
X1829783Y980971D03*
X1821083D03*
X1829783Y987664D03*
X1821083D03*
X1829783Y1017782D03*
X1821083D03*
X1829783Y1027822D03*
X1821083D03*
X1829783Y1034515D03*
X1821083D03*
X1829783Y1041207D03*
X1821083D03*
X1829783Y1047900D03*
X1821083D03*
X1829783Y1054593D03*
X1821083D03*
X1829783Y1061286D03*
X1821083D03*
X1829783Y1067979D03*
X1821083D03*
Y1074672D03*
X1829783D03*
X1821083Y1084711D03*
X1829783D03*
X1821083Y1091404D03*
X1829783D03*
X1821083Y1098097D03*
X1829783D03*
X1821083Y1104790D03*
X1829783D03*
X1821083Y1111483D03*
X1829783D03*
X1821083Y1121522D03*
X1829783D03*
X1821083Y1128215D03*
X1829783D03*
X1821083Y1134908D03*
X1829783D03*
X1821083Y1141601D03*
X1829783D03*
X1821083Y1148294D03*
X1829783D03*
X1821083Y1158333D03*
X1829783D03*
X1821083Y1165026D03*
X1829783D03*
X1821083Y1171719D03*
X1829783D03*
X1821083Y1178412D03*
X1829783D03*
X1821083Y1185105D03*
X1829783D03*
X1821083Y1195144D03*
X1829783D03*
X1821083Y1201837D03*
X1829783D03*
X1821083Y1208530D03*
X1829783D03*
X1821083Y1215223D03*
X1829783D03*
X1821083Y1221916D03*
X1829783D03*
X1821083Y1231955D03*
X1829783D03*
X1821083Y1238648D03*
X1829783D03*
Y1245341D03*
X1821083D03*
G54D57*
X841240Y1420330D03*
X1016240D03*
G54D63*
X986642Y-27947D03*
X986627Y-25432D03*
Y-21558D03*
X986642Y-17918D03*
X986627Y-15403D03*
Y-11529D03*
X986642Y-7889D03*
X986627Y-5374D03*
Y4655D03*
X986642Y2140D03*
X986627Y14684D03*
X986642Y12169D03*
X986627Y8529D03*
X986642Y22698D03*
X989910Y22684D03*
X986627Y19058D03*
Y25213D03*
X989895Y25199D03*
X1296019Y-35472D03*
Y-31598D03*
X1296034Y-37987D03*
Y-27958D03*
X1296019Y-25443D03*
Y-21569D03*
X1296034Y-17929D03*
X1296019Y-15414D03*
Y-11540D03*
X1296034Y-7900D03*
X1296019Y-5385D03*
Y4644D03*
X1296034Y2129D03*
X1296019Y-1511D03*
Y14673D03*
X1296034Y12158D03*
X1296019Y8518D03*
X1296034Y22687D03*
X1296019Y19047D03*
Y25202D03*
X1299302Y22673D03*
X1299287Y25188D03*
X1488393Y-27958D03*
X1488378Y-25443D03*
X1488393Y-37987D03*
X1488378Y-35472D03*
Y-31598D03*
X1488393Y-17929D03*
X1488378Y-15414D03*
Y-11540D03*
Y-21569D03*
X1488393Y2129D03*
X1488378Y4644D03*
X1488393Y-7900D03*
X1488378Y-5385D03*
Y-1511D03*
Y14673D03*
X1488393Y12158D03*
Y22687D03*
X1491661Y22673D03*
X1488378Y8518D03*
Y19047D03*
Y25202D03*
X1491646Y25188D03*
G54D71*
X1879155Y344948D03*
Y592848D03*
X1900275Y-19342D03*
X1889155Y344948D03*
Y592848D03*
X1900275Y716808D03*
X1910275Y-19342D03*
Y716808D03*
X1931395Y592868D03*
X1921395D03*
X1952395Y-19152D03*
X1942395D03*
X1963362Y593010D03*
X1984482Y-19180D03*
X1973362Y593010D03*
X1994482Y-19180D03*
X2015452Y593020D03*
X2005452D03*
X2026452Y-19000D03*
X2036452D03*
X2047419Y593162D03*
X2057419D03*
G54D24*
X57646Y12480D03*
X137272D03*
X186622D03*
X266858D03*
X315598D03*
X502528Y33268D03*
X582154D03*
X631504D03*
X711740D03*
X760480D03*
X1532055Y12480D03*
X1611681D03*
X1661031D03*
X1741267D03*
X1790007D03*
G54D64*
X1077638Y133866D03*
G54D46*
X460000Y278543D03*
G54D69*
X1771457Y1634646D03*
G54D58*
X900196Y175197D03*
X944684Y155216D03*
G54D78*
X1903086Y1318228D03*
X1902402Y1683256D03*
X1950484Y1683497D03*
X1993147Y1682875D03*
G54D76*
X1880836Y1317164D03*
X1881165Y1682207D03*
X1929695Y1683220D03*
X1971555Y1683130D03*
%LPC*%
G75*
G54D79*
G01X-6350Y-464479D02*
Y-539479D01*
X493650D01*
Y-464479D01*
X-6350D01*
G01X5650Y-529479D02*
Y-534479D01*
G01X4193Y-529479D02*
X7107D01*
G01X12017Y-534479D02*
X9483D01*
Y-529479D01*
X12017D01*
G01X11003Y-531896D02*
X9483D01*
G01X14583Y-529479D02*
Y-534479D01*
X17117D01*
G01X20950Y-534646D02*
X20823Y-534562D01*
Y-534396D01*
X20950Y-534312D01*
X21077Y-534396D01*
Y-534562D01*
X20950Y-534646D01*
G01Y-532396D02*
X20823Y-532312D01*
Y-532146D01*
X20950Y-532062D01*
X21077Y-532146D01*
Y-532312D01*
X20950Y-532396D01*
G01X25733Y-536146D02*
X25100Y-535312D01*
X24783Y-534479D01*
Y-531146D01*
X25100Y-530312D01*
X25733Y-529479D01*
G01X31150D02*
X30643Y-529646D01*
X30263Y-530062D01*
X30010Y-530562D01*
X29820Y-531229D01*
X29757Y-531979D01*
X29820Y-532729D01*
X30010Y-533396D01*
X30263Y-533896D01*
X30643Y-534312D01*
X31150Y-534479D01*
X31657Y-534312D01*
X32037Y-533896D01*
X32290Y-533396D01*
X32480Y-532729D01*
X32543Y-531979D01*
X32480Y-531229D01*
X32290Y-530562D01*
X32037Y-530062D01*
X31657Y-529646D01*
X31150Y-529479D01*
G01X34857Y-533479D02*
X35237Y-534062D01*
X35743Y-534396D01*
X36313Y-534479D01*
X36820Y-534396D01*
X37327Y-533979D01*
X37643Y-533479D01*
X37707Y-532979D01*
X37580Y-532396D01*
X37137Y-531979D01*
X36693Y-531812D01*
X36123D01*
G01X36693D02*
X37073Y-531562D01*
X37390Y-531146D01*
X37517Y-530646D01*
X37390Y-530146D01*
X37073Y-529729D01*
X36503Y-529479D01*
X35933Y-529562D01*
X35363Y-529896D01*
G01X41667Y-536146D02*
X42300Y-535312D01*
X42617Y-534479D01*
Y-531146D01*
X42300Y-530312D01*
X41667Y-529479D01*
G01X45057Y-533479D02*
X45437Y-534062D01*
X45943Y-534396D01*
X46513Y-534479D01*
X47020Y-534396D01*
X47527Y-533979D01*
X47843Y-533479D01*
X47907Y-532979D01*
X47780Y-532396D01*
X47337Y-531979D01*
X46893Y-531812D01*
X46323D01*
G01X46893D02*
X47273Y-531562D01*
X47590Y-531146D01*
X47717Y-530646D01*
X47590Y-530146D01*
X47273Y-529729D01*
X46703Y-529479D01*
X46133Y-529562D01*
X45563Y-529896D01*
G01X50347Y-530312D02*
X50727Y-529812D01*
X51170Y-529562D01*
X51677Y-529479D01*
X52310Y-529646D01*
X52753Y-530062D01*
X52880Y-530562D01*
X52817Y-531062D01*
X52563Y-531479D01*
X51297Y-532312D01*
X50727Y-532896D01*
X50347Y-533729D01*
X50220Y-534479D01*
X52880D01*
G01X56523D02*
X56650Y-533396D01*
X56840Y-532479D01*
X57093Y-531646D01*
X57410Y-530729D01*
X57917Y-529479D01*
X55383D01*
G01X60927Y-532812D02*
X62573D01*
G01X65647Y-530312D02*
X66027Y-529812D01*
X66470Y-529562D01*
X66977Y-529479D01*
X67610Y-529646D01*
X68053Y-530062D01*
X68180Y-530562D01*
X68117Y-531062D01*
X67863Y-531479D01*
X66597Y-532312D01*
X66027Y-532896D01*
X65647Y-533729D01*
X65520Y-534479D01*
X68180D01*
G01X70557Y-533479D02*
X70937Y-534062D01*
X71443Y-534396D01*
X72013Y-534479D01*
X72520Y-534396D01*
X73027Y-533979D01*
X73343Y-533479D01*
X73407Y-532979D01*
X73280Y-532396D01*
X72837Y-531979D01*
X72393Y-531812D01*
X71823D01*
G01X72393D02*
X72773Y-531562D01*
X73090Y-531146D01*
X73217Y-530646D01*
X73090Y-530146D01*
X72773Y-529729D01*
X72203Y-529479D01*
X71633Y-529562D01*
X71063Y-529896D01*
G01X77810Y-534479D02*
Y-529479D01*
X75467Y-533062D01*
X78633D01*
G01X80757Y-533729D02*
X81137Y-534146D01*
X81580Y-534396D01*
X82150Y-534479D01*
X82720Y-534312D01*
X83163Y-533979D01*
X83480Y-533396D01*
X83543Y-532729D01*
X83417Y-532062D01*
X83100Y-531646D01*
X82657Y-531312D01*
X82213Y-531229D01*
X81770Y-531312D01*
X81200Y-531646D01*
X81390Y-529479D01*
X83100D01*
G01X91147Y-534479D02*
Y-529479D01*
X93553D01*
G01X92667Y-531896D02*
X91147D01*
G01X95867Y-534479D02*
X97450Y-529479D01*
X99033Y-534479D01*
G01X98463Y-532729D02*
X96437D01*
G01X101220Y-534479D02*
X103880Y-529479D01*
G01X101220D02*
X103880Y-534479D01*
G01X107650Y-534646D02*
X107523Y-534562D01*
Y-534396D01*
X107650Y-534312D01*
X107777Y-534396D01*
Y-534562D01*
X107650Y-534646D01*
G01Y-532396D02*
X107523Y-532312D01*
Y-532146D01*
X107650Y-532062D01*
X107777Y-532146D01*
Y-532312D01*
X107650Y-532396D01*
G01X112433Y-536146D02*
X111800Y-535312D01*
X111483Y-534479D01*
Y-531146D01*
X111800Y-530312D01*
X112433Y-529479D01*
G01X117850D02*
X117343Y-529646D01*
X116963Y-530062D01*
X116710Y-530562D01*
X116520Y-531229D01*
X116457Y-531979D01*
X116520Y-532729D01*
X116710Y-533396D01*
X116963Y-533896D01*
X117343Y-534312D01*
X117850Y-534479D01*
X118357Y-534312D01*
X118737Y-533896D01*
X118990Y-533396D01*
X119180Y-532729D01*
X119243Y-531979D01*
X119180Y-531229D01*
X118990Y-530562D01*
X118737Y-530062D01*
X118357Y-529646D01*
X117850Y-529479D01*
G01X121557Y-533479D02*
X121937Y-534062D01*
X122443Y-534396D01*
X123013Y-534479D01*
X123520Y-534396D01*
X124027Y-533979D01*
X124343Y-533479D01*
X124407Y-532979D01*
X124280Y-532396D01*
X123837Y-531979D01*
X123393Y-531812D01*
X122823D01*
G01X123393D02*
X123773Y-531562D01*
X124090Y-531146D01*
X124217Y-530646D01*
X124090Y-530146D01*
X123773Y-529729D01*
X123203Y-529479D01*
X122633Y-529562D01*
X122063Y-529896D01*
G01X128367Y-536146D02*
X129000Y-535312D01*
X129317Y-534479D01*
Y-531146D01*
X129000Y-530312D01*
X128367Y-529479D01*
G01X131757Y-533479D02*
X132137Y-534062D01*
X132643Y-534396D01*
X133213Y-534479D01*
X133720Y-534396D01*
X134227Y-533979D01*
X134543Y-533479D01*
X134607Y-532979D01*
X134480Y-532396D01*
X134037Y-531979D01*
X133593Y-531812D01*
X133023D01*
G01X133593D02*
X133973Y-531562D01*
X134290Y-531146D01*
X134417Y-530646D01*
X134290Y-530146D01*
X133973Y-529729D01*
X133403Y-529479D01*
X132833Y-529562D01*
X132263Y-529896D01*
G01X137173Y-533896D02*
X137617Y-534312D01*
X138123Y-534479D01*
X138630Y-534312D01*
X139073Y-533812D01*
X139390Y-533062D01*
X139517Y-532312D01*
Y-531396D01*
X139390Y-530646D01*
X139073Y-529979D01*
X138693Y-529646D01*
X138250Y-529479D01*
X137743Y-529646D01*
X137363Y-529979D01*
X137110Y-530479D01*
X136983Y-531146D01*
X137110Y-531729D01*
X137427Y-532312D01*
X137807Y-532646D01*
X138250Y-532729D01*
X138757Y-532562D01*
X139137Y-532146D01*
X139517Y-531396D01*
G01X143223Y-534479D02*
X143350Y-533396D01*
X143540Y-532479D01*
X143793Y-531646D01*
X144110Y-530729D01*
X144617Y-529479D01*
X142083D01*
G01X147627Y-532812D02*
X149273D01*
G01X152157Y-533479D02*
X152537Y-534062D01*
X153043Y-534396D01*
X153613Y-534479D01*
X154120Y-534396D01*
X154627Y-533979D01*
X154943Y-533479D01*
X155007Y-532979D01*
X154880Y-532396D01*
X154437Y-531979D01*
X153993Y-531812D01*
X153423D01*
G01X153993D02*
X154373Y-531562D01*
X154690Y-531146D01*
X154817Y-530646D01*
X154690Y-530146D01*
X154373Y-529729D01*
X153803Y-529479D01*
X153233Y-529562D01*
X152663Y-529896D01*
G01X157447Y-532396D02*
X157890Y-531812D01*
X158270Y-531479D01*
X158777Y-531312D01*
X159220Y-531479D01*
X159537Y-531812D01*
X159790Y-532312D01*
X159853Y-532896D01*
X159790Y-533396D01*
X159537Y-533896D01*
X159157Y-534312D01*
X158713Y-534479D01*
X158207Y-534312D01*
X157763Y-533812D01*
X157510Y-533062D01*
X157447Y-532229D01*
X157573Y-531146D01*
X157763Y-530562D01*
X158080Y-529979D01*
X158523Y-529562D01*
X158967Y-529479D01*
X159410Y-529646D01*
X159727Y-530062D01*
G01X163750Y-534479D02*
Y-529479D01*
X162990Y-530479D01*
G01Y-534479D02*
X164510D01*
G01X169610D02*
Y-529479D01*
X167267Y-533062D01*
X170433D01*
G01X188650Y-464479D02*
Y-539479D01*
G01Y-514479D02*
X291650D01*
Y-489479D01*
G01X188650D02*
X291650D01*
G01Y-464479D02*
Y-539479D01*
G01X293650Y-464479D02*
Y-539479D01*
G01X299157Y-524479D02*
Y-519479D01*
X300423D01*
X300930Y-519729D01*
X301310Y-520062D01*
X301627Y-520562D01*
X301880Y-521146D01*
X301943Y-521979D01*
X301880Y-522812D01*
X301627Y-523396D01*
X301310Y-523896D01*
X300930Y-524229D01*
X300423Y-524479D01*
X299157D01*
G01X304067D02*
X305650Y-519479D01*
X307233Y-524479D01*
G01X306663Y-522729D02*
X304637D01*
G01X310750Y-519479D02*
Y-524479D01*
G01X309293Y-519479D02*
X312207D01*
G01X317117Y-524479D02*
X314583D01*
Y-519479D01*
X317117D01*
G01X316103Y-521896D02*
X314583D01*
G01X320950Y-524646D02*
X320823Y-524562D01*
Y-524396D01*
X320950Y-524312D01*
X321077Y-524396D01*
Y-524562D01*
X320950Y-524646D01*
G01Y-522396D02*
X320823Y-522312D01*
Y-522146D01*
X320950Y-522062D01*
X321077Y-522146D01*
Y-522312D01*
X320950Y-522396D01*
G01X299283Y-499479D02*
Y-494479D01*
X300803D01*
X301310Y-494729D01*
X301690Y-495312D01*
X301817Y-495979D01*
X301690Y-496646D01*
X301373Y-497146D01*
X300803Y-497396D01*
X299283D01*
G01X304510Y-499646D02*
X306790Y-494479D01*
G01X309293Y-499479D02*
Y-494479D01*
X312207Y-499479D01*
Y-494479D01*
G01X315850Y-499646D02*
X315723Y-499562D01*
Y-499396D01*
X315850Y-499312D01*
X315977Y-499396D01*
Y-499562D01*
X315850Y-499646D01*
G01Y-497396D02*
X315723Y-497312D01*
Y-497146D01*
X315850Y-497062D01*
X315977Y-497146D01*
Y-497312D01*
X315850Y-497396D01*
G01X293650Y-514479D02*
X493650D01*
G01X293650Y-489479D02*
X493650D01*
G01X299283Y-474479D02*
Y-469479D01*
X300803D01*
X301310Y-469729D01*
X301690Y-470312D01*
X301817Y-470979D01*
X301690Y-471646D01*
X301373Y-472146D01*
X300803Y-472396D01*
X299283D01*
G01X304383Y-474479D02*
Y-469479D01*
X305967D01*
X306473Y-469729D01*
X306790Y-470062D01*
X306917Y-470729D01*
X306790Y-471396D01*
X306410Y-471812D01*
X305967Y-472062D01*
X304383D01*
G01X305967D02*
X306917Y-474479D01*
G01X310750D02*
X310243Y-474396D01*
X309800Y-474062D01*
X309420Y-473562D01*
X309167Y-472979D01*
X309040Y-472312D01*
Y-471646D01*
X309167Y-470979D01*
X309420Y-470396D01*
X309800Y-469896D01*
X310243Y-469562D01*
X310750Y-469479D01*
X311257Y-469562D01*
X311700Y-469896D01*
X312080Y-470396D01*
X312333Y-470979D01*
X312460Y-471646D01*
Y-472312D01*
X312333Y-472979D01*
X312080Y-473562D01*
X311700Y-474062D01*
X311257Y-474396D01*
X310750Y-474479D01*
G01X314583Y-473479D02*
X314900Y-473979D01*
X315280Y-474312D01*
X315723Y-474479D01*
X316230Y-474312D01*
X316610Y-473979D01*
X316990Y-473479D01*
X317117Y-472812D01*
Y-469479D01*
G01X322217Y-474479D02*
X319683D01*
Y-469479D01*
X322217D01*
G01X321203Y-471896D02*
X319683D01*
G01X327443Y-469896D02*
X327063Y-469646D01*
X326620Y-469479D01*
X326113D01*
X325543Y-469729D01*
X325100Y-470146D01*
X324783Y-470646D01*
X324530Y-471479D01*
X324467Y-472229D01*
X324593Y-472979D01*
X324783Y-473479D01*
X325163Y-473979D01*
X325607Y-474312D01*
X326050Y-474479D01*
X326493D01*
X326937Y-474312D01*
X327317Y-474062D01*
X327633Y-473729D01*
G01X331150Y-469479D02*
Y-474479D01*
G01X329693Y-469479D02*
X332607D01*
G01X336250Y-474646D02*
X336123Y-474562D01*
Y-474396D01*
X336250Y-474312D01*
X336377Y-474396D01*
Y-474562D01*
X336250Y-474646D01*
G01Y-472396D02*
X336123Y-472312D01*
Y-472146D01*
X336250Y-472062D01*
X336377Y-472146D01*
Y-472312D01*
X336250Y-472396D01*
G01X408650Y-514479D02*
Y-539479D01*
G01X411283Y-516979D02*
Y-521979D01*
X413817D01*
G01X416890Y-516979D02*
X418410D01*
G01X417650D02*
Y-521979D01*
G01X416890D02*
X418410D01*
G01X423257Y-519312D02*
X423510Y-519062D01*
X423700Y-518646D01*
X423827Y-518062D01*
X423700Y-517562D01*
X423447Y-517229D01*
X423003Y-516979D01*
X421293D01*
Y-521979D01*
X423383D01*
X423827Y-521646D01*
X424080Y-521146D01*
X424207Y-520562D01*
X424080Y-519979D01*
X423700Y-519479D01*
X423257Y-519312D01*
X421293D01*
G01X427850Y-522146D02*
X427723Y-522062D01*
Y-521896D01*
X427850Y-521812D01*
X427977Y-521896D01*
Y-522062D01*
X427850Y-522146D01*
G01Y-519896D02*
X427723Y-519812D01*
Y-519646D01*
X427850Y-519562D01*
X427977Y-519646D01*
Y-519812D01*
X427850Y-519896D01*
G01X451650Y-514479D02*
Y-539479D01*
G01Y-489479D02*
Y-514479D01*
G01X456663Y-541646D02*
X456770Y-541521D01*
X456850Y-541312D01*
X456903Y-541021D01*
X456850Y-540771D01*
X456743Y-540604D01*
X456557Y-540479D01*
X455837D01*
Y-542979D01*
X456717D01*
X456903Y-542812D01*
X457010Y-542562D01*
X457063Y-542271D01*
X457010Y-541979D01*
X456850Y-541729D01*
X456663Y-541646D01*
X455837D01*
G01X459130Y-542979D02*
Y-541312D01*
G01Y-541604D02*
X459023Y-541437D01*
X458863Y-541354D01*
X458677Y-541312D01*
X458490Y-541396D01*
X458330Y-541562D01*
X458223Y-541812D01*
X458170Y-542146D01*
X458223Y-542479D01*
X458330Y-542729D01*
X458490Y-542896D01*
X458677Y-542979D01*
X458863Y-542937D01*
X459023Y-542812D01*
X459130Y-542646D01*
G01X460450Y-542687D02*
X460583Y-542854D01*
X460770Y-542979D01*
X460930D01*
X461090Y-542896D01*
X461197Y-542771D01*
X461250Y-542604D01*
X461223Y-542354D01*
X461117Y-542229D01*
X460637Y-541979D01*
X460530Y-541687D01*
X460583Y-541479D01*
X460690Y-541354D01*
X460850Y-541312D01*
X461010Y-541354D01*
X461170Y-541479D01*
G01X462650Y-541854D02*
X463503D01*
X463423Y-541562D01*
X463290Y-541396D01*
X463103Y-541312D01*
X462917Y-541354D01*
X462757Y-541479D01*
X462650Y-541771D01*
X462597Y-542021D01*
Y-542271D01*
X462650Y-542521D01*
X462783Y-542771D01*
X462943Y-542937D01*
X463130Y-542979D01*
X463317Y-542896D01*
X463503Y-542646D01*
G01X464770Y-542979D02*
Y-540479D01*
G01Y-541729D02*
X464903Y-541479D01*
X465063Y-541354D01*
X465223Y-541312D01*
X465463Y-541396D01*
X465623Y-541562D01*
X465730Y-541854D01*
Y-542187D01*
X465677Y-542521D01*
X465570Y-542771D01*
X465383Y-542937D01*
X465223Y-542979D01*
X465063Y-542937D01*
X464903Y-542812D01*
X464770Y-542604D01*
G01X467450Y-542979D02*
X467290Y-542937D01*
X467130Y-542771D01*
X467023Y-542479D01*
X466970Y-542146D01*
X467023Y-541812D01*
X467130Y-541521D01*
X467290Y-541354D01*
X467450Y-541312D01*
X467610Y-541354D01*
X467770Y-541521D01*
X467877Y-541812D01*
X467903Y-542146D01*
X467877Y-542479D01*
X467770Y-542771D01*
X467610Y-542937D01*
X467450Y-542979D01*
G01X470130D02*
Y-541312D01*
G01Y-541604D02*
X470023Y-541437D01*
X469863Y-541354D01*
X469677Y-541312D01*
X469490Y-541396D01*
X469330Y-541562D01*
X469223Y-541812D01*
X469170Y-542146D01*
X469223Y-542479D01*
X469330Y-542729D01*
X469490Y-542896D01*
X469677Y-542979D01*
X469863Y-542937D01*
X470023Y-542812D01*
X470130Y-542646D01*
G01X471477Y-542979D02*
Y-541312D01*
G01Y-541646D02*
X471610Y-541479D01*
X471743Y-541354D01*
X471930Y-541312D01*
X472063Y-541354D01*
X472223Y-541479D01*
G01X474530Y-540479D02*
Y-542979D01*
G01Y-542604D02*
X474423Y-542812D01*
X474263Y-542937D01*
X474077Y-542979D01*
X473863Y-542896D01*
X473703Y-542687D01*
X473597Y-542437D01*
X473570Y-542146D01*
X473597Y-541854D01*
X473703Y-541604D01*
X473863Y-541396D01*
X474077Y-541312D01*
X474263Y-541354D01*
X474397Y-541437D01*
X474530Y-541604D01*
G01X477917Y-542979D02*
Y-540479D01*
X478583D01*
X478797Y-540604D01*
X478930Y-540771D01*
X478983Y-541104D01*
X478930Y-541437D01*
X478770Y-541646D01*
X478583Y-541771D01*
X477917D01*
G01X478583D02*
X478983Y-542979D01*
G01X480250Y-541854D02*
X481103D01*
X481023Y-541562D01*
X480890Y-541396D01*
X480703Y-541312D01*
X480517Y-541354D01*
X480357Y-541479D01*
X480250Y-541771D01*
X480197Y-542021D01*
Y-542271D01*
X480250Y-542521D01*
X480383Y-542771D01*
X480543Y-542937D01*
X480730Y-542979D01*
X480917Y-542896D01*
X481103Y-542646D01*
G01X482370Y-541312D02*
X482850Y-542979D01*
X483330Y-541312D01*
G01X485050Y-543062D02*
X484997Y-543021D01*
Y-542937D01*
X485050Y-542896D01*
X485103Y-542937D01*
Y-543021D01*
X485050Y-543062D01*
G01X487250Y-542979D02*
X487437Y-542937D01*
X487650Y-542812D01*
X487783Y-542604D01*
X487837Y-542312D01*
X487783Y-542021D01*
X487623Y-541771D01*
X487383Y-541646D01*
X487117D01*
X486957Y-541562D01*
X486823Y-541354D01*
X486770Y-541062D01*
X486850Y-540771D01*
X487037Y-540562D01*
X487250Y-540479D01*
X487463Y-540562D01*
X487650Y-540771D01*
X487730Y-541062D01*
X487677Y-541354D01*
X487543Y-541562D01*
X487383Y-541646D01*
X487117D01*
X486877Y-541771D01*
X486717Y-542021D01*
X486663Y-542312D01*
X486717Y-542604D01*
X486850Y-542812D01*
X487063Y-542937D01*
X487250Y-542979D01*
G01X489663Y-541646D02*
X489770Y-541521D01*
X489850Y-541312D01*
X489903Y-541021D01*
X489850Y-540771D01*
X489743Y-540604D01*
X489557Y-540479D01*
X488837D01*
Y-542979D01*
X489717D01*
X489903Y-542812D01*
X490010Y-542562D01*
X490063Y-542271D01*
X490010Y-541979D01*
X489850Y-541729D01*
X489663Y-541646D01*
X488837D01*
G01X455550Y-516979D02*
Y-521979D01*
G01X454093Y-516979D02*
X457007D01*
G01X460650Y-521979D02*
X460270Y-521896D01*
X459890Y-521562D01*
X459637Y-520979D01*
X459510Y-520312D01*
X459637Y-519646D01*
X459890Y-519062D01*
X460270Y-518729D01*
X460650Y-518646D01*
X461030Y-518729D01*
X461410Y-519062D01*
X461663Y-519646D01*
X461727Y-520312D01*
X461663Y-520979D01*
X461410Y-521562D01*
X461030Y-521896D01*
X460650Y-521979D01*
G01X465750D02*
X465370Y-521896D01*
X464990Y-521562D01*
X464737Y-520979D01*
X464610Y-520312D01*
X464737Y-519646D01*
X464990Y-519062D01*
X465370Y-518729D01*
X465750Y-518646D01*
X466130Y-518729D01*
X466510Y-519062D01*
X466763Y-519646D01*
X466827Y-520312D01*
X466763Y-520979D01*
X466510Y-521562D01*
X466130Y-521896D01*
X465750Y-521979D01*
G01X470850D02*
Y-516979D01*
G01X475950Y-522146D02*
X475823Y-522062D01*
Y-521896D01*
X475950Y-521812D01*
X476077Y-521896D01*
Y-522062D01*
X475950Y-522146D01*
G01Y-519896D02*
X475823Y-519812D01*
Y-519646D01*
X475950Y-519562D01*
X476077Y-519646D01*
Y-519812D01*
X475950Y-519896D01*
G01X454283Y-496979D02*
Y-491979D01*
X455867D01*
X456373Y-492229D01*
X456690Y-492562D01*
X456817Y-493229D01*
X456690Y-493896D01*
X456310Y-494312D01*
X455867Y-494562D01*
X454283D01*
G01X455867D02*
X456817Y-496979D01*
G01X461917D02*
X459383D01*
Y-491979D01*
X461917D01*
G01X460903Y-494396D02*
X459383D01*
G01X464167Y-491979D02*
X465750Y-496979D01*
X467333Y-491979D01*
G01X470850Y-497146D02*
X470723Y-497062D01*
Y-496896D01*
X470850Y-496812D01*
X470977Y-496896D01*
Y-497062D01*
X470850Y-497146D01*
G01Y-494896D02*
X470723Y-494812D01*
Y-494646D01*
X470850Y-494562D01*
X470977Y-494646D01*
Y-494812D01*
X470850Y-494896D01*
G01X-984580Y-698988D02*
Y4193602D01*
X5868320D01*
Y-698988D01*
X-984580D01*
G01X7723Y-521204D02*
X7253Y-520889D01*
X6705Y-520679D01*
X6078D01*
X5373Y-520994D01*
X4825Y-521519D01*
X4433Y-522149D01*
X4120Y-523199D01*
X4042Y-524144D01*
X4198Y-525089D01*
X4433Y-525719D01*
X4903Y-526349D01*
X5452Y-526769D01*
X6000Y-526979D01*
X6548D01*
X7097Y-526769D01*
X7567Y-526454D01*
X7958Y-526034D01*
G01X11360Y-520679D02*
X13240D01*
G01X12300D02*
Y-526979D01*
G01X11360D02*
X13240D01*
G01X18600Y-520679D02*
Y-526979D01*
G01X16798Y-520679D02*
X20402D01*
G01X24900Y-526979D02*
Y-524144D01*
X23333Y-520679D01*
G01X26467D02*
X24900Y-524144D01*
G01X35777Y-525719D02*
X36247Y-526454D01*
X36873Y-526874D01*
X37578Y-526979D01*
X38205Y-526874D01*
X38832Y-526349D01*
X39223Y-525719D01*
X39302Y-525089D01*
X39145Y-524354D01*
X38597Y-523829D01*
X38048Y-523619D01*
X37343D01*
G01X38048D02*
X38518Y-523304D01*
X38910Y-522779D01*
X39067Y-522149D01*
X38910Y-521519D01*
X38518Y-520994D01*
X37813Y-520679D01*
X37108Y-520784D01*
X36403Y-521204D01*
G01X42077Y-525719D02*
X42547Y-526454D01*
X43173Y-526874D01*
X43878Y-526979D01*
X44505Y-526874D01*
X45132Y-526349D01*
X45523Y-525719D01*
X45602Y-525089D01*
X45445Y-524354D01*
X44897Y-523829D01*
X44348Y-523619D01*
X43643D01*
G01X44348D02*
X44818Y-523304D01*
X45210Y-522779D01*
X45367Y-522149D01*
X45210Y-521519D01*
X44818Y-520994D01*
X44113Y-520679D01*
X43408Y-520784D01*
X42703Y-521204D01*
G01X48377Y-525719D02*
X48847Y-526454D01*
X49473Y-526874D01*
X50178Y-526979D01*
X50805Y-526874D01*
X51432Y-526349D01*
X51823Y-525719D01*
X51902Y-525089D01*
X51745Y-524354D01*
X51197Y-523829D01*
X50648Y-523619D01*
X49943D01*
G01X50648D02*
X51118Y-523304D01*
X51510Y-522779D01*
X51667Y-522149D01*
X51510Y-521519D01*
X51118Y-520994D01*
X50413Y-520679D01*
X49708Y-520784D01*
X49003Y-521204D01*
G01X56243Y-526979D02*
X56400Y-525614D01*
X56635Y-524459D01*
X56948Y-523409D01*
X57340Y-522254D01*
X57967Y-520679D01*
X54833D01*
G01X62543Y-526979D02*
X62700Y-525614D01*
X62935Y-524459D01*
X63248Y-523409D01*
X63640Y-522254D01*
X64267Y-520679D01*
X61133D01*
G01X68843Y-528134D02*
X69157Y-526769D01*
G01X75300Y-520679D02*
Y-526979D01*
G01X73498Y-520679D02*
X77102D01*
G01X79642Y-526979D02*
X81600Y-520679D01*
X83558Y-526979D01*
G01X82853Y-524774D02*
X80347D01*
G01X86960Y-520679D02*
X88840D01*
G01X87900D02*
Y-526979D01*
G01X86960D02*
X88840D01*
G01X91850Y-520679D02*
X92947Y-526979D01*
X94200Y-520679D01*
X95453Y-526979D01*
X96550Y-520679D01*
G01X98542Y-526979D02*
X100500Y-520679D01*
X102458Y-526979D01*
G01X101753Y-524774D02*
X99247D01*
G01X104998Y-526979D02*
Y-520679D01*
X108602Y-526979D01*
Y-520679D01*
G01X119008Y-529079D02*
X118225Y-528029D01*
X117833Y-526979D01*
Y-522779D01*
X118225Y-521729D01*
X119008Y-520679D01*
G01X130433Y-526979D02*
Y-520679D01*
X132392D01*
X133018Y-520994D01*
X133410Y-521414D01*
X133567Y-522254D01*
X133410Y-523094D01*
X132940Y-523619D01*
X132392Y-523934D01*
X130433D01*
G01X132392D02*
X133567Y-526979D01*
G01X138300Y-527189D02*
X138143Y-527084D01*
Y-526874D01*
X138300Y-526769D01*
X138457Y-526874D01*
Y-527084D01*
X138300Y-527189D01*
G01X144600Y-526979D02*
X143973Y-526874D01*
X143425Y-526454D01*
X142955Y-525824D01*
X142642Y-525089D01*
X142485Y-524249D01*
Y-523409D01*
X142642Y-522569D01*
X142955Y-521834D01*
X143425Y-521204D01*
X143973Y-520784D01*
X144600Y-520679D01*
X145227Y-520784D01*
X145775Y-521204D01*
X146245Y-521834D01*
X146558Y-522569D01*
X146715Y-523409D01*
Y-524249D01*
X146558Y-525089D01*
X146245Y-525824D01*
X145775Y-526454D01*
X145227Y-526874D01*
X144600Y-526979D01*
G01X150900Y-527189D02*
X150743Y-527084D01*
Y-526874D01*
X150900Y-526769D01*
X151057Y-526874D01*
Y-527084D01*
X150900Y-527189D01*
G01X158923Y-521204D02*
X158453Y-520889D01*
X157905Y-520679D01*
X157278D01*
X156573Y-520994D01*
X156025Y-521519D01*
X155633Y-522149D01*
X155320Y-523199D01*
X155242Y-524144D01*
X155398Y-525089D01*
X155633Y-525719D01*
X156103Y-526349D01*
X156652Y-526769D01*
X157200Y-526979D01*
X157748D01*
X158297Y-526769D01*
X158767Y-526454D01*
X159158Y-526034D01*
G01X163500Y-527189D02*
X163343Y-527084D01*
Y-526874D01*
X163500Y-526769D01*
X163657Y-526874D01*
Y-527084D01*
X163500Y-527189D01*
G01X170192Y-529079D02*
X170975Y-528029D01*
X171367Y-526979D01*
Y-522779D01*
X170975Y-521729D01*
X170192Y-520679D01*
G01X6470Y-513829D02*
X8037D01*
Y-515719D01*
X7567Y-516349D01*
X7018Y-516769D01*
X6235Y-516979D01*
X5452Y-516769D01*
X4903Y-516349D01*
X4433Y-515719D01*
X4120Y-514984D01*
X3963Y-514144D01*
Y-513409D01*
X4120Y-512779D01*
X4433Y-512044D01*
X4903Y-511414D01*
X5373Y-510994D01*
X6000Y-510679D01*
X6548D01*
X7175Y-510889D01*
X7645Y-511309D01*
G01X10577Y-510679D02*
Y-515194D01*
X10890Y-516139D01*
X11517Y-516769D01*
X12300Y-516979D01*
X13083Y-516769D01*
X13710Y-516139D01*
X14023Y-515194D01*
Y-510679D01*
G01X17660D02*
X19540D01*
G01X18600D02*
Y-516979D01*
G01X17660D02*
X19540D01*
G01X23255Y-516139D02*
X23882Y-516664D01*
X24587Y-516979D01*
X25213D01*
X25840Y-516664D01*
X26310Y-516139D01*
X26545Y-515404D01*
X26388Y-514669D01*
X25997Y-514039D01*
X25292Y-513619D01*
X24352Y-513409D01*
X23803Y-512989D01*
X23568Y-512254D01*
X23725Y-511519D01*
X24117Y-510994D01*
X24665Y-510679D01*
X25213D01*
X25762Y-510889D01*
X26232Y-511414D01*
G01X29555Y-516979D02*
Y-510679D01*
G01X32845D02*
Y-516979D01*
G01Y-513829D02*
X29555D01*
G01X35542Y-516979D02*
X37500Y-510679D01*
X39458Y-516979D01*
G01X38753Y-514774D02*
X36247D01*
G01X41998Y-516979D02*
Y-510679D01*
X45602Y-516979D01*
Y-510679D01*
G01X54677Y-516979D02*
Y-510679D01*
X56243D01*
X56870Y-510994D01*
X57340Y-511414D01*
X57732Y-512044D01*
X58045Y-512779D01*
X58123Y-513829D01*
X58045Y-514879D01*
X57732Y-515614D01*
X57340Y-516244D01*
X56870Y-516664D01*
X56243Y-516979D01*
X54677D01*
G01X61760Y-510679D02*
X63640D01*
G01X62700D02*
Y-516979D01*
G01X61760D02*
X63640D01*
G01X67355Y-516139D02*
X67982Y-516664D01*
X68687Y-516979D01*
X69313D01*
X69940Y-516664D01*
X70410Y-516139D01*
X70645Y-515404D01*
X70488Y-514669D01*
X70097Y-514039D01*
X69392Y-513619D01*
X68452Y-513409D01*
X67903Y-512989D01*
X67668Y-512254D01*
X67825Y-511519D01*
X68217Y-510994D01*
X68765Y-510679D01*
X69313D01*
X69862Y-510889D01*
X70332Y-511414D01*
G01X75300Y-510679D02*
Y-516979D01*
G01X73498Y-510679D02*
X77102D01*
G01X81600Y-517189D02*
X81443Y-517084D01*
Y-516874D01*
X81600Y-516769D01*
X81757Y-516874D01*
Y-517084D01*
X81600Y-517189D01*
G01X87743Y-518134D02*
X88057Y-516769D01*
G01X94200Y-510679D02*
Y-516979D01*
G01X92398Y-510679D02*
X96002D01*
G01X98542Y-516979D02*
X100500Y-510679D01*
X102458Y-516979D01*
G01X101753Y-514774D02*
X99247D01*
G01X106800Y-516979D02*
X106173Y-516874D01*
X105625Y-516454D01*
X105155Y-515824D01*
X104842Y-515089D01*
X104685Y-514249D01*
Y-513409D01*
X104842Y-512569D01*
X105155Y-511834D01*
X105625Y-511204D01*
X106173Y-510784D01*
X106800Y-510679D01*
X107427Y-510784D01*
X107975Y-511204D01*
X108445Y-511834D01*
X108758Y-512569D01*
X108915Y-513409D01*
Y-514249D01*
X108758Y-515089D01*
X108445Y-515824D01*
X107975Y-516454D01*
X107427Y-516874D01*
X106800Y-516979D01*
G01X113100D02*
Y-514144D01*
X111533Y-510679D01*
G01X114667D02*
X113100Y-514144D01*
G01X117677Y-510679D02*
Y-515194D01*
X117990Y-516139D01*
X118617Y-516769D01*
X119400Y-516979D01*
X120183Y-516769D01*
X120810Y-516139D01*
X121123Y-515194D01*
Y-510679D01*
G01X123742Y-516979D02*
X125700Y-510679D01*
X127658Y-516979D01*
G01X126953Y-514774D02*
X124447D01*
G01X130198Y-516979D02*
Y-510679D01*
X133802Y-516979D01*
Y-510679D01*
G01X4198Y-506979D02*
Y-500679D01*
X7802Y-506979D01*
Y-500679D01*
G01X12300Y-506979D02*
X11673Y-506874D01*
X11125Y-506454D01*
X10655Y-505824D01*
X10342Y-505089D01*
X10185Y-504249D01*
Y-503409D01*
X10342Y-502569D01*
X10655Y-501834D01*
X11125Y-501204D01*
X11673Y-500784D01*
X12300Y-500679D01*
X12927Y-500784D01*
X13475Y-501204D01*
X13945Y-501834D01*
X14258Y-502569D01*
X14415Y-503409D01*
Y-504249D01*
X14258Y-505089D01*
X13945Y-505824D01*
X13475Y-506454D01*
X12927Y-506874D01*
X12300Y-506979D01*
G01X18600Y-507189D02*
X18443Y-507084D01*
Y-506874D01*
X18600Y-506769D01*
X18757Y-506874D01*
Y-507084D01*
X18600Y-507189D01*
G01X23412Y-501729D02*
X23882Y-501099D01*
X24430Y-500784D01*
X25057Y-500679D01*
X25840Y-500889D01*
X26388Y-501414D01*
X26545Y-502044D01*
X26467Y-502674D01*
X26153Y-503199D01*
X24587Y-504249D01*
X23882Y-504984D01*
X23412Y-506034D01*
X23255Y-506979D01*
X26545D01*
G01X31200D02*
Y-500679D01*
X30260Y-501939D01*
G01Y-506979D02*
X32140D01*
G01X37500D02*
Y-500679D01*
X36560Y-501939D01*
G01Y-506979D02*
X38440D01*
G01X43643Y-508134D02*
X43957Y-506769D01*
G01X47750Y-500679D02*
X48847Y-506979D01*
X50100Y-500679D01*
X51353Y-506979D01*
X52450Y-500679D01*
G01X57967Y-506979D02*
X54833D01*
Y-500679D01*
X57967D01*
G01X56713Y-503724D02*
X54833D01*
G01X60898Y-506979D02*
Y-500679D01*
X64502Y-506979D01*
Y-500679D01*
G01X67355Y-506979D02*
Y-500679D01*
G01X70645D02*
Y-506979D01*
G01Y-503829D02*
X67355D01*
G01X73577Y-500679D02*
Y-505194D01*
X73890Y-506139D01*
X74517Y-506769D01*
X75300Y-506979D01*
X76083Y-506769D01*
X76710Y-506139D01*
X77023Y-505194D01*
Y-500679D01*
G01X79642Y-506979D02*
X81600Y-500679D01*
X83558Y-506979D01*
G01X82853Y-504774D02*
X80347D01*
G01X92712Y-501729D02*
X93182Y-501099D01*
X93730Y-500784D01*
X94357Y-500679D01*
X95140Y-500889D01*
X95688Y-501414D01*
X95845Y-502044D01*
X95767Y-502674D01*
X95453Y-503199D01*
X93887Y-504249D01*
X93182Y-504984D01*
X92712Y-506034D01*
X92555Y-506979D01*
X95845D01*
G01X98698D02*
Y-500679D01*
X102302Y-506979D01*
Y-500679D01*
G01X105077Y-506979D02*
Y-500679D01*
X106643D01*
X107270Y-500994D01*
X107740Y-501414D01*
X108132Y-502044D01*
X108445Y-502779D01*
X108523Y-503829D01*
X108445Y-504879D01*
X108132Y-505614D01*
X107740Y-506244D01*
X107270Y-506664D01*
X106643Y-506979D01*
X105077D01*
G01X117833D02*
Y-500679D01*
X119792D01*
X120418Y-500994D01*
X120810Y-501414D01*
X120967Y-502254D01*
X120810Y-503094D01*
X120340Y-503619D01*
X119792Y-503934D01*
X117833D01*
G01X119792D02*
X120967Y-506979D01*
G01X123977D02*
Y-500679D01*
X125543D01*
X126170Y-500994D01*
X126640Y-501414D01*
X127032Y-502044D01*
X127345Y-502779D01*
X127423Y-503829D01*
X127345Y-504879D01*
X127032Y-505614D01*
X126640Y-506244D01*
X126170Y-506664D01*
X125543Y-506979D01*
X123977D01*
G01X132000Y-507189D02*
X131843Y-507084D01*
Y-506874D01*
X132000Y-506769D01*
X132157Y-506874D01*
Y-507084D01*
X132000Y-507189D01*
G01X28300Y-494279D02*
X25780Y-493862D01*
X23575Y-492196D01*
X21685Y-489696D01*
X20425Y-486779D01*
X19795Y-483446D01*
Y-480112D01*
X20425Y-476779D01*
X21685Y-473862D01*
X23575Y-471363D01*
X25780Y-469696D01*
X28300Y-469279D01*
X30820Y-469696D01*
X33025Y-471363D01*
X34915Y-473862D01*
X36175Y-476779D01*
X36805Y-480112D01*
Y-483446D01*
X36175Y-486779D01*
X34915Y-489696D01*
X33025Y-492196D01*
X30820Y-493862D01*
X28300Y-494279D01*
G01X30820Y-487612D02*
X34600Y-494279D01*
G01X48145Y-477613D02*
Y-489279D01*
X49405Y-492196D01*
X51295Y-493862D01*
X53500Y-494279D01*
X55705Y-493862D01*
X57595Y-492196D01*
X58855Y-489279D01*
G01Y-494279D02*
Y-477613D01*
G01X84370Y-494279D02*
Y-477613D01*
G01Y-480529D02*
X83110Y-478863D01*
X81220Y-478029D01*
X79015Y-477613D01*
X76810Y-478446D01*
X74920Y-480112D01*
X73660Y-482613D01*
X73030Y-485946D01*
X73660Y-489279D01*
X74920Y-491780D01*
X76810Y-493446D01*
X79015Y-494279D01*
X81220Y-493862D01*
X83110Y-492613D01*
X84370Y-490946D01*
G01X98545Y-494279D02*
Y-477613D01*
G01Y-481779D02*
X99805Y-479696D01*
X101695Y-478029D01*
X104215Y-477613D01*
X106420Y-478029D01*
X108310Y-479696D01*
X109255Y-482613D01*
Y-494279D01*
G01X129100Y-469279D02*
Y-494279D01*
G01X124690Y-477613D02*
X133510D01*
G01X159970Y-494279D02*
Y-477613D01*
G01Y-480529D02*
X158710Y-478863D01*
X156820Y-478029D01*
X154615Y-477613D01*
X152410Y-478446D01*
X150520Y-480112D01*
X149260Y-482613D01*
X148630Y-485946D01*
X149260Y-489279D01*
X150520Y-491780D01*
X152410Y-493446D01*
X154615Y-494279D01*
X156820Y-493862D01*
X158710Y-492613D01*
X159970Y-490946D01*
G01X199650Y-473979D02*
Y-481979D01*
X203650D01*
G01X211450D02*
Y-476646D01*
G01Y-477579D02*
X211050Y-477046D01*
X210450Y-476779D01*
X209750Y-476646D01*
X209050Y-476912D01*
X208450Y-477446D01*
X208050Y-478246D01*
X207850Y-479312D01*
X208050Y-480379D01*
X208450Y-481179D01*
X209050Y-481712D01*
X209750Y-481979D01*
X210450Y-481846D01*
X211050Y-481446D01*
X211450Y-480913D01*
G01X215550Y-484379D02*
X216150Y-484646D01*
X216950Y-484379D01*
X217450Y-483846D01*
X217850Y-483179D01*
X218450Y-481046D01*
X219750Y-476646D01*
G01X216550D02*
X218450Y-481046D01*
G01X224150Y-478379D02*
X227350D01*
X227050Y-477446D01*
X226550Y-476912D01*
X225850Y-476646D01*
X225150Y-476779D01*
X224550Y-477179D01*
X224150Y-478112D01*
X223950Y-478913D01*
Y-479712D01*
X224150Y-480512D01*
X224650Y-481312D01*
X225250Y-481846D01*
X225950Y-481979D01*
X226650Y-481712D01*
X227350Y-480913D01*
G01X232250Y-481979D02*
Y-476646D01*
G01Y-477712D02*
X232750Y-477179D01*
X233250Y-476779D01*
X233950Y-476646D01*
X234450Y-476779D01*
X235050Y-477179D01*
G01X223350Y-531979D02*
Y-523979D01*
X227950Y-531979D01*
Y-523979D01*
G01X233650Y-526646D02*
Y-531979D01*
G01Y-524512D02*
X233450Y-524379D01*
Y-524112D01*
X233650Y-523979D01*
X233850Y-524112D01*
Y-524379D01*
X233650Y-524512D01*
G01X239950Y-531979D02*
Y-526646D01*
G01Y-527979D02*
X240350Y-527312D01*
X240950Y-526779D01*
X241750Y-526646D01*
X242450Y-526779D01*
X243050Y-527312D01*
X243350Y-528246D01*
Y-531979D01*
G01X251450D02*
Y-526646D01*
G01Y-527579D02*
X251050Y-527046D01*
X250450Y-526779D01*
X249750Y-526646D01*
X249050Y-526912D01*
X248450Y-527446D01*
X248050Y-528246D01*
X247850Y-529312D01*
X248050Y-530379D01*
X248450Y-531179D01*
X249050Y-531712D01*
X249750Y-531979D01*
X250450Y-531846D01*
X251050Y-531446D01*
X251450Y-530913D01*
G01X227279Y-504436D02*
X229279D01*
Y-506836D01*
X228679Y-507636D01*
X227979Y-508169D01*
X226979Y-508436D01*
X225979Y-508169D01*
X225279Y-507636D01*
X224679Y-506836D01*
X224279Y-505903D01*
X224079Y-504836D01*
Y-503903D01*
X224279Y-503103D01*
X224679Y-502169D01*
X225279Y-501369D01*
X225879Y-500836D01*
X226679Y-500436D01*
X227379D01*
X228179Y-500703D01*
X228779Y-501236D01*
G01X232379Y-508436D02*
Y-500436D01*
X236979Y-508436D01*
Y-500436D01*
G01X240479Y-508436D02*
Y-500436D01*
X242479D01*
X243279Y-500836D01*
X243879Y-501369D01*
X244379Y-502169D01*
X244779Y-503103D01*
X244879Y-504436D01*
X244779Y-505769D01*
X244379Y-506703D01*
X243879Y-507503D01*
X243279Y-508036D01*
X242479Y-508436D01*
X240479D01*
G01X248779Y-501769D02*
X249379Y-500969D01*
X250079Y-500569D01*
X250879Y-500436D01*
X251879Y-500703D01*
X252579Y-501369D01*
X252779Y-502169D01*
X252679Y-502970D01*
X252279Y-503636D01*
X250279Y-504969D01*
X249379Y-505903D01*
X248779Y-507236D01*
X248579Y-508436D01*
X252779D01*
G01X252279Y-480103D02*
X252979Y-479169D01*
X253579Y-478636D01*
X254379Y-478369D01*
X255079Y-478636D01*
X255579Y-479169D01*
X255979Y-479969D01*
X256079Y-480903D01*
X255979Y-481703D01*
X255579Y-482503D01*
X254979Y-483169D01*
X254279Y-483436D01*
X253479Y-483169D01*
X252779Y-482370D01*
X252379Y-481169D01*
X252279Y-479836D01*
X252479Y-478103D01*
X252779Y-477169D01*
X253279Y-476236D01*
X253979Y-475569D01*
X254679Y-475436D01*
X255379Y-475703D01*
X255879Y-476369D01*
G01X326250Y-525312D02*
X326850Y-524512D01*
X327550Y-524112D01*
X328350Y-523979D01*
X329350Y-524246D01*
X330050Y-524912D01*
X330250Y-525712D01*
X330150Y-526513D01*
X329750Y-527179D01*
X327750Y-528512D01*
X326850Y-529446D01*
X326250Y-530779D01*
X326050Y-531979D01*
X330250D01*
G01X336150Y-523979D02*
X335350Y-524246D01*
X334750Y-524912D01*
X334350Y-525712D01*
X334050Y-526779D01*
X333950Y-527979D01*
X334050Y-529179D01*
X334350Y-530246D01*
X334750Y-531046D01*
X335350Y-531712D01*
X336150Y-531979D01*
X336950Y-531712D01*
X337550Y-531046D01*
X337950Y-530246D01*
X338250Y-529179D01*
X338350Y-527979D01*
X338250Y-526779D01*
X337950Y-525712D01*
X337550Y-524912D01*
X336950Y-524246D01*
X336150Y-523979D01*
G01X342250Y-525312D02*
X342850Y-524512D01*
X343550Y-524112D01*
X344350Y-523979D01*
X345350Y-524246D01*
X346050Y-524912D01*
X346250Y-525712D01*
X346150Y-526513D01*
X345750Y-527179D01*
X343750Y-528512D01*
X342850Y-529446D01*
X342250Y-530779D01*
X342050Y-531979D01*
X346250D01*
G01X349950Y-530379D02*
X350550Y-531312D01*
X351350Y-531846D01*
X352250Y-531979D01*
X353050Y-531846D01*
X353850Y-531179D01*
X354350Y-530379D01*
X354450Y-529579D01*
X354250Y-528646D01*
X353550Y-527979D01*
X352850Y-527712D01*
X351950D01*
G01X352850D02*
X353450Y-527312D01*
X353950Y-526646D01*
X354150Y-525846D01*
X353950Y-525046D01*
X353450Y-524379D01*
X352550Y-523979D01*
X351650Y-524112D01*
X350750Y-524646D01*
G01X358350Y-532246D02*
X361950Y-523979D01*
G01X368150D02*
X367350Y-524246D01*
X366750Y-524912D01*
X366350Y-525712D01*
X366050Y-526779D01*
X365950Y-527979D01*
X366050Y-529179D01*
X366350Y-530246D01*
X366750Y-531046D01*
X367350Y-531712D01*
X368150Y-531979D01*
X368950Y-531712D01*
X369550Y-531046D01*
X369950Y-530246D01*
X370250Y-529179D01*
X370350Y-527979D01*
X370250Y-526779D01*
X369950Y-525712D01*
X369550Y-524912D01*
X368950Y-524246D01*
X368150Y-523979D01*
G01X373950Y-530379D02*
X374550Y-531312D01*
X375350Y-531846D01*
X376250Y-531979D01*
X377050Y-531846D01*
X377850Y-531179D01*
X378350Y-530379D01*
X378450Y-529579D01*
X378250Y-528646D01*
X377550Y-527979D01*
X376850Y-527712D01*
X375950D01*
G01X376850D02*
X377450Y-527312D01*
X377950Y-526646D01*
X378150Y-525846D01*
X377950Y-525046D01*
X377450Y-524379D01*
X376550Y-523979D01*
X375650Y-524112D01*
X374750Y-524646D01*
G01X382350Y-532246D02*
X385950Y-523979D01*
G01X390250Y-525312D02*
X390850Y-524512D01*
X391550Y-524112D01*
X392350Y-523979D01*
X393350Y-524246D01*
X394050Y-524912D01*
X394250Y-525712D01*
X394150Y-526513D01*
X393750Y-527179D01*
X391750Y-528512D01*
X390850Y-529446D01*
X390250Y-530779D01*
X390050Y-531979D01*
X394250D01*
G01X401350D02*
Y-523979D01*
X397650Y-529712D01*
X402650D01*
G01X325950Y-506979D02*
Y-498979D01*
X327950D01*
X328750Y-499379D01*
X329350Y-499912D01*
X329850Y-500712D01*
X330250Y-501646D01*
X330350Y-502979D01*
X330250Y-504312D01*
X329850Y-505246D01*
X329350Y-506046D01*
X328750Y-506579D01*
X327950Y-506979D01*
X325950D01*
G01X333650D02*
X336150Y-498979D01*
X338650Y-506979D01*
G01X337750Y-504179D02*
X334550D01*
G01X344150Y-498979D02*
X343350Y-499246D01*
X342750Y-499912D01*
X342350Y-500712D01*
X342050Y-501779D01*
X341950Y-502979D01*
X342050Y-504179D01*
X342350Y-505246D01*
X342750Y-506046D01*
X343350Y-506712D01*
X344150Y-506979D01*
X344950Y-506712D01*
X345550Y-506046D01*
X345950Y-505246D01*
X346250Y-504179D01*
X346350Y-502979D01*
X346250Y-501779D01*
X345950Y-500712D01*
X345550Y-499912D01*
X344950Y-499246D01*
X344150Y-498979D01*
G01X350250Y-506979D02*
Y-498979D01*
X354050D01*
G01X352650Y-502846D02*
X350250D01*
G01X360150Y-498979D02*
X359350Y-499246D01*
X358750Y-499912D01*
X358350Y-500712D01*
X358050Y-501779D01*
X357950Y-502979D01*
X358050Y-504179D01*
X358350Y-505246D01*
X358750Y-506046D01*
X359350Y-506712D01*
X360150Y-506979D01*
X360950Y-506712D01*
X361550Y-506046D01*
X361950Y-505246D01*
X362250Y-504179D01*
X362350Y-502979D01*
X362250Y-501779D01*
X361950Y-500712D01*
X361550Y-499912D01*
X360950Y-499246D01*
X360150Y-498979D01*
G01X368150D02*
Y-506979D01*
G01X365850Y-498979D02*
X370450D01*
G01X373550Y-506979D02*
Y-498979D01*
X376150Y-505646D01*
X378750Y-498979D01*
Y-506979D01*
G01X384950Y-502712D02*
X385350Y-502312D01*
X385650Y-501646D01*
X385850Y-500712D01*
X385650Y-499912D01*
X385250Y-499379D01*
X384550Y-498979D01*
X381850D01*
Y-506979D01*
X385150D01*
X385850Y-506446D01*
X386250Y-505646D01*
X386450Y-504712D01*
X386250Y-503779D01*
X385650Y-502979D01*
X384950Y-502712D01*
X381850D01*
G01X390950Y-498979D02*
X393350D01*
G01X392150D02*
Y-506979D01*
G01X390950D02*
X393350D01*
G01X398150Y-505379D02*
X398650Y-506179D01*
X399250Y-506712D01*
X399950Y-506979D01*
X400750Y-506712D01*
X401350Y-506179D01*
X401950Y-505379D01*
X402150Y-504312D01*
Y-498979D01*
G01X408150D02*
X407350Y-499246D01*
X406750Y-499912D01*
X406350Y-500712D01*
X406050Y-501779D01*
X405950Y-502979D01*
X406050Y-504179D01*
X406350Y-505246D01*
X406750Y-506046D01*
X407350Y-506712D01*
X408150Y-506979D01*
X408950Y-506712D01*
X409550Y-506046D01*
X409950Y-505246D01*
X410250Y-504179D01*
X410350Y-502979D01*
X410250Y-501779D01*
X409950Y-500712D01*
X409550Y-499912D01*
X408950Y-499246D01*
X408150Y-498979D01*
G01X343750Y-481979D02*
Y-473979D01*
X347550D01*
G01X346150Y-477846D02*
X343750D01*
G01X353650Y-473979D02*
X352850Y-474246D01*
X352250Y-474912D01*
X351850Y-475712D01*
X351550Y-476779D01*
X351450Y-477979D01*
X351550Y-479179D01*
X351850Y-480246D01*
X352250Y-481046D01*
X352850Y-481712D01*
X353650Y-481979D01*
X354450Y-481712D01*
X355050Y-481046D01*
X355450Y-480246D01*
X355750Y-479179D01*
X355850Y-477979D01*
X355750Y-476779D01*
X355450Y-475712D01*
X355050Y-474912D01*
X354450Y-474246D01*
X353650Y-473979D01*
G01X361650D02*
Y-481979D01*
G01X359350Y-473979D02*
X363950D01*
G01X366650Y-484646D02*
X372650D01*
G01X375050Y-481979D02*
Y-473979D01*
X377650Y-480646D01*
X380250Y-473979D01*
Y-481979D01*
G01X386450Y-477712D02*
X386850Y-477312D01*
X387150Y-476646D01*
X387350Y-475712D01*
X387150Y-474912D01*
X386750Y-474379D01*
X386050Y-473979D01*
X383350D01*
Y-481979D01*
X386650D01*
X387350Y-481446D01*
X387750Y-480646D01*
X387950Y-479712D01*
X387750Y-478779D01*
X387150Y-477979D01*
X386450Y-477712D01*
X383350D01*
G01X390650Y-484646D02*
X396650D01*
G01X403650Y-481979D02*
X399650D01*
Y-473979D01*
X403650D01*
G01X402050Y-477846D02*
X399650D01*
G01X407050Y-481979D02*
Y-473979D01*
X409650Y-480646D01*
X412250Y-473979D01*
Y-481979D01*
G01X417650D02*
X418350Y-481846D01*
X419150Y-481446D01*
X419650Y-480779D01*
X419850Y-479846D01*
X419650Y-478913D01*
X419050Y-478112D01*
X418150Y-477712D01*
X417150D01*
X416550Y-477446D01*
X416050Y-476779D01*
X415850Y-475846D01*
X416150Y-474912D01*
X416850Y-474246D01*
X417650Y-473979D01*
X418450Y-474246D01*
X419150Y-474912D01*
X419450Y-475846D01*
X419250Y-476779D01*
X418750Y-477446D01*
X418150Y-477712D01*
X417150D01*
X416250Y-478112D01*
X415650Y-478913D01*
X415450Y-479846D01*
X415650Y-480779D01*
X416150Y-481446D01*
X416950Y-481846D01*
X417650Y-481979D01*
G01X423950Y-481046D02*
X424650Y-481712D01*
X425450Y-481979D01*
X426250Y-481712D01*
X426950Y-480913D01*
X427450Y-479712D01*
X427650Y-478512D01*
Y-477046D01*
X427450Y-475846D01*
X426950Y-474779D01*
X426350Y-474246D01*
X425650Y-473979D01*
X424850Y-474246D01*
X424250Y-474779D01*
X423850Y-475579D01*
X423650Y-476646D01*
X423850Y-477579D01*
X424350Y-478512D01*
X424950Y-479046D01*
X425650Y-479179D01*
X426450Y-478913D01*
X427050Y-478246D01*
X427650Y-477046D01*
G01X433650Y-473979D02*
X432850Y-474246D01*
X432250Y-474912D01*
X431850Y-475712D01*
X431550Y-476779D01*
X431450Y-477979D01*
X431550Y-479179D01*
X431850Y-480246D01*
X432250Y-481046D01*
X432850Y-481712D01*
X433650Y-481979D01*
X434450Y-481712D01*
X435050Y-481046D01*
X435450Y-480246D01*
X435750Y-479179D01*
X435850Y-477979D01*
X435750Y-476779D01*
X435450Y-475712D01*
X435050Y-474912D01*
X434450Y-474246D01*
X433650Y-473979D01*
G01X439450Y-481979D02*
Y-473979D01*
G01X443250D02*
X439450Y-478913D01*
G01X443850Y-481979D02*
X441150Y-476646D01*
G01X414650Y-534979D02*
Y-526979D01*
X413450Y-528579D01*
G01Y-534979D02*
X415850D01*
G01X420750Y-531646D02*
X421450Y-530712D01*
X422050Y-530179D01*
X422850Y-529912D01*
X423550Y-530179D01*
X424050Y-530712D01*
X424450Y-531512D01*
X424550Y-532446D01*
X424450Y-533246D01*
X424050Y-534046D01*
X423450Y-534712D01*
X422750Y-534979D01*
X421950Y-534712D01*
X421250Y-533913D01*
X420850Y-532712D01*
X420750Y-531379D01*
X420950Y-529646D01*
X421250Y-528712D01*
X421750Y-527779D01*
X422450Y-527112D01*
X423150Y-526979D01*
X423850Y-527246D01*
X424350Y-527912D01*
G01X430650Y-535246D02*
X430450Y-535112D01*
Y-534846D01*
X430650Y-534712D01*
X430850Y-534846D01*
Y-535112D01*
X430650Y-535246D01*
G01X436750Y-531646D02*
X437450Y-530712D01*
X438050Y-530179D01*
X438850Y-529912D01*
X439550Y-530179D01*
X440050Y-530712D01*
X440450Y-531512D01*
X440550Y-532446D01*
X440450Y-533246D01*
X440050Y-534046D01*
X439450Y-534712D01*
X438750Y-534979D01*
X437950Y-534712D01*
X437250Y-533913D01*
X436850Y-532712D01*
X436750Y-531379D01*
X436950Y-529646D01*
X437250Y-528712D01*
X437750Y-527779D01*
X438450Y-527112D01*
X439150Y-526979D01*
X439850Y-527246D01*
X440350Y-527912D01*
G01X459650Y-534979D02*
Y-526979D01*
X458450Y-528579D01*
G01Y-534979D02*
X460850D01*
G01X467450D02*
X467650Y-533246D01*
X467950Y-531779D01*
X468350Y-530446D01*
X468850Y-528979D01*
X469650Y-526979D01*
X465650D01*
G01X475650Y-535246D02*
X475450Y-535112D01*
Y-534846D01*
X475650Y-534712D01*
X475850Y-534846D01*
Y-535112D01*
X475650Y-535246D01*
G01X481750Y-528312D02*
X482350Y-527512D01*
X483050Y-527112D01*
X483850Y-526979D01*
X484850Y-527246D01*
X485550Y-527912D01*
X485750Y-528712D01*
X485650Y-529513D01*
X485250Y-530179D01*
X483250Y-531512D01*
X482350Y-532446D01*
X481750Y-533779D01*
X481550Y-534979D01*
X485750D01*
G01X479650Y-508379D02*
X480150Y-509179D01*
X480750Y-509712D01*
X481450Y-509979D01*
X482250Y-509712D01*
X482850Y-509179D01*
X483450Y-508379D01*
X483650Y-507312D01*
Y-501979D01*
M02*
